(kicad_pcb
	(version 20260206)
	(generator "pcbnew")
	(generator_version "10.0")
	(general
		(thickness 1.6)
		(legacy_teardrops no)
	)
	(paper "A4")
	(layers
		(0 "F.Cu" signal "TOP")
		(4 "In1.Cu" signal "02_GND")
		(6 "In2.Cu" signal "03_SIG")
		(8 "In3.Cu" signal "04_SIG")
		(10 "In4.Cu" signal "05_GND")
		(12 "In5.Cu" signal "06_PWR1")
		(14 "In6.Cu" signal "07_SIG")
		(16 "In7.Cu" signal "08_SIG")
		(18 "In8.Cu" signal "09_GND")
		(2 "B.Cu" signal "BOTTOM")
		(9 "F.Adhes" user "F.Adhesive")
		(11 "B.Adhes" user "B.Adhesive")
		(13 "F.Paste" user "Package Geometry/Pastemask Top")
		(15 "B.Paste" user "Package Geometry/Pastemask Bottom")
		(5 "F.SilkS" user "Ref Des/Silkscreen Top")
		(7 "B.SilkS" user "Ref Des/Silkscreen Bottom")
		(1 "F.Mask" user "Board Geometry/Soldermask Top")
		(3 "B.Mask" user "Board Geometry/Soldermask Bottom")
		(17 "Dwgs.User" user "User.Drawings")
		(19 "Cmts.User" user "User.Comments")
		(21 "Eco1.User" user "User.Eco1")
		(23 "Eco2.User" user "User.Eco2")
		(25 "Edge.Cuts" user "Board Geometry/Outline")
		(27 "Margin" user)
		(31 "F.CrtYd" user "Package Geometry/Place Bound Top")
		(29 "B.CrtYd" user "Package Geometry/Place Bound Bottom")
		(35 "F.Fab" user "Ref Des/Assembly Top")
		(33 "B.Fab" user "Ref Des/Assembly Bottom")
		(45 "User.4" user "COMPVAL_TYPE_BOTTOM")
	)
	(setup
		(pad_to_mask_clearance 0)
		(allow_soldermask_bridges_in_footprints no)
		(tenting
			(front yes)
			(back yes)
		)
		(covering
			(front no)
			(back no)
		)
		(plugging
			(front no)
			(back no)
		)
		(capping no)
		(filling no)
		(pcbplotparams
			(layerselection 0x00000000_00000000_55555555_5755f5ff)
			(plot_on_all_layers_selection 0x00000000_00000000_00000000_00000000)
			(disableapertmacros no)
			(usegerberextensions no)
			(usegerberattributes yes)
			(usegerberadvancedattributes yes)
			(creategerberjobfile yes)
			(dashed_line_dash_ratio 12)
			(dashed_line_gap_ratio 3)
			(svgprecision 4)
			(plotframeref no)
			(mode 1)
			(useauxorigin no)
			(pdf_front_fp_property_popups yes)
			(pdf_back_fp_property_popups yes)
			(pdf_metadata yes)
			(pdf_single_document no)
			(dxfpolygonmode yes)
			(dxfimperialunits yes)
			(dxfusepcbnewfont yes)
			(psnegative no)
			(psa4output no)
			(plot_black_and_white yes)
			(sketchpadsonfab no)
			(plotpadnumbers no)
			(hidednponfab no)
			(sketchdnponfab yes)
			(crossoutdnponfab yes)
			(subtractmaskfromsilk no)
			(outputformat 1)
			(mirror no)
			(drillshape 1)
			(scaleselection 1)
			(outputdirectory "")
		)
	)
	(footprint ""
		(layer "F.Cu")
		(at 22.1488 22.479 90)
		(property "Reference" "U15"
			(at 3.65633 -5.0038 0)
			(unlocked yes)
			(layer "F.SilkS")
			(effects
				(font
					(size 0.7874 0.5842)
					(thickness 0.127)
				)
				(justify left)
			)
		)
		(property "Value" "*"
			(at -0.4826 1.375842 90)
			(unlocked yes)
			(layer "F.Fab")
			(hide yes)
			(effects
				(font
					(size 1.27 0.9652)
					(thickness 0.000001)
				)
				(justify left)
			)
		)
		(property "Device Type" "PROG0055"
			(at -0.4826 1.375842 90)
			(unlocked yes)
			(layer "F.Fab")
			(hide yes)
			(effects
				(font
					(size 1.27 0.9652)
					(thickness 0.000001)
				)
				(justify left)
			)
		)
		(duplicate_pad_numbers_are_jumpers no)
		(fp_line
			(start 3.048 -3.048)
			(end 3.048 -2.54)
			(stroke
				(width 0.2032)
				(type default)
			)
			(layer "F.SilkS")
		)
		(fp_line
			(start -0.587858 -3.048)
			(end 3.048 -3.048)
			(stroke
				(width 0.2032)
				(type default)
			)
			(layer "F.SilkS")
		)
		(fp_line
			(start -0.762 -3.048)
			(end -0.762 -2.286)
			(stroke
				(width 0.2032)
				(type default)
			)
			(layer "F.SilkS")
		)
		(fp_line
			(start -1.755775 -3.048)
			(end -0.936142 -3.048)
			(stroke
				(width 0.2032)
				(type default)
			)
			(layer "F.SilkS")
		)
		(fp_line
			(start -3.048 -3.048)
			(end 3.048 -3.048)
			(stroke
				(width 0.2032)
				(type default)
			)
			(layer "F.SilkS")
		)
		(fp_line
			(start -3.048 -2.54)
			(end -3.048 -3.048)
			(stroke
				(width 0.2032)
				(type default)
			)
			(layer "F.SilkS")
		)
		(fp_line
			(start 0.762 -2.286)
			(end 0.762 -3.048)
			(stroke
				(width 0.2032)
				(type default)
			)
			(layer "F.SilkS")
		)
		(fp_line
			(start 0.762 -2.286)
			(end 0.762 -3.048)
			(stroke
				(width 0.2032)
				(type default)
			)
			(layer "F.SilkS")
		)
		(fp_line
			(start -0.178918 -2.286)
			(end 0.762 -2.286)
			(stroke
				(width 0.2032)
				(type default)
			)
			(layer "F.SilkS")
		)
		(fp_line
			(start -0.762 -2.286)
			(end 0.762 -2.286)
			(stroke
				(width 0.2032)
				(type default)
			)
			(layer "F.SilkS")
		)
		(fp_line
			(start 3.048 2.54)
			(end 3.048 3.048)
			(stroke
				(width 0.2032)
				(type default)
			)
			(layer "F.SilkS")
		)
		(fp_line
			(start 3.048 3.048)
			(end -3.048 3.048)
			(stroke
				(width 0.2032)
				(type default)
			)
			(layer "F.SilkS")
		)
		(fp_line
			(start 3.048 3.048)
			(end -3.048 3.048)
			(stroke
				(width 0.2032)
				(type default)
			)
			(layer "F.SilkS")
		)
		(fp_line
			(start -3.048 3.048)
			(end -3.048 2.54)
			(stroke
				(width 0.2032)
				(type default)
			)
			(layer "F.SilkS")
		)
		(fp_circle
			(center -4.064 -2.667)
			(end -4.064 -2.413)
			(stroke
				(width 0.2032)
				(type default)
			)
			(fill no)
			(layer "F.SilkS")
		)
		(fp_poly
			(pts
				(xy -3.302 3.302) (xy 3.302 3.302) (xy 3.302 2.794) (xy 5.08 2.794) (xy 5.08 -2.794) (xy 3.302 -2.794)
				(xy 3.302 -3.302) (xy -3.302 -3.302) (xy -3.302 -2.794) (xy -5.08 -2.794) (xy -5.08 2.794) (xy -3.302 2.794)
			)
			(stroke
				(width 0)
				(type default)
			)
			(fill no)
			(layer "F.CrtYd")
		)
		(fp_line
			(start 2.7432 -2.7432)
			(end -2.7432 -2.7432)
			(stroke
				(width 0.2032)
				(type default)
			)
			(layer "F.Fab")
		)
		(fp_line
			(start -2.7432 -2.7432)
			(end -2.7432 2.7432)
			(stroke
				(width 0.2032)
				(type default)
			)
			(layer "F.Fab")
		)
		(fp_line
			(start -0.762 -2.667)
			(end -0.762 -1.905)
			(stroke
				(width 0.2032)
				(type default)
			)
			(layer "F.Fab")
		)
		(fp_line
			(start 0.762 -1.905)
			(end 0.762 -2.667)
			(stroke
				(width 0.2032)
				(type default)
			)
			(layer "F.Fab")
		)
		(fp_line
			(start -0.762 -1.905)
			(end 0.762 -1.905)
			(stroke
				(width 0.2032)
				(type default)
			)
			(layer "F.Fab")
		)
		(fp_line
			(start 2.7432 2.7432)
			(end 2.7432 -2.7432)
			(stroke
				(width 0.2032)
				(type default)
			)
			(layer "F.Fab")
		)
		(fp_line
			(start -2.7432 2.7432)
			(end 2.7432 2.7432)
			(stroke
				(width 0.2032)
				(type default)
			)
			(layer "F.Fab")
		)
		(fp_circle
			(center -1.905 -1.905)
			(end -1.905 -1.524)
			(stroke
				(width 0.2032)
				(type default)
			)
			(fill no)
			(layer "F.Fab")
		)
		(pad "1" smd rect
			(at -3.6449 -1.905 90)
			(size 1.8288 0.635)
			(layers "F.Cu" "F.Mask" "F.Paste")
			(net "NFP_ARM_SPI_FLASH_SEL")
		)
		(pad "2" smd rect
			(at -3.6449 -0.635 90)
			(size 1.8288 0.635)
			(layers "F.Cu" "F.Mask" "F.Paste")
			(net "NFP_ARM_SPI_FLASH_MISO")
		)
		(pad "3" smd rect
			(at -3.6449 0.635 90)
			(size 1.8288 0.635)
			(layers "F.Cu" "F.Mask" "F.Paste")
			(net "NFP_ARM_SPI_FLASH_WP_L")
		)
		(pad "4" smd rect
			(at -3.6449 1.905 90)
			(size 1.8288 0.635)
			(layers "F.Cu" "F.Mask" "F.Paste")
			(net "GND")
		)
		(pad "5" smd rect
			(at 3.6449 1.905 90)
			(size 1.8288 0.635)
			(layers "F.Cu" "F.Mask" "F.Paste")
			(net "NFP_ARM_SPI_FLASH_MOSI")
		)
		(pad "6" smd rect
			(at 3.6449 0.635 90)
			(size 1.8288 0.635)
			(layers "F.Cu" "F.Mask" "F.Paste")
			(net "NFP_ARM_SPI_FLASH_SCK")
		)
		(pad "7" smd rect
			(at 3.6449 -0.635 90)
			(size 1.8288 0.635)
			(layers "F.Cu" "F.Mask" "F.Paste")
			(net "3N2521")
		)
		(pad "8" smd rect
			(at 3.6449 -1.905 90)
			(size 1.8288 0.635)
			(layers "F.Cu" "F.Mask" "F.Paste")
			(net "VDD_3.3V")
		)
	)
	(footprint ""
		(layer "F.Cu")
		(at 78.3082 49.53 90)
		(property "Reference" "C66"
			(at -1.67767 -0.3302 0)
			(unlocked yes)
			(layer "F.SilkS")
			(effects
				(font
					(size 0.7874 0.5842)
					(thickness 0.127)
				)
				(justify left)
			)
		)
		(property "Value" "100UF"
			(at -0.78232 0.4826 180)
			(unlocked yes)
			(layer "F.Fab")
			(hide yes)
			(effects
				(font
					(size 1.27 0.9652)
					(thickness 0.000001)
				)
				(justify left)
			)
		)
		(property "Device Type" "CAPC0087"
			(at -0.78232 0.4826 180)
			(unlocked yes)
			(layer "F.Fab")
			(hide yes)
			(effects
				(font
					(size 1.27 0.9652)
					(thickness 0.000001)
				)
				(justify left)
			)
		)
		(duplicate_pad_numbers_are_jumpers no)
		(fp_circle
			(center 0 0)
			(end 0 0.508)
			(stroke
				(width 0.2032)
				(type default)
			)
			(fill no)
			(layer "F.SilkS")
		)
		(fp_circle
			(center 0 0)
			(end 0 0.508)
			(stroke
				(width 0.2032)
				(type default)
			)
			(fill no)
			(layer "F.SilkS")
		)
		(fp_poly
			(pts
				(xy -1.27 2.9464) (xy 1.27 2.9464) (xy 1.27 -2.795295) (xy -1.27 -2.795295)
			)
			(stroke
				(width 0)
				(type default)
			)
			(fill no)
			(layer "F.CrtYd")
		)
		(fp_line
			(start 1.016 -2.794)
			(end 1.016 2.794)
			(stroke
				(width 0.0254)
				(type default)
			)
			(layer "F.Fab")
		)
		(fp_line
			(start -1.016 -2.794)
			(end 1.016 -2.794)
			(stroke
				(width 0.0254)
				(type default)
			)
			(layer "F.Fab")
		)
		(fp_line
			(start 1.016 2.794)
			(end -1.016 2.794)
			(stroke
				(width 0.0254)
				(type default)
			)
			(layer "F.Fab")
		)
		(fp_line
			(start -1.016 2.794)
			(end -1.016 -2.794)
			(stroke
				(width 0.0254)
				(type default)
			)
			(layer "F.Fab")
		)
		(pad "1" smd rect
			(at 0 -1.6764 90)
			(size 1.524 1.524)
			(layers "F.Cu" "F.Mask" "F.Paste")
			(net "DDR_VDDQ")
		)
		(pad "2" smd rect
			(at 0 1.6764 90)
			(size 1.524 1.524)
			(layers "F.Cu" "F.Mask" "F.Paste")
			(net "GND")
		)
		(zone
			(layer "F.Cu")
			(hatch none 0.5)
			(connect_pads
				(clearance 0)
			)
			(min_thickness 0.25)
			(keepout
				(tracks not_allowed)
				(vias allowed)
				(pads allowed)
				(copperpour not_allowed)
				(footprints allowed)
			)
			(placement
				(enabled no)
				(sheetname "")
			)
			(fill
				(thermal_gap 0.5)
				(thermal_bridge_width 0.5)
				(island_removal_mode 0)
			)
			(polygon
				(pts
					(xy 77.4192 50.3174) (xy 77.4192 48.7426) (xy 77.5716 48.7426) (xy 77.5716 50.3174)
				)
			)
		)
		(zone
			(layer "F.Cu")
			(hatch none 0.5)
			(connect_pads
				(clearance 0)
			)
			(min_thickness 0.25)
			(keepout
				(tracks not_allowed)
				(vias allowed)
				(pads allowed)
				(copperpour not_allowed)
				(footprints allowed)
			)
			(placement
				(enabled no)
				(sheetname "")
			)
			(fill
				(thermal_gap 0.5)
				(thermal_bridge_width 0.5)
				(island_removal_mode 0)
			)
			(polygon
				(pts
					(xy 79.0448 50.3174) (xy 79.0448 48.7426) (xy 79.1972 48.7426) (xy 79.1972 50.3174)
				)
			)
		)
		(zone
			(layer "F.Cu")
			(hatch none 0.5)
			(connect_pads
				(clearance 0)
			)
			(min_thickness 0.25)
			(keepout
				(tracks allowed)
				(vias not_allowed)
				(pads allowed)
				(copperpour not_allowed)
				(footprints allowed)
			)
			(placement
				(enabled no)
				(sheetname "")
			)
			(fill
				(thermal_gap 0.5)
				(thermal_bridge_width 0.5)
				(island_removal_mode 0)
			)
			(polygon
				(pts
					(xy 79.9084 50.3174) (xy 79.9084 48.7426) (xy 76.708 48.7426) (xy 76.708 50.3174)
				)
			)
		)
	)
	(footprint ""
		(layer "F.Cu")
		(at 17.78 24.384 180)
		(property "Reference" "R395"
			(at 0.48133 1.27 90)
			(unlocked yes)
			(layer "F.SilkS")
			(effects
				(font
					(size 0.7874 0.5842)
					(thickness 0.127)
				)
				(justify left)
			)
		)
		(property "Value" "4.75K"
			(at -0.148158 1.3462 270)
			(unlocked yes)
			(layer "F.Fab")
			(hide yes)
			(effects
				(font
					(size 1.27 0.9652)
					(thickness 0.000001)
				)
				(justify left)
			)
		)
		(property "Device Type" "REST4024"
			(at -0.148158 1.3462 270)
			(unlocked yes)
			(layer "F.Fab")
			(hide yes)
			(effects
				(font
					(size 1.27 0.9652)
					(thickness 0.000001)
				)
				(justify left)
			)
		)
		(duplicate_pad_numbers_are_jumpers no)
		(fp_poly
			(pts
				(xy 0.635 1.0668) (xy 0.635 -1.0668) (xy -0.635 -1.0668) (xy -0.635 1.0668)
			)
			(stroke
				(width 0)
				(type default)
			)
			(fill no)
			(layer "F.CrtYd")
		)
		(fp_line
			(start 0.254 0.508)
			(end -0.254 0.508)
			(stroke
				(width 0.0254)
				(type default)
			)
			(layer "F.Fab")
		)
		(fp_line
			(start 0.254 -0.508)
			(end 0.254 0.508)
			(stroke
				(width 0.0254)
				(type default)
			)
			(layer "F.Fab")
		)
		(fp_line
			(start -0.254 0.508)
			(end -0.254 -0.508)
			(stroke
				(width 0.0254)
				(type default)
			)
			(layer "F.Fab")
		)
		(fp_line
			(start -0.254 -0.508)
			(end 0.254 -0.508)
			(stroke
				(width 0.0254)
				(type default)
			)
			(layer "F.Fab")
		)
		(pad "1" smd rect
			(at 0 -0.4191 180)
			(size 0.508 0.5334)
			(layers "F.Cu" "F.Mask" "F.Paste")
			(net "EXT_3.3V")
		)
		(pad "2" smd rect
			(at 0 0.4191 180)
			(size 0.508 0.5334)
			(layers "F.Cu" "F.Mask" "F.Paste")
			(net "CPLD_NIC_MEZZ_ID1")
		)
		(zone
			(layer "F.Cu")
			(hatch none 0.5)
			(connect_pads
				(clearance 0)
			)
			(min_thickness 0.25)
			(keepout
				(tracks not_allowed)
				(vias allowed)
				(pads allowed)
				(copperpour not_allowed)
				(footprints allowed)
			)
			(placement
				(enabled no)
				(sheetname "")
			)
			(fill
				(thermal_gap 0.5)
				(thermal_bridge_width 0.5)
				(island_removal_mode 0)
			)
			(polygon
				(pts
					(xy 17.7546 24.4094) (xy 17.7546 24.3586) (xy 17.8054 24.3586) (xy 17.8054 24.4094)
				)
			)
		)
	)
	(footprint ""
		(layer "F.Cu")
		(at 11.811 33.528 -90)
		(property "Reference" "C134"
			(at -0.98933 1.524 0)
			(unlocked yes)
			(layer "F.SilkS")
			(effects
				(font
					(size 0.7874 0.5842)
					(thickness 0.127)
				)
				(justify left)
			)
		)
		(property "Value" "10UF"
			(at -0.148158 1.7526 0)
			(unlocked yes)
			(layer "F.Fab")
			(hide yes)
			(effects
				(font
					(size 1.27 0.9652)
					(thickness 0.000001)
				)
				(justify left)
			)
		)
		(property "Device Type" "CAPC0058"
			(at -0.148158 1.7526 0)
			(unlocked yes)
			(layer "F.Fab")
			(hide yes)
			(effects
				(font
					(size 1.27 0.9652)
					(thickness 0.000001)
				)
				(justify left)
			)
		)
		(duplicate_pad_numbers_are_jumpers no)
		(fp_circle
			(center 0 0)
			(end 0 -0.127)
			(stroke
				(width 0.2032)
				(type default)
			)
			(fill no)
			(layer "F.SilkS")
		)
		(fp_poly
			(pts
				(xy 0.7874 -1.6637) (xy -0.7874 -1.6637) (xy -0.7874 1.6637) (xy 0.7874 1.6637)
			)
			(stroke
				(width 0)
				(type default)
			)
			(fill no)
			(layer "F.CrtYd")
		)
		(fp_line
			(start -0.4064 0.8128)
			(end -0.4064 -0.7874)
			(stroke
				(width 0.0254)
				(type default)
			)
			(layer "F.Fab")
		)
		(fp_line
			(start 0.4064 0.8128)
			(end -0.4064 0.8128)
			(stroke
				(width 0.0254)
				(type default)
			)
			(layer "F.Fab")
		)
		(fp_line
			(start -0.4064 -0.7874)
			(end 0.4064 -0.7874)
			(stroke
				(width 0.0254)
				(type default)
			)
			(layer "F.Fab")
		)
		(fp_line
			(start 0.4064 -0.7874)
			(end 0.4064 0.8128)
			(stroke
				(width 0.0254)
				(type default)
			)
			(layer "F.Fab")
		)
		(pad "1" smd rect
			(at 0 -0.8001 270)
			(size 0.8636 0.9652)
			(layers "F.Cu" "F.Mask" "F.Paste")
			(net "VDD_5.0V")
		)
		(pad "2" smd rect
			(at 0 0.8001 270)
			(size 0.8636 0.9652)
			(layers "F.Cu" "F.Mask" "F.Paste")
			(net "GND")
		)
	)
	(footprint ""
		(layer "F.Cu")
		(at 30.099 32.639)
		(property "Reference" "R96"
			(at 0 0 0)
			(layer "F.SilkS")
			(hide yes)
			(effects
				(font
					(size 1.27 1.27)
				)
			)
		)
		(property "Value" "4.75K"
			(at -0.148158 1.3462 90)
			(unlocked yes)
			(layer "F.Fab")
			(hide yes)
			(effects
				(font
					(size 1.27 0.9652)
					(thickness 0.000001)
				)
				(justify left)
			)
		)
		(property "Device Type" "REST4024"
			(at -0.148158 1.3462 90)
			(unlocked yes)
			(layer "F.Fab")
			(hide yes)
			(effects
				(font
					(size 1.27 0.9652)
					(thickness 0.000001)
				)
				(justify left)
			)
		)
		(duplicate_pad_numbers_are_jumpers no)
		(fp_poly
			(pts
				(xy 0.635 1.0668) (xy 0.635 -1.0668) (xy -0.635 -1.0668) (xy -0.635 1.0668)
			)
			(stroke
				(width 0)
				(type default)
			)
			(fill no)
			(layer "F.CrtYd")
		)
		(fp_line
			(start -0.254 -0.508)
			(end 0.254 -0.508)
			(stroke
				(width 0.0254)
				(type default)
			)
			(layer "F.Fab")
		)
		(fp_line
			(start -0.254 0.508)
			(end -0.254 -0.508)
			(stroke
				(width 0.0254)
				(type default)
			)
			(layer "F.Fab")
		)
		(fp_line
			(start 0.254 -0.508)
			(end 0.254 0.508)
			(stroke
				(width 0.0254)
				(type default)
			)
			(layer "F.Fab")
		)
		(fp_line
			(start 0.254 0.508)
			(end -0.254 0.508)
			(stroke
				(width 0.0254)
				(type default)
			)
			(layer "F.Fab")
		)
		(pad "1" smd rect
			(at 0 -0.4191)
			(size 0.508 0.5334)
			(layers "F.Cu" "F.Mask" "F.Paste")
			(net "GND")
		)
		(pad "2" smd rect
			(at 0 0.4191)
			(size 0.508 0.5334)
			(layers "F.Cu" "F.Mask" "F.Paste")
			(net "_NFP_CORE_VID2")
		)
		(zone
			(layer "F.Cu")
			(hatch none 0.5)
			(connect_pads
				(clearance 0)
			)
			(min_thickness 0.25)
			(keepout
				(tracks not_allowed)
				(vias allowed)
				(pads allowed)
				(copperpour not_allowed)
				(footprints allowed)
			)
			(placement
				(enabled no)
				(sheetname "")
			)
			(fill
				(thermal_gap 0.5)
				(thermal_bridge_width 0.5)
				(island_removal_mode 0)
			)
			(polygon
				(pts
					(xy 30.1244 32.6136) (xy 30.1244 32.6644) (xy 30.0736 32.6644) (xy 30.0736 32.6136)
				)
			)
		)
	)
	(footprint ""
		(layer "F.Cu")
		(at 76.708 29.083 -90)
		(property "Reference" "R7"
			(at 0.91567 -0.508 0)
			(unlocked yes)
			(layer "F.SilkS")
			(effects
				(font
					(size 0.7874 0.5842)
					(thickness 0.127)
				)
				(justify left)
			)
		)
		(property "Value" "36.0"
			(at -0.148158 1.3462 0)
			(unlocked yes)
			(layer "F.Fab")
			(hide yes)
			(effects
				(font
					(size 1.27 0.9652)
					(thickness 0.000001)
				)
				(justify left)
			)
		)
		(property "Device Type" "REST0125"
			(at -0.148158 1.3462 0)
			(unlocked yes)
			(layer "F.Fab")
			(hide yes)
			(effects
				(font
					(size 1.27 0.9652)
					(thickness 0.000001)
				)
				(justify left)
			)
		)
		(duplicate_pad_numbers_are_jumpers no)
		(fp_poly
			(pts
				(xy 0.635 1.0668) (xy 0.635 -1.0668) (xy -0.635 -1.0668) (xy -0.635 1.0668)
			)
			(stroke
				(width 0)
				(type default)
			)
			(fill no)
			(layer "F.CrtYd")
		)
		(fp_line
			(start -0.254 0.508)
			(end -0.254 -0.508)
			(stroke
				(width 0.0254)
				(type default)
			)
			(layer "F.Fab")
		)
		(fp_line
			(start 0.254 0.508)
			(end -0.254 0.508)
			(stroke
				(width 0.0254)
				(type default)
			)
			(layer "F.Fab")
		)
		(fp_line
			(start -0.254 -0.508)
			(end 0.254 -0.508)
			(stroke
				(width 0.0254)
				(type default)
			)
			(layer "F.Fab")
		)
		(fp_line
			(start 0.254 -0.508)
			(end 0.254 0.508)
			(stroke
				(width 0.0254)
				(type default)
			)
			(layer "F.Fab")
		)
		(pad "1" smd rect
			(at 0 -0.4191 270)
			(size 0.508 0.5334)
			(layers "F.Cu" "F.Mask" "F.Paste")
			(net "DDR0_32A_CK0_P")
		)
		(pad "2" smd rect
			(at 0 0.4191 270)
			(size 0.508 0.5334)
			(layers "F.Cu" "F.Mask" "F.Paste")
			(net "6N4748")
		)
		(zone
			(layer "F.Cu")
			(hatch none 0.5)
			(connect_pads
				(clearance 0)
			)
			(min_thickness 0.25)
			(keepout
				(tracks not_allowed)
				(vias allowed)
				(pads allowed)
				(copperpour not_allowed)
				(footprints allowed)
			)
			(placement
				(enabled no)
				(sheetname "")
			)
			(fill
				(thermal_gap 0.5)
				(thermal_bridge_width 0.5)
				(island_removal_mode 0)
			)
			(polygon
				(pts
					(xy 76.7334 29.1084) (xy 76.6826 29.1084) (xy 76.6826 29.0576) (xy 76.7334 29.0576)
				)
			)
		)
	)
	(footprint ""
		(layer "F.Cu")
		(at 14.732 40.894 90)
		(property "Reference" "C133"
			(at 0.86233 -1.524 0)
			(unlocked yes)
			(layer "F.SilkS")
			(effects
				(font
					(size 0.7874 0.5842)
					(thickness 0.127)
				)
				(justify left)
			)
		)
		(property "Value" "10UF"
			(at -0.148158 1.7526 180)
			(unlocked yes)
			(layer "F.Fab")
			(hide yes)
			(effects
				(font
					(size 1.27 0.9652)
					(thickness 0.000001)
				)
				(justify left)
			)
		)
		(property "Device Type" "CAPC0058"
			(at -0.148158 1.7526 180)
			(unlocked yes)
			(layer "F.Fab")
			(hide yes)
			(effects
				(font
					(size 1.27 0.9652)
					(thickness 0.000001)
				)
				(justify left)
			)
		)
		(duplicate_pad_numbers_are_jumpers no)
		(fp_circle
			(center 0 0)
			(end 0 0.127)
			(stroke
				(width 0.2032)
				(type default)
			)
			(fill no)
			(layer "F.SilkS")
		)
		(fp_poly
			(pts
				(xy 0.7874 -1.6637) (xy -0.7874 -1.6637) (xy -0.7874 1.6637) (xy 0.7874 1.6637)
			)
			(stroke
				(width 0)
				(type default)
			)
			(fill no)
			(layer "F.CrtYd")
		)
		(fp_line
			(start 0.4064 -0.7874)
			(end 0.4064 0.8128)
			(stroke
				(width 0.0254)
				(type default)
			)
			(layer "F.Fab")
		)
		(fp_line
			(start -0.4064 -0.7874)
			(end 0.4064 -0.7874)
			(stroke
				(width 0.0254)
				(type default)
			)
			(layer "F.Fab")
		)
		(fp_line
			(start 0.4064 0.8128)
			(end -0.4064 0.8128)
			(stroke
				(width 0.0254)
				(type default)
			)
			(layer "F.Fab")
		)
		(fp_line
			(start -0.4064 0.8128)
			(end -0.4064 -0.7874)
			(stroke
				(width 0.0254)
				(type default)
			)
			(layer "F.Fab")
		)
		(pad "1" smd rect
			(at 0 -0.8001 90)
			(size 0.8636 0.9652)
			(layers "F.Cu" "F.Mask" "F.Paste")
			(net "VDD_5.0V")
		)
		(pad "2" smd rect
			(at 0 0.8001 90)
			(size 0.8636 0.9652)
			(layers "F.Cu" "F.Mask" "F.Paste")
			(net "GND")
		)
	)
	(footprint ""
		(layer "F.Cu")
		(at 42.418 51.816 180)
		(property "Reference" "R317"
			(at 3.302 -0.02667 0)
			(unlocked yes)
			(layer "F.SilkS")
			(effects
				(font
					(size 0.7874 0.5842)
					(thickness 0.127)
				)
				(justify left)
			)
		)
		(property "Value" "1.0K"
			(at -0.148158 1.3462 270)
			(unlocked yes)
			(layer "F.Fab")
			(hide yes)
			(effects
				(font
					(size 1.27 0.9652)
					(thickness 0.000001)
				)
				(justify left)
			)
		)
		(property "Device Type" "REST0025"
			(at -0.148158 1.3462 270)
			(unlocked yes)
			(layer "F.Fab")
			(hide yes)
			(effects
				(font
					(size 1.27 0.9652)
					(thickness 0.000001)
				)
				(justify left)
			)
		)
		(duplicate_pad_numbers_are_jumpers no)
		(fp_poly
			(pts
				(xy 0.635 1.0668) (xy 0.635 -1.0668) (xy -0.635 -1.0668) (xy -0.635 1.0668)
			)
			(stroke
				(width 0)
				(type default)
			)
			(fill no)
			(layer "F.CrtYd")
		)
		(fp_line
			(start 0.254 0.508)
			(end -0.254 0.508)
			(stroke
				(width 0.0254)
				(type default)
			)
			(layer "F.Fab")
		)
		(fp_line
			(start 0.254 -0.508)
			(end 0.254 0.508)
			(stroke
				(width 0.0254)
				(type default)
			)
			(layer "F.Fab")
		)
		(fp_line
			(start -0.254 0.508)
			(end -0.254 -0.508)
			(stroke
				(width 0.0254)
				(type default)
			)
			(layer "F.Fab")
		)
		(fp_line
			(start -0.254 -0.508)
			(end 0.254 -0.508)
			(stroke
				(width 0.0254)
				(type default)
			)
			(layer "F.Fab")
		)
		(pad "1" smd rect
			(at 0 -0.4191 180)
			(size 0.508 0.5334)
			(layers "F.Cu" "F.Mask" "F.Paste")
			(net "GND")
		)
		(pad "2" smd rect
			(at 0 0.4191 180)
			(size 0.508 0.5334)
			(layers "F.Cu" "F.Mask" "F.Paste")
			(net "EXT_12.0V_THRESHOLD")
		)
		(zone
			(layer "F.Cu")
			(hatch none 0.5)
			(connect_pads
				(clearance 0)
			)
			(min_thickness 0.25)
			(keepout
				(tracks not_allowed)
				(vias allowed)
				(pads allowed)
				(copperpour not_allowed)
				(footprints allowed)
			)
			(placement
				(enabled no)
				(sheetname "")
			)
			(fill
				(thermal_gap 0.5)
				(thermal_bridge_width 0.5)
				(island_removal_mode 0)
			)
			(polygon
				(pts
					(xy 42.3926 51.8414) (xy 42.3926 51.7906) (xy 42.4434 51.7906) (xy 42.4434 51.8414)
				)
			)
		)
	)
	(footprint ""
		(layer "F.Cu")
		(at 75.451005 7.498994)
		(property "Reference" "V_A-DQ07"
			(at 0 0 0)
			(layer "F.SilkS")
			(hide yes)
			(effects
				(font
					(size 1.27 1.27)
				)
			)
		)
		(property "Value" ""
			(at 0 0 0)
			(layer "F.Fab")
			(effects
				(font
					(size 1.27 1.27)
				)
			)
		)
		(duplicate_pad_numbers_are_jumpers no)
		(pad "1" thru_hole circle
			(at 0 0)
			(size 0.762 0.762)
			(drill 0.20574)
			(layers "*.Cu" "*.Mask")
			(remove_unused_layers no)
			(net "DDR0_32A_DQ7")
			(clearance 0.127)
			(thermal_gap 0.127)
			(padstack
				(mode front_inner_back)
				(layer "Inner"
					(shape circle)
					(size 0.4572 0.4572)
					(clearance 0.1143)
				)
				(layer "B.Cu"
					(shape circle)
					(size 0.4572 0.4572)
					(clearance 0.1143)
				)
			)
		)
	)
	(footprint ""
		(layer "F.Cu")
		(at 84.582 26.924)
		(property "Reference" "R219"
			(at 0 -1.24333 0)
			(unlocked yes)
			(layer "F.SilkS")
			(effects
				(font
					(size 0.7874 0.5842)
					(thickness 0.127)
				)
				(justify left)
			)
		)
		(property "Value" "39.0"
			(at -0.148158 1.3462 90)
			(unlocked yes)
			(layer "F.Fab")
			(hide yes)
			(effects
				(font
					(size 1.27 0.9652)
					(thickness 0.000001)
				)
				(justify left)
			)
		)
		(property "Device Type" "REST0108"
			(at -0.148158 1.3462 90)
			(unlocked yes)
			(layer "F.Fab")
			(hide yes)
			(effects
				(font
					(size 1.27 0.9652)
					(thickness 0.000001)
				)
				(justify left)
			)
		)
		(duplicate_pad_numbers_are_jumpers no)
		(fp_poly
			(pts
				(xy 0.635 1.0668) (xy 0.635 -1.0668) (xy -0.635 -1.0668) (xy -0.635 1.0668)
			)
			(stroke
				(width 0)
				(type default)
			)
			(fill no)
			(layer "F.CrtYd")
		)
		(fp_line
			(start -0.254 -0.508)
			(end 0.254 -0.508)
			(stroke
				(width 0.0254)
				(type default)
			)
			(layer "F.Fab")
		)
		(fp_line
			(start -0.254 0.508)
			(end -0.254 -0.508)
			(stroke
				(width 0.0254)
				(type default)
			)
			(layer "F.Fab")
		)
		(fp_line
			(start 0.254 -0.508)
			(end 0.254 0.508)
			(stroke
				(width 0.0254)
				(type default)
			)
			(layer "F.Fab")
		)
		(fp_line
			(start 0.254 0.508)
			(end -0.254 0.508)
			(stroke
				(width 0.0254)
				(type default)
			)
			(layer "F.Fab")
		)
		(pad "1" smd rect
			(at 0 -0.4191)
			(size 0.508 0.5334)
			(layers "F.Cu" "F.Mask" "F.Paste")
			(net "DDR0_32A_A13")
		)
		(pad "2" smd rect
			(at 0 0.4191)
			(size 0.508 0.5334)
			(layers "F.Cu" "F.Mask" "F.Paste")
			(net "DDR_VTT")
		)
		(zone
			(layer "F.Cu")
			(hatch none 0.5)
			(connect_pads
				(clearance 0)
			)
			(min_thickness 0.25)
			(keepout
				(tracks not_allowed)
				(vias allowed)
				(pads allowed)
				(copperpour not_allowed)
				(footprints allowed)
			)
			(placement
				(enabled no)
				(sheetname "")
			)
			(fill
				(thermal_gap 0.5)
				(thermal_bridge_width 0.5)
				(island_removal_mode 0)
			)
			(polygon
				(pts
					(xy 84.6074 26.8986) (xy 84.6074 26.9494) (xy 84.5566 26.9494) (xy 84.5566 26.8986)
				)
			)
		)
	)
	(footprint ""
		(layer "F.Cu")
		(at 83.693 28.702 180)
		(property "Reference" "R217"
			(at 0 0 180)
			(layer "F.SilkS")
			(hide yes)
			(effects
				(font
					(size 1.27 1.27)
				)
			)
		)
		(property "Value" "39.0"
			(at -0.148158 1.3462 270)
			(unlocked yes)
			(layer "F.Fab")
			(hide yes)
			(effects
				(font
					(size 1.27 0.9652)
					(thickness 0.000001)
				)
				(justify left)
			)
		)
		(property "Device Type" "REST0108"
			(at -0.148158 1.3462 270)
			(unlocked yes)
			(layer "F.Fab")
			(hide yes)
			(effects
				(font
					(size 1.27 0.9652)
					(thickness 0.000001)
				)
				(justify left)
			)
		)
		(duplicate_pad_numbers_are_jumpers no)
		(fp_poly
			(pts
				(xy 0.635 1.0668) (xy 0.635 -1.0668) (xy -0.635 -1.0668) (xy -0.635 1.0668)
			)
			(stroke
				(width 0)
				(type default)
			)
			(fill no)
			(layer "F.CrtYd")
		)
		(fp_line
			(start 0.254 0.508)
			(end -0.254 0.508)
			(stroke
				(width 0.0254)
				(type default)
			)
			(layer "F.Fab")
		)
		(fp_line
			(start 0.254 -0.508)
			(end 0.254 0.508)
			(stroke
				(width 0.0254)
				(type default)
			)
			(layer "F.Fab")
		)
		(fp_line
			(start -0.254 0.508)
			(end -0.254 -0.508)
			(stroke
				(width 0.0254)
				(type default)
			)
			(layer "F.Fab")
		)
		(fp_line
			(start -0.254 -0.508)
			(end 0.254 -0.508)
			(stroke
				(width 0.0254)
				(type default)
			)
			(layer "F.Fab")
		)
		(pad "1" smd rect
			(at 0 -0.4191 180)
			(size 0.508 0.5334)
			(layers "F.Cu" "F.Mask" "F.Paste")
			(net "DDR0_32A_A11")
		)
		(pad "2" smd rect
			(at 0 0.4191 180)
			(size 0.508 0.5334)
			(layers "F.Cu" "F.Mask" "F.Paste")
			(net "DDR_VTT")
		)
		(zone
			(layer "F.Cu")
			(hatch none 0.5)
			(connect_pads
				(clearance 0)
			)
			(min_thickness 0.25)
			(keepout
				(tracks not_allowed)
				(vias allowed)
				(pads allowed)
				(copperpour not_allowed)
				(footprints allowed)
			)
			(placement
				(enabled no)
				(sheetname "")
			)
			(fill
				(thermal_gap 0.5)
				(thermal_bridge_width 0.5)
				(island_removal_mode 0)
			)
			(polygon
				(pts
					(xy 83.6676 28.7274) (xy 83.6676 28.6766) (xy 83.7184 28.6766) (xy 83.7184 28.7274)
				)
			)
		)
	)
	(footprint ""
		(layer "F.Cu")
		(at 79.1972 22.987 180)
		(property "Reference" "R229"
			(at 0 0 180)
			(layer "F.SilkS")
			(hide yes)
			(effects
				(font
					(size 1.27 1.27)
				)
			)
		)
		(property "Value" "39.0"
			(at -0.148158 1.3462 270)
			(unlocked yes)
			(layer "F.Fab")
			(hide yes)
			(effects
				(font
					(size 1.27 0.9652)
					(thickness 0.000001)
				)
				(justify left)
			)
		)
		(property "Device Type" "REST0108"
			(at -0.148158 1.3462 270)
			(unlocked yes)
			(layer "F.Fab")
			(hide yes)
			(effects
				(font
					(size 1.27 0.9652)
					(thickness 0.000001)
				)
				(justify left)
			)
		)
		(duplicate_pad_numbers_are_jumpers no)
		(fp_poly
			(pts
				(xy 0.635 1.0668) (xy 0.635 -1.0668) (xy -0.635 -1.0668) (xy -0.635 1.0668)
			)
			(stroke
				(width 0)
				(type default)
			)
			(fill no)
			(layer "F.CrtYd")
		)
		(fp_line
			(start 0.254 0.508)
			(end -0.254 0.508)
			(stroke
				(width 0.0254)
				(type default)
			)
			(layer "F.Fab")
		)
		(fp_line
			(start 0.254 -0.508)
			(end 0.254 0.508)
			(stroke
				(width 0.0254)
				(type default)
			)
			(layer "F.Fab")
		)
		(fp_line
			(start -0.254 0.508)
			(end -0.254 -0.508)
			(stroke
				(width 0.0254)
				(type default)
			)
			(layer "F.Fab")
		)
		(fp_line
			(start -0.254 -0.508)
			(end 0.254 -0.508)
			(stroke
				(width 0.0254)
				(type default)
			)
			(layer "F.Fab")
		)
		(pad "1" smd rect
			(at 0 -0.4191 180)
			(size 0.508 0.5334)
			(layers "F.Cu" "F.Mask" "F.Paste")
			(net "DDR0_32A_CS0_L")
		)
		(pad "2" smd rect
			(at 0 0.4191 180)
			(size 0.508 0.5334)
			(layers "F.Cu" "F.Mask" "F.Paste")
			(net "DDR_VTT")
		)
		(zone
			(layer "F.Cu")
			(hatch none 0.5)
			(connect_pads
				(clearance 0)
			)
			(min_thickness 0.25)
			(keepout
				(tracks not_allowed)
				(vias allowed)
				(pads allowed)
				(copperpour not_allowed)
				(footprints allowed)
			)
			(placement
				(enabled no)
				(sheetname "")
			)
			(fill
				(thermal_gap 0.5)
				(thermal_bridge_width 0.5)
				(island_removal_mode 0)
			)
			(polygon
				(pts
					(xy 79.1718 23.0124) (xy 79.1718 22.9616) (xy 79.2226 22.9616) (xy 79.2226 23.0124)
				)
			)
		)
	)
	(footprint ""
		(layer "F.Cu")
		(at 81.6356 41.529)
		(property "Reference" "U3"
			(at -2.1336 -2.51333 0)
			(unlocked yes)
			(layer "F.SilkS")
			(effects
				(font
					(size 0.7874 0.5842)
					(thickness 0.127)
				)
				(justify left)
			)
		)
		(property "Value" "*"
			(at -0.4826 -0.105105 0)
			(unlocked yes)
			(layer "F.Fab")
			(hide yes)
			(effects
				(font
					(size 1.27 0.9652)
					(thickness 0.000001)
				)
				(justify left)
			)
		)
		(property "Device Type" "DCDC0049"
			(at -0.4826 -0.105105 0)
			(unlocked yes)
			(layer "F.Fab")
			(hide yes)
			(effects
				(font
					(size 1.27 0.9652)
					(thickness 0.000001)
				)
				(justify left)
			)
		)
		(duplicate_pad_numbers_are_jumpers no)
		(fp_line
			(start -1.905 -1.905)
			(end -1.27 -1.905)
			(stroke
				(width 0.1524)
				(type default)
			)
			(layer "F.SilkS")
		)
		(fp_line
			(start -1.905 -1.905)
			(end -1.27 -1.905)
			(stroke
				(width 0.1524)
				(type default)
			)
			(layer "F.SilkS")
		)
		(fp_line
			(start -1.905 -1.27)
			(end -1.905 -1.905)
			(stroke
				(width 0.1524)
				(type default)
			)
			(layer "F.SilkS")
		)
		(fp_line
			(start -1.905 -1.27)
			(end -1.905 -1.905)
			(stroke
				(width 0.1524)
				(type default)
			)
			(layer "F.SilkS")
		)
		(fp_line
			(start -1.905 -1.27)
			(end -1.27 -1.905)
			(stroke
				(width 0.1524)
				(type default)
			)
			(layer "F.SilkS")
		)
		(fp_line
			(start -1.905 -1.27)
			(end -1.27 -1.905)
			(stroke
				(width 0.1524)
				(type default)
			)
			(layer "F.SilkS")
		)
		(fp_line
			(start -1.905 1.905)
			(end -1.905 1.27)
			(stroke
				(width 0.1524)
				(type default)
			)
			(layer "F.SilkS")
		)
		(fp_line
			(start -1.27 1.905)
			(end -1.905 1.905)
			(stroke
				(width 0.1524)
				(type default)
			)
			(layer "F.SilkS")
		)
		(fp_line
			(start 1.27 -1.905)
			(end 1.905 -1.905)
			(stroke
				(width 0.1524)
				(type default)
			)
			(layer "F.SilkS")
		)
		(fp_line
			(start 1.27 1.905)
			(end 1.905 1.905)
			(stroke
				(width 0.1524)
				(type default)
			)
			(layer "F.SilkS")
		)
		(fp_line
			(start 1.27 1.905)
			(end 1.905 1.905)
			(stroke
				(width 0.1524)
				(type default)
			)
			(layer "F.SilkS")
		)
		(fp_line
			(start 1.905 -1.905)
			(end 1.905 -1.27)
			(stroke
				(width 0.1524)
				(type default)
			)
			(layer "F.SilkS")
		)
		(fp_line
			(start 1.905 -1.905)
			(end 1.905 -1.27)
			(stroke
				(width 0.1524)
				(type default)
			)
			(layer "F.SilkS")
		)
		(fp_line
			(start 1.905 1.905)
			(end 1.905 1.27)
			(stroke
				(width 0.1524)
				(type default)
			)
			(layer "F.SilkS")
		)
		(fp_arc
			(start -2.39776 -1.207389)
			(mid -2.345186 -1.236366)
			(end -2.286 -1.246403)
			(stroke
				(width 0.1524)
				(type default)
			)
			(layer "F.SilkS")
		)
		(fp_arc
			(start -2.286 -1.246403)
			(mid -2.249785 -1.242714)
			(end -2.215058 -1.231798)
			(stroke
				(width 0.1524)
				(type default)
			)
			(layer "F.SilkS")
		)
		(fp_circle
			(center -2.286 -1.0668)
			(end -2.106397 -1.0668)
			(stroke
				(width 0.1524)
				(type default)
			)
			(fill no)
			(layer "F.SilkS")
		)
		(fp_poly
			(pts
				(xy -2.54 2.54) (xy 2.54 2.54) (xy 2.54 -2.54) (xy -1.093597 -2.54) (xy -1.093597 -2.202104) (xy -2.353589 -0.942111)
				(xy -2.54 -0.942111)
			)
			(stroke
				(width 0)
				(type default)
			)
			(fill no)
			(layer "F.CrtYd")
		)
		(fp_line
			(start -1.5494 -1.5494)
			(end -1.5494 1.5494)
			(stroke
				(width 0.1524)
				(type default)
			)
			(layer "F.Fab")
		)
		(fp_line
			(start -1.5494 1.5494)
			(end 1.5494 1.5494)
			(stroke
				(width 0.1524)
				(type default)
			)
			(layer "F.Fab")
		)
		(fp_line
			(start -1.524 -1.016)
			(end -1.016 -1.524)
			(stroke
				(width 0.1524)
				(type default)
			)
			(layer "F.Fab")
		)
		(fp_line
			(start 1.5494 -1.5494)
			(end -1.5494 -1.5494)
			(stroke
				(width 0.1524)
				(type default)
			)
			(layer "F.Fab")
		)
		(fp_line
			(start 1.5494 1.5494)
			(end 1.5494 -1.5494)
			(stroke
				(width 0.1524)
				(type default)
			)
			(layer "F.Fab")
		)
		(fp_circle
			(center -0.889 -0.889)
			(end -0.605003 -0.889)
			(stroke
				(width 0.1524)
				(type default)
			)
			(fill no)
			(layer "F.Fab")
		)
		(pad "1" smd custom
			(at -1.4986 -0.799998 270)
			(size 0.0508 0.0508)
			(layers "F.Cu" "F.Mask" "F.Paste")
			(net "11N2199")
			(options
				(clearance outline)
				(anchor circle)
			)
			(primitives
				(gr_poly
					(pts
						(arc
							(start -0.1016 -0.3048)
							(mid 0 -0.4064)
							(end 0.1016 -0.3048)
						)
						(xy 0.1016 0.4064) (xy -0.1016 0.4064)
					)
					(width 0)
					(fill yes)
				)
			)
		)
		(pad "2" smd custom
			(at -1.4986 -0.399999 270)
			(size 0.0508 0.0508)
			(layers "F.Cu" "F.Mask" "F.Paste")
			(net "DDR_VDDQ")
			(options
				(clearance outline)
				(anchor circle)
			)
			(primitives
				(gr_poly
					(pts
						(arc
							(start -0.1016 -0.3048)
							(mid 0 -0.4064)
							(end 0.1016 -0.3048)
						)
						(xy 0.1016 0.4064) (xy -0.1016 0.4064)
					)
					(width 0)
					(fill yes)
				)
			)
		)
		(pad "3" smd custom
			(at -1.4986 0 270)
			(size 0.0508 0.0508)
			(layers "F.Cu" "F.Mask" "F.Paste")
			(net "DDR_VTT")
			(options
				(clearance outline)
				(anchor circle)
			)
			(primitives
				(gr_poly
					(pts
						(arc
							(start -0.1016 -0.3048)
							(mid 0 -0.4064)
							(end 0.1016 -0.3048)
						)
						(xy 0.1016 0.4064) (xy -0.1016 0.4064)
					)
					(width 0)
					(fill yes)
				)
			)
		)
		(pad "4" smd custom
			(at -1.4986 0.399999 270)
			(size 0.0508 0.0508)
			(layers "F.Cu" "F.Mask" "F.Paste")
			(net "GND")
			(options
				(clearance outline)
				(anchor circle)
			)
			(primitives
				(gr_poly
					(pts
						(arc
							(start -0.1016 -0.3048)
							(mid 0 -0.4064)
							(end 0.1016 -0.3048)
						)
						(xy 0.1016 0.4064) (xy -0.1016 0.4064)
					)
					(width 0)
					(fill yes)
				)
			)
		)
		(pad "5" smd custom
			(at -1.4986 0.799998 270)
			(size 0.0508 0.0508)
			(layers "F.Cu" "F.Mask" "F.Paste")
			(net "11N2202")
			(options
				(clearance outline)
				(anchor circle)
			)
			(primitives
				(gr_poly
					(pts
						(arc
							(start -0.1016 -0.3048)
							(mid 0 -0.4064)
							(end 0.1016 -0.3048)
						)
						(xy 0.1016 0.4064) (xy -0.1016 0.4064)
					)
					(width 0)
					(fill yes)
				)
			)
		)
		(pad "6" smd custom
			(at -0.799998 1.4986)
			(size 0.0508 0.0508)
			(layers "F.Cu" "F.Mask" "F.Paste")
			(net "11N2152")
			(options
				(clearance outline)
				(anchor circle)
			)
			(primitives
				(gr_poly
					(pts
						(arc
							(start -0.1016 -0.3048)
							(mid 0 -0.4064)
							(end 0.1016 -0.3048)
						)
						(xy 0.1016 0.4064) (xy -0.1016 0.4064)
					)
					(width 0)
					(fill yes)
				)
			)
		)
		(pad "7" smd custom
			(at -0.399999 1.4986)
			(size 0.0508 0.0508)
			(layers "F.Cu" "F.Mask" "F.Paste")
			(net "GND")
			(options
				(clearance outline)
				(anchor circle)
			)
			(primitives
				(gr_poly
					(pts
						(arc
							(start -0.1016 -0.3048)
							(mid 0 -0.4064)
							(end 0.1016 -0.3048)
						)
						(xy 0.1016 0.4064) (xy -0.1016 0.4064)
					)
					(width 0)
					(fill yes)
				)
			)
		)
		(pad "8" smd custom
			(at 0 1.4986)
			(size 0.0508 0.0508)
			(layers "F.Cu" "F.Mask" "F.Paste")
			(net "11N2146")
			(options
				(clearance outline)
				(anchor circle)
			)
			(primitives
				(gr_poly
					(pts
						(arc
							(start -0.1016 -0.3048)
							(mid 0 -0.4064)
							(end 0.1016 -0.3048)
						)
						(xy 0.1016 0.4064) (xy -0.1016 0.4064)
					)
					(width 0)
					(fill yes)
				)
			)
		)
		(pad "9" smd custom
			(at 0.399999 1.4986)
			(size 0.0508 0.0508)
			(layers "F.Cu" "F.Mask" "F.Paste")
			(net "11N2191")
			(options
				(clearance outline)
				(anchor circle)
			)
			(primitives
				(gr_poly
					(pts
						(arc
							(start -0.1016 -0.3048)
							(mid 0 -0.4064)
							(end 0.1016 -0.3048)
						)
						(xy 0.1016 0.4064) (xy -0.1016 0.4064)
					)
					(width 0)
					(fill yes)
				)
			)
		)
		(pad "10" smd custom
			(at 0.799998 1.4986)
			(size 0.0508 0.0508)
			(layers "F.Cu" "F.Mask" "F.Paste")
			(net "GND")
			(options
				(clearance outline)
				(anchor circle)
			)
			(primitives
				(gr_poly
					(pts
						(arc
							(start -0.1016 -0.3048)
							(mid 0 -0.4064)
							(end 0.1016 -0.3048)
						)
						(xy 0.1016 0.4064) (xy -0.1016 0.4064)
					)
					(width 0)
					(fill yes)
				)
			)
		)
		(pad "11" smd custom
			(at 1.4986 0.799998 90)
			(size 0.0508 0.0508)
			(layers "F.Cu" "F.Mask" "F.Paste")
			(net "11N2177")
			(options
				(clearance outline)
				(anchor circle)
			)
			(primitives
				(gr_poly
					(pts
						(arc
							(start -0.1016 -0.3048)
							(mid 0 -0.4064)
							(end 0.1016 -0.3048)
						)
						(xy 0.1016 0.4064) (xy -0.1016 0.4064)
					)
					(width 0)
					(fill yes)
				)
			)
		)
		(pad "12" smd custom
			(at 1.4986 0.399999 90)
			(size 0.0508 0.0508)
			(layers "F.Cu" "F.Mask" "F.Paste")
			(net "11N2159")
			(options
				(clearance outline)
				(anchor circle)
			)
			(primitives
				(gr_poly
					(pts
						(arc
							(start -0.1016 -0.3048)
							(mid 0 -0.4064)
							(end 0.1016 -0.3048)
						)
						(xy 0.1016 0.4064) (xy -0.1016 0.4064)
					)
					(width 0)
					(fill yes)
				)
			)
		)
		(pad "13" smd custom
			(at 1.4986 0 90)
			(size 0.0508 0.0508)
			(layers "F.Cu" "F.Mask" "F.Paste")
			(net "11N2175")
			(options
				(clearance outline)
				(anchor circle)
			)
			(primitives
				(gr_poly
					(pts
						(arc
							(start -0.1016 -0.3048)
							(mid 0 -0.4064)
							(end 0.1016 -0.3048)
						)
						(xy 0.1016 0.4064) (xy -0.1016 0.4064)
					)
					(width 0)
					(fill yes)
				)
			)
		)
		(pad "14" smd custom
			(at 1.4986 -0.399999 90)
			(size 0.0508 0.0508)
			(layers "F.Cu" "F.Mask" "F.Paste")
			(net "11N2173")
			(options
				(clearance outline)
				(anchor circle)
			)
			(primitives
				(gr_poly
					(pts
						(arc
							(start -0.1016 -0.3048)
							(mid 0 -0.4064)
							(end 0.1016 -0.3048)
						)
						(xy 0.1016 0.4064) (xy -0.1016 0.4064)
					)
					(width 0)
					(fill yes)
				)
			)
		)
		(pad "15" smd custom
			(at 1.4986 -0.799998 90)
			(size 0.0508 0.0508)
			(layers "F.Cu" "F.Mask" "F.Paste")
			(net "11N2179")
			(options
				(clearance outline)
				(anchor circle)
			)
			(primitives
				(gr_poly
					(pts
						(arc
							(start -0.1016 -0.3048)
							(mid 0 -0.4064)
							(end 0.1016 -0.3048)
						)
						(xy 0.1016 0.4064) (xy -0.1016 0.4064)
					)
					(width 0)
					(fill yes)
				)
			)
		)
		(pad "16" smd custom
			(at 0.799998 -1.4986 180)
			(size 0.0508 0.0508)
			(layers "F.Cu" "F.Mask" "F.Paste")
			(net "VDDQ_VTT_EN")
			(options
				(clearance outline)
				(anchor circle)
			)
			(primitives
				(gr_poly
					(pts
						(arc
							(start -0.1016 -0.3048)
							(mid 0 -0.4064)
							(end 0.1016 -0.3048)
						)
						(xy 0.1016 0.4064) (xy -0.1016 0.4064)
					)
					(width 0)
					(fill yes)
				)
			)
		)
		(pad "17" smd custom
			(at 0.399999 -1.4986 180)
			(size 0.0508 0.0508)
			(layers "F.Cu" "F.Mask" "F.Paste")
			(net "VDDQ_VTT_EN")
			(options
				(clearance outline)
				(anchor circle)
			)
			(primitives
				(gr_poly
					(pts
						(arc
							(start -0.1016 -0.3048)
							(mid 0 -0.4064)
							(end 0.1016 -0.3048)
						)
						(xy 0.1016 0.4064) (xy -0.1016 0.4064)
					)
					(width 0)
					(fill yes)
				)
			)
		)
		(pad "18" smd custom
			(at 0 -1.4986 180)
			(size 0.0508 0.0508)
			(layers "F.Cu" "F.Mask" "F.Paste")
			(net "11N2140")
			(options
				(clearance outline)
				(anchor circle)
			)
			(primitives
				(gr_poly
					(pts
						(arc
							(start -0.1016 -0.3048)
							(mid 0 -0.4064)
							(end 0.1016 -0.3048)
						)
						(xy 0.1016 0.4064) (xy -0.1016 0.4064)
					)
					(width 0)
					(fill yes)
				)
			)
		)
		(pad "19" smd custom
			(at -0.399999 -1.4986 180)
			(size 0.0508 0.0508)
			(layers "F.Cu" "F.Mask" "F.Paste")
			(net "11N2138")
			(options
				(clearance outline)
				(anchor circle)
			)
			(primitives
				(gr_poly
					(pts
						(arc
							(start -0.1016 -0.3048)
							(mid 0 -0.4064)
							(end 0.1016 -0.3048)
						)
						(xy 0.1016 0.4064) (xy -0.1016 0.4064)
					)
					(width 0)
					(fill yes)
				)
			)
		)
		(pad "20" smd custom
			(at -0.799998 -1.4986 180)
			(size 0.0508 0.0508)
			(layers "F.Cu" "F.Mask" "F.Paste")
			(net "VDDQ_VTT_PGOOD")
			(options
				(clearance outline)
				(anchor circle)
			)
			(primitives
				(gr_poly
					(pts
						(arc
							(start -0.1016 -0.3048)
							(mid 0 -0.4064)
							(end 0.1016 -0.3048)
						)
						(xy 0.1016 0.4064) (xy -0.1016 0.4064)
					)
					(width 0)
					(fill yes)
				)
			)
		)
		(pad "21" smd rect
			(at 0 0)
			(size 1.5748 1.5748)
			(layers "F.Cu" "F.Mask" "F.Paste")
			(net "GND")
		)
	)
	(footprint ""
		(layer "F.Cu")
		(at 53.594 36.957 90)
		(property "Reference" "R167"
			(at 0.22733 1.27 0)
			(unlocked yes)
			(layer "F.SilkS")
			(effects
				(font
					(size 0.7874 0.5842)
					(thickness 0.127)
				)
				(justify left)
			)
		)
		(property "Value" "0"
			(at -0.148158 1.3462 180)
			(unlocked yes)
			(layer "F.Fab")
			(hide yes)
			(effects
				(font
					(size 1.27 0.9652)
					(thickness 0.000001)
				)
				(justify left)
			)
		)
		(property "Device Type" "REST1111"
			(at -0.148158 1.3462 180)
			(unlocked yes)
			(layer "F.Fab")
			(hide yes)
			(effects
				(font
					(size 1.27 0.9652)
					(thickness 0.000001)
				)
				(justify left)
			)
		)
		(duplicate_pad_numbers_are_jumpers no)
		(fp_poly
			(pts
				(xy 0.635 1.0668) (xy 0.635 -1.0668) (xy -0.635 -1.0668) (xy -0.635 1.0668)
			)
			(stroke
				(width 0)
				(type default)
			)
			(fill no)
			(layer "F.CrtYd")
		)
		(fp_line
			(start 0.254 -0.508)
			(end 0.254 0.508)
			(stroke
				(width 0.0254)
				(type default)
			)
			(layer "F.Fab")
		)
		(fp_line
			(start -0.254 -0.508)
			(end 0.254 -0.508)
			(stroke
				(width 0.0254)
				(type default)
			)
			(layer "F.Fab")
		)
		(fp_line
			(start 0.254 0.508)
			(end -0.254 0.508)
			(stroke
				(width 0.0254)
				(type default)
			)
			(layer "F.Fab")
		)
		(fp_line
			(start -0.254 0.508)
			(end -0.254 -0.508)
			(stroke
				(width 0.0254)
				(type default)
			)
			(layer "F.Fab")
		)
		(pad "1" smd rect
			(at 0 -0.4191 90)
			(size 0.508 0.5334)
			(layers "F.Cu" "F.Mask" "F.Paste")
			(net "VDD_CORE")
		)
		(pad "2" smd rect
			(at 0 0.4191 90)
			(size 0.508 0.5334)
			(layers "F.Cu" "F.Mask" "F.Paste")
			(net "NFP_VDD_CORE_ISEN2_N")
		)
		(zone
			(layer "F.Cu")
			(hatch none 0.5)
			(connect_pads
				(clearance 0)
			)
			(min_thickness 0.25)
			(keepout
				(tracks not_allowed)
				(vias allowed)
				(pads allowed)
				(copperpour not_allowed)
				(footprints allowed)
			)
			(placement
				(enabled no)
				(sheetname "")
			)
			(fill
				(thermal_gap 0.5)
				(thermal_bridge_width 0.5)
				(island_removal_mode 0)
			)
			(polygon
				(pts
					(xy 53.5686 36.9316) (xy 53.6194 36.9316) (xy 53.6194 36.9824) (xy 53.5686 36.9824)
				)
			)
		)
	)
	(footprint ""
		(layer "F.Cu")
		(at 61.2902 46.355 90)
		(property "Reference" "R2"
			(at -1.778 1.29667 90)
			(unlocked yes)
			(layer "F.SilkS")
			(effects
				(font
					(size 0.7874 0.5842)
					(thickness 0.127)
				)
				(justify left)
			)
		)
		(property "Value" "100K"
			(at -0.148158 1.7526 180)
			(unlocked yes)
			(layer "F.Fab")
			(hide yes)
			(effects
				(font
					(size 1.27 0.9652)
					(thickness 0.000001)
				)
				(justify left)
			)
		)
		(property "Device Type" "REST0288"
			(at -0.148158 1.7526 180)
			(unlocked yes)
			(layer "F.Fab")
			(hide yes)
			(effects
				(font
					(size 1.27 0.9652)
					(thickness 0.000001)
				)
				(justify left)
			)
		)
		(duplicate_pad_numbers_are_jumpers no)
		(fp_circle
			(center 0 0)
			(end 0 0.127)
			(stroke
				(width 0.2032)
				(type default)
			)
			(fill no)
			(layer "F.SilkS")
		)
		(fp_poly
			(pts
				(xy 0.7874 -1.6637) (xy -0.7874 -1.6637) (xy -0.7874 1.6637) (xy 0.7874 1.6637)
			)
			(stroke
				(width 0)
				(type default)
			)
			(fill no)
			(layer "F.CrtYd")
		)
		(fp_line
			(start 0.4064 -0.8128)
			(end 0.4064 0.8128)
			(stroke
				(width 0.0254)
				(type default)
			)
			(layer "F.Fab")
		)
		(fp_line
			(start -0.4064 -0.8128)
			(end 0.4064 -0.8128)
			(stroke
				(width 0.0254)
				(type default)
			)
			(layer "F.Fab")
		)
		(fp_line
			(start 0.4064 0.8128)
			(end -0.4064 0.8128)
			(stroke
				(width 0.0254)
				(type default)
			)
			(layer "F.Fab")
		)
		(fp_line
			(start -0.4064 0.8128)
			(end -0.4064 -0.8128)
			(stroke
				(width 0.0254)
				(type default)
			)
			(layer "F.Fab")
		)
		(pad "1" smd rect
			(at 0 -0.8001 90)
			(size 0.762 0.9652)
			(layers "F.Cu" "F.Mask" "F.Paste")
			(net "NFP_VDD_CORE_TCOMPB")
		)
		(pad "2" smd rect
			(at 0 0.8001 90)
			(size 0.762 0.9652)
			(layers "F.Cu" "F.Mask" "F.Paste")
			(net "NFP_VDD_CORE_TCOMPA")
		)
		(zone
			(layer "F.Cu")
			(hatch none 0.5)
			(connect_pads
				(clearance 0)
			)
			(min_thickness 0.25)
			(keepout
				(tracks not_allowed)
				(vias allowed)
				(pads allowed)
				(copperpour not_allowed)
				(footprints allowed)
			)
			(placement
				(enabled no)
				(sheetname "")
			)
			(fill
				(thermal_gap 0.5)
				(thermal_bridge_width 0.5)
				(island_removal_mode 0)
			)
			(polygon
				(pts
					(xy 61.0362 46.4185) (xy 61.0362 46.2915) (xy 61.5442 46.2915) (xy 61.5442 46.4185)
				)
			)
		)
	)
	(footprint ""
		(layer "F.Cu")
		(at 33.6042 42.545 90)
		(property "Reference" "C35"
			(at 0 0 90)
			(layer "F.SilkS")
			(hide yes)
			(effects
				(font
					(size 1.27 1.27)
				)
			)
		)
		(property "Value" "6800PF"
			(at -0.091846 0.2921 180)
			(unlocked yes)
			(layer "F.Fab")
			(hide yes)
			(effects
				(font
					(size 0.7874 0.5842)
					(thickness 0.2032)
				)
				(justify left)
			)
		)
		(property "Device Type" "CAPC0079"
			(at -0.091846 0.2921 180)
			(unlocked yes)
			(layer "F.Fab")
			(hide yes)
			(effects
				(font
					(size 0.7874 0.5842)
					(thickness 0.2032)
				)
				(justify left)
			)
		)
		(duplicate_pad_numbers_are_jumpers no)
		(fp_poly
			(pts
				(xy 0.635 1.0668) (xy 0.635 -1.0668) (xy -0.635 -1.0668) (xy -0.635 1.0668)
			)
			(stroke
				(width 0)
				(type default)
			)
			(fill no)
			(layer "F.CrtYd")
		)
		(fp_line
			(start 0.254 -0.508)
			(end 0.254 0.508)
			(stroke
				(width 0.0254)
				(type default)
			)
			(layer "F.Fab")
		)
		(fp_line
			(start -0.254 -0.508)
			(end 0.254 -0.508)
			(stroke
				(width 0.0254)
				(type default)
			)
			(layer "F.Fab")
		)
		(fp_line
			(start 0.254 0.508)
			(end -0.254 0.508)
			(stroke
				(width 0.0254)
				(type default)
			)
			(layer "F.Fab")
		)
		(fp_line
			(start -0.254 0.508)
			(end -0.254 -0.508)
			(stroke
				(width 0.0254)
				(type default)
			)
			(layer "F.Fab")
		)
		(pad "1" smd rect
			(at 0 -0.4191 90)
			(size 0.508 0.5334)
			(layers "F.Cu" "F.Mask" "F.Paste")
			(net "10N2528")
		)
		(pad "2" smd rect
			(at 0 0.4191 90)
			(size 0.508 0.5334)
			(layers "F.Cu" "F.Mask" "F.Paste")
			(net "NFP_VDD_CORE_TCOMPA")
		)
		(zone
			(layer "F.Cu")
			(hatch none 0.5)
			(connect_pads
				(clearance 0)
			)
			(min_thickness 0.25)
			(keepout
				(tracks not_allowed)
				(vias allowed)
				(pads allowed)
				(copperpour not_allowed)
				(footprints allowed)
			)
			(placement
				(enabled no)
				(sheetname "")
			)
			(fill
				(thermal_gap 0.5)
				(thermal_bridge_width 0.5)
				(island_removal_mode 0)
			)
			(polygon
				(pts
					(xy 33.5788 42.5196) (xy 33.6296 42.5196) (xy 33.6296 42.5704) (xy 33.5788 42.5704)
				)
			)
		)
	)
	(footprint ""
		(layer "F.Cu")
		(at 59.055 53.721)
		(property "Reference" "C181"
			(at -1.651 2.18567 0)
			(unlocked yes)
			(layer "F.SilkS")
			(effects
				(font
					(size 0.7874 0.5842)
					(thickness 0.127)
				)
				(justify left)
			)
		)
		(property "Value" ""
			(at 0 0 0)
			(layer "F.Fab")
			(effects
				(font
					(size 1.27 1.27)
				)
			)
		)
		(duplicate_pad_numbers_are_jumpers no)
		(fp_arc
			(start -0.381 -0.336017)
			(mid -0.20901 -0.463015)
			(end 0 -0.508)
			(stroke
				(width 0.2032)
				(type default)
			)
			(layer "F.SilkS")
		)
		(fp_arc
			(start 0 -0.508)
			(mid 0.209008 -0.463011)
			(end 0.381 -0.336017)
			(stroke
				(width 0.2032)
				(type default)
			)
			(layer "F.SilkS")
		)
		(fp_arc
			(start 0 0.508)
			(mid -0.209 0.463015)
			(end -0.381 0.336042)
			(stroke
				(width 0.2032)
				(type default)
			)
			(layer "F.SilkS")
		)
		(fp_arc
			(start 0.381 0.335991)
			(mid 0.209012 0.462996)
			(end 0 0.508)
			(stroke
				(width 0.2032)
				(type default)
			)
			(layer "F.SilkS")
		)
		(fp_circle
			(center 0 0)
			(end 0.508 0)
			(stroke
				(width 0.2032)
				(type default)
			)
			(fill no)
			(layer "F.SilkS")
		)
		(fp_poly
			(pts
				(xy -2.286 1.778) (xy -2.286 -1.778) (xy 2.286 -1.778) (xy 2.286 1.778)
			)
			(stroke
				(width 0)
				(type default)
			)
			(fill no)
			(layer "F.CrtYd")
		)
		(fp_line
			(start -1.524 -1.27)
			(end 1.524 -1.27)
			(stroke
				(width 0.0254)
				(type default)
			)
			(layer "F.Fab")
		)
		(fp_line
			(start -1.524 1.27)
			(end -1.524 -1.27)
			(stroke
				(width 0.0254)
				(type default)
			)
			(layer "F.Fab")
		)
		(fp_line
			(start 1.524 -1.27)
			(end 1.524 1.27)
			(stroke
				(width 0.0254)
				(type default)
			)
			(layer "F.Fab")
		)
		(fp_line
			(start 1.524 1.27)
			(end -1.524 1.27)
			(stroke
				(width 0.0254)
				(type default)
			)
			(layer "F.Fab")
		)
		(pad "1" smd rect
			(at -1.4224 0 90)
			(size 2.7432 1.3716)
			(layers "F.Cu" "F.Mask" "F.Paste")
			(net "VDD_5.0V")
		)
		(pad "2" smd rect
			(at 1.4224 0 90)
			(size 2.7432 1.3716)
			(layers "F.Cu" "F.Mask" "F.Paste")
			(net "GND")
		)
	)
	(footprint ""
		(layer "F.Cu")
		(at 43.307 51.816)
		(property "Reference" "C248"
			(at 0 0 0)
			(layer "F.SilkS")
			(hide yes)
			(effects
				(font
					(size 1.27 1.27)
				)
			)
		)
		(property "Value" "0.1UF"
			(at -0.091846 0.2921 90)
			(unlocked yes)
			(layer "F.Fab")
			(hide yes)
			(effects
				(font
					(size 0.7874 0.5842)
					(thickness 0.2032)
				)
				(justify left)
			)
		)
		(property "Device Type" "CAPC0073"
			(at -0.091846 0.2921 90)
			(unlocked yes)
			(layer "F.Fab")
			(hide yes)
			(effects
				(font
					(size 0.7874 0.5842)
					(thickness 0.2032)
				)
				(justify left)
			)
		)
		(duplicate_pad_numbers_are_jumpers no)
		(fp_poly
			(pts
				(xy 0.635 1.0668) (xy 0.635 -1.0668) (xy -0.635 -1.0668) (xy -0.635 1.0668)
			)
			(stroke
				(width 0)
				(type default)
			)
			(fill no)
			(layer "F.CrtYd")
		)
		(fp_line
			(start -0.254 -0.508)
			(end 0.254 -0.508)
			(stroke
				(width 0.0254)
				(type default)
			)
			(layer "F.Fab")
		)
		(fp_line
			(start -0.254 0.508)
			(end -0.254 -0.508)
			(stroke
				(width 0.0254)
				(type default)
			)
			(layer "F.Fab")
		)
		(fp_line
			(start 0.254 -0.508)
			(end 0.254 0.508)
			(stroke
				(width 0.0254)
				(type default)
			)
			(layer "F.Fab")
		)
		(fp_line
			(start 0.254 0.508)
			(end -0.254 0.508)
			(stroke
				(width 0.0254)
				(type default)
			)
			(layer "F.Fab")
		)
		(pad "1" smd rect
			(at 0 -0.4191)
			(size 0.508 0.5334)
			(layers "F.Cu" "F.Mask" "F.Paste")
			(net "EXT_12.0V_THRESHOLD")
		)
		(pad "2" smd rect
			(at 0 0.4191)
			(size 0.508 0.5334)
			(layers "F.Cu" "F.Mask" "F.Paste")
			(net "GND")
		)
		(zone
			(layer "F.Cu")
			(hatch none 0.5)
			(connect_pads
				(clearance 0)
			)
			(min_thickness 0.25)
			(keepout
				(tracks not_allowed)
				(vias allowed)
				(pads allowed)
				(copperpour not_allowed)
				(footprints allowed)
			)
			(placement
				(enabled no)
				(sheetname "")
			)
			(fill
				(thermal_gap 0.5)
				(thermal_bridge_width 0.5)
				(island_removal_mode 0)
			)
			(polygon
				(pts
					(xy 43.3324 51.7906) (xy 43.3324 51.8414) (xy 43.2816 51.8414) (xy 43.2816 51.7906)
				)
			)
		)
	)
	(footprint ""
		(layer "F.Cu")
		(at 6.9342 38.608)
		(property "Reference" "TP20"
			(at -1.24333 3.937 90)
			(unlocked yes)
			(layer "F.SilkS")
			(effects
				(font
					(size 0.7874 0.5842)
					(thickness 0.127)
				)
				(justify left)
			)
		)
		(property "Value" "*"
			(at -0.4826 -0.14732 0)
			(unlocked yes)
			(layer "F.Fab")
			(hide yes)
			(effects
				(font
					(size 1.27 0.9652)
					(thickness 0.000001)
				)
				(justify left)
			)
		)
		(property "Device Type" "TP_SMALL"
			(at -0.4826 -0.14732 0)
			(unlocked yes)
			(layer "F.Fab")
			(hide yes)
			(effects
				(font
					(size 1.27 0.9652)
					(thickness 0.000001)
				)
				(justify left)
			)
		)
		(duplicate_pad_numbers_are_jumpers no)
		(fp_line
			(start -0.8636 -0.8636)
			(end -0.8636 0.8636)
			(stroke
				(width 0.1524)
				(type default)
			)
			(layer "F.SilkS")
		)
		(fp_line
			(start -0.8636 0.8636)
			(end 0.8636 0.8636)
			(stroke
				(width 0.1524)
				(type default)
			)
			(layer "F.SilkS")
		)
		(fp_line
			(start 0.8636 -0.8636)
			(end -0.8636 -0.8636)
			(stroke
				(width 0.1524)
				(type default)
			)
			(layer "F.SilkS")
		)
		(fp_line
			(start 0.8636 0.8636)
			(end 0.8636 -0.8636)
			(stroke
				(width 0.1524)
				(type default)
			)
			(layer "F.SilkS")
		)
		(fp_poly
			(pts
				(xy -0.635 -0.635) (xy -0.635 0.635) (xy 0.635 0.635) (xy 0.635 -0.635)
			)
			(stroke
				(width 0)
				(type default)
			)
			(fill no)
			(layer "F.CrtYd")
		)
		(pad "1" smd rect
			(at 0 0)
			(size 1.27 1.27)
			(layers "F.Cu" "F.Mask" "F.Paste")
			(net "CPLD_GPIO_2")
		)
	)
	(footprint ""
		(layer "F.Cu")
		(at 41.91 49.3776 180)
		(property "Reference" "R122"
			(at 0 0 180)
			(layer "F.SilkS")
			(hide yes)
			(effects
				(font
					(size 1.27 1.27)
				)
			)
		)
		(property "Value" "100K"
			(at -0.148158 1.3462 270)
			(unlocked yes)
			(layer "F.Fab")
			(hide yes)
			(effects
				(font
					(size 1.27 0.9652)
					(thickness 0.000001)
				)
				(justify left)
			)
		)
		(property "Device Type" "REST0001"
			(at -0.148158 1.3462 270)
			(unlocked yes)
			(layer "F.Fab")
			(hide yes)
			(effects
				(font
					(size 1.27 0.9652)
					(thickness 0.000001)
				)
				(justify left)
			)
		)
		(duplicate_pad_numbers_are_jumpers no)
		(fp_poly
			(pts
				(xy 0.635 1.0668) (xy 0.635 -1.0668) (xy -0.635 -1.0668) (xy -0.635 1.0668)
			)
			(stroke
				(width 0)
				(type default)
			)
			(fill no)
			(layer "F.CrtYd")
		)
		(fp_line
			(start 0.254 0.508)
			(end -0.254 0.508)
			(stroke
				(width 0.0254)
				(type default)
			)
			(layer "F.Fab")
		)
		(fp_line
			(start 0.254 -0.508)
			(end 0.254 0.508)
			(stroke
				(width 0.0254)
				(type default)
			)
			(layer "F.Fab")
		)
		(fp_line
			(start -0.254 0.508)
			(end -0.254 -0.508)
			(stroke
				(width 0.0254)
				(type default)
			)
			(layer "F.Fab")
		)
		(fp_line
			(start -0.254 -0.508)
			(end 0.254 -0.508)
			(stroke
				(width 0.0254)
				(type default)
			)
			(layer "F.Fab")
		)
		(pad "1" smd rect
			(at 0 -0.4191 180)
			(size 0.508 0.5334)
			(layers "F.Cu" "F.Mask" "F.Paste")
			(net "EXT_12.0V_THRESHOLD")
		)
		(pad "2" smd rect
			(at 0 0.4191 180)
			(size 0.508 0.5334)
			(layers "F.Cu" "F.Mask" "F.Paste")
			(net "EXT_12.0V_PGOOD")
		)
		(zone
			(layer "F.Cu")
			(hatch none 0.5)
			(connect_pads
				(clearance 0)
			)
			(min_thickness 0.25)
			(keepout
				(tracks not_allowed)
				(vias allowed)
				(pads allowed)
				(copperpour not_allowed)
				(footprints allowed)
			)
			(placement
				(enabled no)
				(sheetname "")
			)
			(fill
				(thermal_gap 0.5)
				(thermal_bridge_width 0.5)
				(island_removal_mode 0)
			)
			(polygon
				(pts
					(xy 41.8846 49.403) (xy 41.8846 49.3522) (xy 41.9354 49.3522) (xy 41.9354 49.403)
				)
			)
		)
	)
	(footprint ""
		(layer "F.Cu")
		(at 27.559 43.561)
		(property "Reference" "R120"
			(at 0 0 0)
			(layer "F.SilkS")
			(hide yes)
			(effects
				(font
					(size 1.27 1.27)
				)
			)
		)
		(property "Value" "100K"
			(at -0.148158 1.3462 90)
			(unlocked yes)
			(layer "F.Fab")
			(hide yes)
			(effects
				(font
					(size 1.27 0.9652)
					(thickness 0.000001)
				)
				(justify left)
			)
		)
		(property "Device Type" "REST0001"
			(at -0.148158 1.3462 90)
			(unlocked yes)
			(layer "F.Fab")
			(hide yes)
			(effects
				(font
					(size 1.27 0.9652)
					(thickness 0.000001)
				)
				(justify left)
			)
		)
		(duplicate_pad_numbers_are_jumpers no)
		(fp_poly
			(pts
				(xy 0.635 1.0668) (xy 0.635 -1.0668) (xy -0.635 -1.0668) (xy -0.635 1.0668)
			)
			(stroke
				(width 0)
				(type default)
			)
			(fill no)
			(layer "F.CrtYd")
		)
		(fp_line
			(start -0.254 -0.508)
			(end 0.254 -0.508)
			(stroke
				(width 0.0254)
				(type default)
			)
			(layer "F.Fab")
		)
		(fp_line
			(start -0.254 0.508)
			(end -0.254 -0.508)
			(stroke
				(width 0.0254)
				(type default)
			)
			(layer "F.Fab")
		)
		(fp_line
			(start 0.254 -0.508)
			(end 0.254 0.508)
			(stroke
				(width 0.0254)
				(type default)
			)
			(layer "F.Fab")
		)
		(fp_line
			(start 0.254 0.508)
			(end -0.254 0.508)
			(stroke
				(width 0.0254)
				(type default)
			)
			(layer "F.Fab")
		)
		(pad "1" smd rect
			(at 0 -0.4191)
			(size 0.508 0.5334)
			(layers "F.Cu" "F.Mask" "F.Paste")
			(net "10N2383")
		)
		(pad "2" smd rect
			(at 0 0.4191)
			(size 0.508 0.5334)
			(layers "F.Cu" "F.Mask" "F.Paste")
			(net "10N2504")
		)
		(zone
			(layer "F.Cu")
			(hatch none 0.5)
			(connect_pads
				(clearance 0)
			)
			(min_thickness 0.25)
			(keepout
				(tracks not_allowed)
				(vias allowed)
				(pads allowed)
				(copperpour not_allowed)
				(footprints allowed)
			)
			(placement
				(enabled no)
				(sheetname "")
			)
			(fill
				(thermal_gap 0.5)
				(thermal_bridge_width 0.5)
				(island_removal_mode 0)
			)
			(polygon
				(pts
					(xy 27.5844 43.5356) (xy 27.5844 43.5864) (xy 27.5336 43.5864) (xy 27.5336 43.5356)
				)
			)
		)
	)
	(footprint ""
		(layer "F.Cu")
		(at 75.057 32.258 90)
		(property "Reference" "C219"
			(at -0.91567 -1.524 0)
			(unlocked yes)
			(layer "F.SilkS")
			(effects
				(font
					(size 0.7874 0.5842)
					(thickness 0.127)
				)
				(justify left)
			)
		)
		(property "Value" "1UF"
			(at -0.091846 0.2921 180)
			(unlocked yes)
			(layer "F.Fab")
			(hide yes)
			(effects
				(font
					(size 0.7874 0.5842)
					(thickness 0.2032)
				)
				(justify left)
			)
		)
		(property "Device Type" "CAPC0028"
			(at -0.091846 0.2921 180)
			(unlocked yes)
			(layer "F.Fab")
			(hide yes)
			(effects
				(font
					(size 0.7874 0.5842)
					(thickness 0.2032)
				)
				(justify left)
			)
		)
		(duplicate_pad_numbers_are_jumpers no)
		(fp_poly
			(pts
				(xy 0.635 1.0668) (xy 0.635 -1.0668) (xy -0.635 -1.0668) (xy -0.635 1.0668)
			)
			(stroke
				(width 0)
				(type default)
			)
			(fill no)
			(layer "F.CrtYd")
		)
		(fp_line
			(start 0.254 -0.508)
			(end 0.254 0.508)
			(stroke
				(width 0.0254)
				(type default)
			)
			(layer "F.Fab")
		)
		(fp_line
			(start -0.254 -0.508)
			(end 0.254 -0.508)
			(stroke
				(width 0.0254)
				(type default)
			)
			(layer "F.Fab")
		)
		(fp_line
			(start 0.254 0.508)
			(end -0.254 0.508)
			(stroke
				(width 0.0254)
				(type default)
			)
			(layer "F.Fab")
		)
		(fp_line
			(start -0.254 0.508)
			(end -0.254 -0.508)
			(stroke
				(width 0.0254)
				(type default)
			)
			(layer "F.Fab")
		)
		(pad "1" smd rect
			(at 0 -0.4191 90)
			(size 0.508 0.5334)
			(layers "F.Cu" "F.Mask" "F.Paste")
			(net "DDR_VDDQ")
		)
		(pad "2" smd rect
			(at 0 0.4191 90)
			(size 0.508 0.5334)
			(layers "F.Cu" "F.Mask" "F.Paste")
			(net "GND")
		)
		(zone
			(layer "F.Cu")
			(hatch none 0.5)
			(connect_pads
				(clearance 0)
			)
			(min_thickness 0.25)
			(keepout
				(tracks not_allowed)
				(vias allowed)
				(pads allowed)
				(copperpour not_allowed)
				(footprints allowed)
			)
			(placement
				(enabled no)
				(sheetname "")
			)
			(fill
				(thermal_gap 0.5)
				(thermal_bridge_width 0.5)
				(island_removal_mode 0)
			)
			(polygon
				(pts
					(xy 75.0316 32.2326) (xy 75.0824 32.2326) (xy 75.0824 32.2834) (xy 75.0316 32.2834)
				)
			)
		)
	)
	(footprint ""
		(layer "F.Cu")
		(at 26.67 41.275 90)
		(property "Reference" "R308"
			(at 0 0 90)
			(layer "F.SilkS")
			(hide yes)
			(effects
				(font
					(size 1.27 1.27)
				)
			)
		)
		(property "Value" "523K"
			(at -0.148158 1.3462 180)
			(unlocked yes)
			(layer "F.Fab")
			(hide yes)
			(effects
				(font
					(size 1.27 0.9652)
					(thickness 0.000001)
				)
				(justify left)
			)
		)
		(property "Device Type" "REST0291"
			(at -0.148158 1.3462 180)
			(unlocked yes)
			(layer "F.Fab")
			(hide yes)
			(effects
				(font
					(size 1.27 0.9652)
					(thickness 0.000001)
				)
				(justify left)
			)
		)
		(duplicate_pad_numbers_are_jumpers no)
		(fp_poly
			(pts
				(xy 0.635 1.0668) (xy 0.635 -1.0668) (xy -0.635 -1.0668) (xy -0.635 1.0668)
			)
			(stroke
				(width 0)
				(type default)
			)
			(fill no)
			(layer "F.CrtYd")
		)
		(fp_line
			(start 0.254 -0.508)
			(end 0.254 0.508)
			(stroke
				(width 0.0254)
				(type default)
			)
			(layer "F.Fab")
		)
		(fp_line
			(start -0.254 -0.508)
			(end 0.254 -0.508)
			(stroke
				(width 0.0254)
				(type default)
			)
			(layer "F.Fab")
		)
		(fp_line
			(start 0.254 0.508)
			(end -0.254 0.508)
			(stroke
				(width 0.0254)
				(type default)
			)
			(layer "F.Fab")
		)
		(fp_line
			(start -0.254 0.508)
			(end -0.254 -0.508)
			(stroke
				(width 0.0254)
				(type default)
			)
			(layer "F.Fab")
		)
		(pad "1" smd rect
			(at 0 -0.4191 90)
			(size 0.508 0.5334)
			(layers "F.Cu" "F.Mask" "F.Paste")
			(net "GND")
		)
		(pad "2" smd rect
			(at 0 0.4191 90)
			(size 0.508 0.5334)
			(layers "F.Cu" "F.Mask" "F.Paste")
			(net "10N2399")
		)
		(zone
			(layer "F.Cu")
			(hatch none 0.5)
			(connect_pads
				(clearance 0)
			)
			(min_thickness 0.25)
			(keepout
				(tracks not_allowed)
				(vias allowed)
				(pads allowed)
				(copperpour not_allowed)
				(footprints allowed)
			)
			(placement
				(enabled no)
				(sheetname "")
			)
			(fill
				(thermal_gap 0.5)
				(thermal_bridge_width 0.5)
				(island_removal_mode 0)
			)
			(polygon
				(pts
					(xy 26.6446 41.2496) (xy 26.6954 41.2496) (xy 26.6954 41.3004) (xy 26.6446 41.3004)
				)
			)
		)
	)
	(footprint ""
		(layer "F.Cu")
		(at 11.303 40.894 -90)
		(property "Reference" "C131"
			(at -0.98933 1.651 0)
			(unlocked yes)
			(layer "F.SilkS")
			(effects
				(font
					(size 0.7874 0.5842)
					(thickness 0.127)
				)
				(justify left)
			)
		)
		(property "Value" "10UF"
			(at -0.148158 1.7526 0)
			(unlocked yes)
			(layer "F.Fab")
			(hide yes)
			(effects
				(font
					(size 1.27 0.9652)
					(thickness 0.000001)
				)
				(justify left)
			)
		)
		(property "Device Type" "CAPC0058"
			(at -0.148158 1.7526 0)
			(unlocked yes)
			(layer "F.Fab")
			(hide yes)
			(effects
				(font
					(size 1.27 0.9652)
					(thickness 0.000001)
				)
				(justify left)
			)
		)
		(duplicate_pad_numbers_are_jumpers no)
		(fp_circle
			(center 0 0)
			(end 0 -0.127)
			(stroke
				(width 0.2032)
				(type default)
			)
			(fill no)
			(layer "F.SilkS")
		)
		(fp_poly
			(pts
				(xy 0.7874 -1.6637) (xy -0.7874 -1.6637) (xy -0.7874 1.6637) (xy 0.7874 1.6637)
			)
			(stroke
				(width 0)
				(type default)
			)
			(fill no)
			(layer "F.CrtYd")
		)
		(fp_line
			(start -0.4064 0.8128)
			(end -0.4064 -0.7874)
			(stroke
				(width 0.0254)
				(type default)
			)
			(layer "F.Fab")
		)
		(fp_line
			(start 0.4064 0.8128)
			(end -0.4064 0.8128)
			(stroke
				(width 0.0254)
				(type default)
			)
			(layer "F.Fab")
		)
		(fp_line
			(start -0.4064 -0.7874)
			(end 0.4064 -0.7874)
			(stroke
				(width 0.0254)
				(type default)
			)
			(layer "F.Fab")
		)
		(fp_line
			(start 0.4064 -0.7874)
			(end 0.4064 0.8128)
			(stroke
				(width 0.0254)
				(type default)
			)
			(layer "F.Fab")
		)
		(pad "1" smd rect
			(at 0 -0.8001 270)
			(size 0.8636 0.9652)
			(layers "F.Cu" "F.Mask" "F.Paste")
			(net "VDD_5.0V")
		)
		(pad "2" smd rect
			(at 0 0.8001 270)
			(size 0.8636 0.9652)
			(layers "F.Cu" "F.Mask" "F.Paste")
			(net "GND")
		)
	)
	(footprint ""
		(layer "F.Cu")
		(at 20.193 40.132)
		(property "Reference" "C21"
			(at 1.04267 1.143 90)
			(unlocked yes)
			(layer "F.SilkS")
			(effects
				(font
					(size 0.7874 0.5842)
					(thickness 0.127)
				)
				(justify left)
			)
		)
		(property "Value" "22UF"
			(at -0.148158 1.7526 90)
			(unlocked yes)
			(layer "F.Fab")
			(hide yes)
			(effects
				(font
					(size 1.27 0.9652)
					(thickness 0.000001)
				)
				(justify left)
			)
		)
		(property "Device Type" "CAPC0063"
			(at -0.148158 1.7526 90)
			(unlocked yes)
			(layer "F.Fab")
			(hide yes)
			(effects
				(font
					(size 1.27 0.9652)
					(thickness 0.000001)
				)
				(justify left)
			)
		)
		(duplicate_pad_numbers_are_jumpers no)
		(fp_circle
			(center 0 0)
			(end 0.127 0)
			(stroke
				(width 0.2032)
				(type default)
			)
			(fill no)
			(layer "F.SilkS")
		)
		(fp_poly
			(pts
				(xy 0.7874 -1.6637) (xy -0.7874 -1.6637) (xy -0.7874 1.6637) (xy 0.7874 1.6637)
			)
			(stroke
				(width 0)
				(type default)
			)
			(fill no)
			(layer "F.CrtYd")
		)
		(fp_line
			(start -0.4064 -0.7874)
			(end 0.4064 -0.7874)
			(stroke
				(width 0.0254)
				(type default)
			)
			(layer "F.Fab")
		)
		(fp_line
			(start -0.4064 0.8128)
			(end -0.4064 -0.7874)
			(stroke
				(width 0.0254)
				(type default)
			)
			(layer "F.Fab")
		)
		(fp_line
			(start 0.4064 -0.7874)
			(end 0.4064 0.8128)
			(stroke
				(width 0.0254)
				(type default)
			)
			(layer "F.Fab")
		)
		(fp_line
			(start 0.4064 0.8128)
			(end -0.4064 0.8128)
			(stroke
				(width 0.0254)
				(type default)
			)
			(layer "F.Fab")
		)
		(pad "1" smd rect
			(at 0 -0.8001)
			(size 0.8636 0.9652)
			(layers "F.Cu" "F.Mask" "F.Paste")
			(net "DDR_1.8V")
		)
		(pad "2" smd rect
			(at 0 0.8001)
			(size 0.8636 0.9652)
			(layers "F.Cu" "F.Mask" "F.Paste")
			(net "GND")
		)
		(zone
			(layer "F.Cu")
			(hatch none 0.5)
			(connect_pads
				(clearance 0)
			)
			(min_thickness 0.25)
			(keepout
				(tracks not_allowed)
				(vias allowed)
				(pads allowed)
				(copperpour not_allowed)
				(footprints allowed)
			)
			(placement
				(enabled no)
				(sheetname "")
			)
			(fill
				(thermal_gap 0.5)
				(thermal_bridge_width 0.5)
				(island_removal_mode 0)
			)
			(polygon
				(pts
					(xy 20.1295 39.878) (xy 20.2565 39.878) (xy 20.2565 40.386) (xy 20.1295 40.386)
				)
			)
		)
	)
	(footprint ""
		(layer "F.Cu")
		(at 9.017 41.3512 180)
		(property "Reference" "C22"
			(at -0.508 -0.53467 0)
			(unlocked yes)
			(layer "F.SilkS")
			(effects
				(font
					(size 0.7874 0.5842)
					(thickness 0.127)
				)
				(justify left)
			)
		)
		(property "Value" "22UF"
			(at -0.148158 1.7526 270)
			(unlocked yes)
			(layer "F.Fab")
			(hide yes)
			(effects
				(font
					(size 1.27 0.9652)
					(thickness 0.000001)
				)
				(justify left)
			)
		)
		(property "Device Type" "CAPC0063"
			(at -0.148158 1.7526 270)
			(unlocked yes)
			(layer "F.Fab")
			(hide yes)
			(effects
				(font
					(size 1.27 0.9652)
					(thickness 0.000001)
				)
				(justify left)
			)
		)
		(duplicate_pad_numbers_are_jumpers no)
		(fp_circle
			(center 0 0)
			(end -0.127 0)
			(stroke
				(width 0.2032)
				(type default)
			)
			(fill no)
			(layer "F.SilkS")
		)
		(fp_poly
			(pts
				(xy 0.658419 -1.6637) (xy -0.7874 -1.6637) (xy -0.7874 1.6637) (xy 0.658419 1.6637)
			)
			(stroke
				(width 0)
				(type default)
			)
			(fill no)
			(layer "F.CrtYd")
		)
		(fp_line
			(start 0.4064 0.8128)
			(end -0.4064 0.8128)
			(stroke
				(width 0.0254)
				(type default)
			)
			(layer "F.Fab")
		)
		(fp_line
			(start 0.4064 -0.7874)
			(end 0.4064 0.8128)
			(stroke
				(width 0.0254)
				(type default)
			)
			(layer "F.Fab")
		)
		(fp_line
			(start -0.4064 0.8128)
			(end -0.4064 -0.7874)
			(stroke
				(width 0.0254)
				(type default)
			)
			(layer "F.Fab")
		)
		(fp_line
			(start -0.4064 -0.7874)
			(end 0.4064 -0.7874)
			(stroke
				(width 0.0254)
				(type default)
			)
			(layer "F.Fab")
		)
		(pad "1" smd rect
			(at 0 -0.8001 180)
			(size 0.8636 0.9652)
			(layers "F.Cu" "F.Mask" "F.Paste")
			(net "VDD_1.5V")
		)
		(pad "2" smd rect
			(at 0 0.8001 180)
			(size 0.8636 0.9652)
			(layers "F.Cu" "F.Mask" "F.Paste")
			(net "GND")
		)
		(zone
			(layer "F.Cu")
			(hatch none 0.5)
			(connect_pads
				(clearance 0)
			)
			(min_thickness 0.25)
			(keepout
				(tracks not_allowed)
				(vias allowed)
				(pads allowed)
				(copperpour not_allowed)
				(footprints allowed)
			)
			(placement
				(enabled no)
				(sheetname "")
			)
			(fill
				(thermal_gap 0.5)
				(thermal_bridge_width 0.5)
				(island_removal_mode 0)
			)
			(polygon
				(pts
					(xy 9.0805 41.6052) (xy 8.9535 41.6052) (xy 8.9535 41.0972) (xy 9.0805 41.0972)
				)
			)
		)
	)
	(footprint ""
		(layer "F.Cu")
		(at 82.804 32.576414)
		(property "Reference" "R210"
			(at 0 0 0)
			(layer "F.SilkS")
			(hide yes)
			(effects
				(font
					(size 1.27 1.27)
				)
			)
		)
		(property "Value" "39.0"
			(at -0.148158 1.3462 90)
			(unlocked yes)
			(layer "F.Fab")
			(hide yes)
			(effects
				(font
					(size 1.27 0.9652)
					(thickness 0.000001)
				)
				(justify left)
			)
		)
		(property "Device Type" "REST0108"
			(at -0.148158 1.3462 90)
			(unlocked yes)
			(layer "F.Fab")
			(hide yes)
			(effects
				(font
					(size 1.27 0.9652)
					(thickness 0.000001)
				)
				(justify left)
			)
		)
		(duplicate_pad_numbers_are_jumpers no)
		(fp_poly
			(pts
				(xy 0.635 1.0668) (xy 0.635 -1.0668) (xy -0.635 -1.0668) (xy -0.635 1.0668)
			)
			(stroke
				(width 0)
				(type default)
			)
			(fill no)
			(layer "F.CrtYd")
		)
		(fp_line
			(start -0.254 -0.508)
			(end 0.254 -0.508)
			(stroke
				(width 0.0254)
				(type default)
			)
			(layer "F.Fab")
		)
		(fp_line
			(start -0.254 0.508)
			(end -0.254 -0.508)
			(stroke
				(width 0.0254)
				(type default)
			)
			(layer "F.Fab")
		)
		(fp_line
			(start 0.254 -0.508)
			(end 0.254 0.508)
			(stroke
				(width 0.0254)
				(type default)
			)
			(layer "F.Fab")
		)
		(fp_line
			(start 0.254 0.508)
			(end -0.254 0.508)
			(stroke
				(width 0.0254)
				(type default)
			)
			(layer "F.Fab")
		)
		(pad "1" smd rect
			(at 0 -0.4191)
			(size 0.508 0.5334)
			(layers "F.Cu" "F.Mask" "F.Paste")
			(net "DDR0_32A_A4")
		)
		(pad "2" smd rect
			(at 0 0.4191)
			(size 0.508 0.5334)
			(layers "F.Cu" "F.Mask" "F.Paste")
			(net "DDR_VTT")
		)
		(zone
			(layer "F.Cu")
			(hatch none 0.5)
			(connect_pads
				(clearance 0)
			)
			(min_thickness 0.25)
			(keepout
				(tracks not_allowed)
				(vias allowed)
				(pads allowed)
				(copperpour not_allowed)
				(footprints allowed)
			)
			(placement
				(enabled no)
				(sheetname "")
			)
			(fill
				(thermal_gap 0.5)
				(thermal_bridge_width 0.5)
				(island_removal_mode 0)
			)
			(polygon
				(pts
					(xy 82.8294 32.551014) (xy 82.8294 32.601814) (xy 82.7786 32.601814) (xy 82.7786 32.551014)
				)
			)
		)
	)
	(footprint ""
		(layer "F.Cu")
		(at 31.369 43.942)
		(property "Reference" "R182"
			(at 0 0 0)
			(layer "F.SilkS")
			(hide yes)
			(effects
				(font
					(size 1.27 1.27)
				)
			)
		)
		(property "Value" "0"
			(at -0.148158 1.3462 90)
			(unlocked yes)
			(layer "F.Fab")
			(hide yes)
			(effects
				(font
					(size 1.27 0.9652)
					(thickness 0.000001)
				)
				(justify left)
			)
		)
		(property "Device Type" "REST1111"
			(at -0.148158 1.3462 90)
			(unlocked yes)
			(layer "F.Fab")
			(hide yes)
			(effects
				(font
					(size 1.27 0.9652)
					(thickness 0.000001)
				)
				(justify left)
			)
		)
		(duplicate_pad_numbers_are_jumpers no)
		(fp_poly
			(pts
				(xy 0.635 1.0668) (xy 0.635 -1.0668) (xy -0.635 -1.0668) (xy -0.635 1.0668)
			)
			(stroke
				(width 0)
				(type default)
			)
			(fill no)
			(layer "F.CrtYd")
		)
		(fp_line
			(start -0.254 -0.508)
			(end 0.254 -0.508)
			(stroke
				(width 0.0254)
				(type default)
			)
			(layer "F.Fab")
		)
		(fp_line
			(start -0.254 0.508)
			(end -0.254 -0.508)
			(stroke
				(width 0.0254)
				(type default)
			)
			(layer "F.Fab")
		)
		(fp_line
			(start 0.254 -0.508)
			(end 0.254 0.508)
			(stroke
				(width 0.0254)
				(type default)
			)
			(layer "F.Fab")
		)
		(fp_line
			(start 0.254 0.508)
			(end -0.254 0.508)
			(stroke
				(width 0.0254)
				(type default)
			)
			(layer "F.Fab")
		)
		(pad "1" smd rect
			(at 0 -0.4191)
			(size 0.508 0.5334)
			(layers "F.Cu" "F.Mask" "F.Paste")
			(net "10N2385")
		)
		(pad "2" smd rect
			(at 0 0.4191)
			(size 0.508 0.5334)
			(layers "F.Cu" "F.Mask" "F.Paste")
			(net "NFP_VDD_CORE_SENSE_VDD")
		)
		(zone
			(layer "F.Cu")
			(hatch none 0.5)
			(connect_pads
				(clearance 0)
			)
			(min_thickness 0.25)
			(keepout
				(tracks not_allowed)
				(vias allowed)
				(pads allowed)
				(copperpour not_allowed)
				(footprints allowed)
			)
			(placement
				(enabled no)
				(sheetname "")
			)
			(fill
				(thermal_gap 0.5)
				(thermal_bridge_width 0.5)
				(island_removal_mode 0)
			)
			(polygon
				(pts
					(xy 31.3944 43.9166) (xy 31.3944 43.9674) (xy 31.3436 43.9674) (xy 31.3436 43.9166)
				)
			)
		)
	)
	(footprint ""
		(layer "F.Cu")
		(at 84.6836 40.64)
		(property "Reference" "R108"
			(at 0.4064 -0.73533 0)
			(unlocked yes)
			(layer "F.SilkS")
			(effects
				(font
					(size 0.7874 0.5842)
					(thickness 0.127)
				)
				(justify left)
			)
		)
		(property "Value" "2.2"
			(at -0.148158 1.3462 90)
			(unlocked yes)
			(layer "F.Fab")
			(hide yes)
			(effects
				(font
					(size 1.27 0.9652)
					(thickness 0.000001)
				)
				(justify left)
			)
		)
		(property "Device Type" "REST0114"
			(at -0.148158 1.3462 90)
			(unlocked yes)
			(layer "F.Fab")
			(hide yes)
			(effects
				(font
					(size 1.27 0.9652)
					(thickness 0.000001)
				)
				(justify left)
			)
		)
		(duplicate_pad_numbers_are_jumpers no)
		(fp_poly
			(pts
				(xy 0.635 1.0668) (xy 0.635 -1.0668) (xy -0.635 -1.0668) (xy -0.635 1.0668)
			)
			(stroke
				(width 0)
				(type default)
			)
			(fill no)
			(layer "F.CrtYd")
		)
		(fp_line
			(start -0.254 -0.508)
			(end 0.254 -0.508)
			(stroke
				(width 0.0254)
				(type default)
			)
			(layer "F.Fab")
		)
		(fp_line
			(start -0.254 0.508)
			(end -0.254 -0.508)
			(stroke
				(width 0.0254)
				(type default)
			)
			(layer "F.Fab")
		)
		(fp_line
			(start 0.254 -0.508)
			(end 0.254 0.508)
			(stroke
				(width 0.0254)
				(type default)
			)
			(layer "F.Fab")
		)
		(fp_line
			(start 0.254 0.508)
			(end -0.254 0.508)
			(stroke
				(width 0.0254)
				(type default)
			)
			(layer "F.Fab")
		)
		(pad "1" smd rect
			(at 0 -0.4191)
			(size 0.508 0.5334)
			(layers "F.Cu" "F.Mask" "F.Paste")
			(net "11N2179")
		)
		(pad "2" smd rect
			(at 0 0.4191)
			(size 0.508 0.5334)
			(layers "F.Cu" "F.Mask" "F.Paste")
			(net "11N2181")
		)
		(zone
			(layer "F.Cu")
			(hatch none 0.5)
			(connect_pads
				(clearance 0)
			)
			(min_thickness 0.25)
			(keepout
				(tracks not_allowed)
				(vias allowed)
				(pads allowed)
				(copperpour not_allowed)
				(footprints allowed)
			)
			(placement
				(enabled no)
				(sheetname "")
			)
			(fill
				(thermal_gap 0.5)
				(thermal_bridge_width 0.5)
				(island_removal_mode 0)
			)
			(polygon
				(pts
					(xy 84.709 40.6146) (xy 84.709 40.6654) (xy 84.6582 40.6654) (xy 84.6582 40.6146)
				)
			)
		)
	)
	(footprint ""
		(layer "F.Cu")
		(at 82.7278 22.987 180)
		(property "Reference" "R209"
			(at 0 0 180)
			(layer "F.SilkS")
			(hide yes)
			(effects
				(font
					(size 1.27 1.27)
				)
			)
		)
		(property "Value" "39.0"
			(at -0.148158 1.3462 270)
			(unlocked yes)
			(layer "F.Fab")
			(hide yes)
			(effects
				(font
					(size 1.27 0.9652)
					(thickness 0.000001)
				)
				(justify left)
			)
		)
		(property "Device Type" "REST0108"
			(at -0.148158 1.3462 270)
			(unlocked yes)
			(layer "F.Fab")
			(hide yes)
			(effects
				(font
					(size 1.27 0.9652)
					(thickness 0.000001)
				)
				(justify left)
			)
		)
		(duplicate_pad_numbers_are_jumpers no)
		(fp_poly
			(pts
				(xy 0.635 1.0668) (xy 0.635 -1.0668) (xy -0.635 -1.0668) (xy -0.635 1.0668)
			)
			(stroke
				(width 0)
				(type default)
			)
			(fill no)
			(layer "F.CrtYd")
		)
		(fp_line
			(start 0.254 0.508)
			(end -0.254 0.508)
			(stroke
				(width 0.0254)
				(type default)
			)
			(layer "F.Fab")
		)
		(fp_line
			(start 0.254 -0.508)
			(end 0.254 0.508)
			(stroke
				(width 0.0254)
				(type default)
			)
			(layer "F.Fab")
		)
		(fp_line
			(start -0.254 0.508)
			(end -0.254 -0.508)
			(stroke
				(width 0.0254)
				(type default)
			)
			(layer "F.Fab")
		)
		(fp_line
			(start -0.254 -0.508)
			(end 0.254 -0.508)
			(stroke
				(width 0.0254)
				(type default)
			)
			(layer "F.Fab")
		)
		(pad "1" smd rect
			(at 0 -0.4191 180)
			(size 0.508 0.5334)
			(layers "F.Cu" "F.Mask" "F.Paste")
			(net "DDR0_32A_A3")
		)
		(pad "2" smd rect
			(at 0 0.4191 180)
			(size 0.508 0.5334)
			(layers "F.Cu" "F.Mask" "F.Paste")
			(net "DDR_VTT")
		)
		(zone
			(layer "F.Cu")
			(hatch none 0.5)
			(connect_pads
				(clearance 0)
			)
			(min_thickness 0.25)
			(keepout
				(tracks not_allowed)
				(vias allowed)
				(pads allowed)
				(copperpour not_allowed)
				(footprints allowed)
			)
			(placement
				(enabled no)
				(sheetname "")
			)
			(fill
				(thermal_gap 0.5)
				(thermal_bridge_width 0.5)
				(island_removal_mode 0)
			)
			(polygon
				(pts
					(xy 82.7024 23.0124) (xy 82.7024 22.9616) (xy 82.7532 22.9616) (xy 82.7532 23.0124)
				)
			)
		)
	)
	(footprint ""
		(layer "F.Cu")
		(at 82.804 28.702 180)
		(property "Reference" "R207"
			(at 0 0 180)
			(layer "F.SilkS")
			(hide yes)
			(effects
				(font
					(size 1.27 1.27)
				)
			)
		)
		(property "Value" "39.0"
			(at -0.148158 1.3462 270)
			(unlocked yes)
			(layer "F.Fab")
			(hide yes)
			(effects
				(font
					(size 1.27 0.9652)
					(thickness 0.000001)
				)
				(justify left)
			)
		)
		(property "Device Type" "REST0108"
			(at -0.148158 1.3462 270)
			(unlocked yes)
			(layer "F.Fab")
			(hide yes)
			(effects
				(font
					(size 1.27 0.9652)
					(thickness 0.000001)
				)
				(justify left)
			)
		)
		(duplicate_pad_numbers_are_jumpers no)
		(fp_poly
			(pts
				(xy 0.635 1.0668) (xy 0.635 -1.0668) (xy -0.635 -1.0668) (xy -0.635 1.0668)
			)
			(stroke
				(width 0)
				(type default)
			)
			(fill no)
			(layer "F.CrtYd")
		)
		(fp_line
			(start 0.254 0.508)
			(end -0.254 0.508)
			(stroke
				(width 0.0254)
				(type default)
			)
			(layer "F.Fab")
		)
		(fp_line
			(start 0.254 -0.508)
			(end 0.254 0.508)
			(stroke
				(width 0.0254)
				(type default)
			)
			(layer "F.Fab")
		)
		(fp_line
			(start -0.254 0.508)
			(end -0.254 -0.508)
			(stroke
				(width 0.0254)
				(type default)
			)
			(layer "F.Fab")
		)
		(fp_line
			(start -0.254 -0.508)
			(end 0.254 -0.508)
			(stroke
				(width 0.0254)
				(type default)
			)
			(layer "F.Fab")
		)
		(pad "1" smd rect
			(at 0 -0.4191 180)
			(size 0.508 0.5334)
			(layers "F.Cu" "F.Mask" "F.Paste")
			(net "DDR0_32A_A1")
		)
		(pad "2" smd rect
			(at 0 0.4191 180)
			(size 0.508 0.5334)
			(layers "F.Cu" "F.Mask" "F.Paste")
			(net "DDR_VTT")
		)
		(zone
			(layer "F.Cu")
			(hatch none 0.5)
			(connect_pads
				(clearance 0)
			)
			(min_thickness 0.25)
			(keepout
				(tracks not_allowed)
				(vias allowed)
				(pads allowed)
				(copperpour not_allowed)
				(footprints allowed)
			)
			(placement
				(enabled no)
				(sheetname "")
			)
			(fill
				(thermal_gap 0.5)
				(thermal_bridge_width 0.5)
				(island_removal_mode 0)
			)
			(polygon
				(pts
					(xy 82.7786 28.7274) (xy 82.7786 28.6766) (xy 82.8294 28.6766) (xy 82.8294 28.7274)
				)
			)
		)
	)
	(footprint ""
		(layer "F.Cu")
		(at 25.9588 35.052 -90)
		(property "Reference" "R87"
			(at 0 0 270)
			(layer "F.SilkS")
			(hide yes)
			(effects
				(font
					(size 1.27 1.27)
				)
			)
		)
		(property "Value" "4.75K"
			(at -0.148158 1.3462 0)
			(unlocked yes)
			(layer "F.Fab")
			(hide yes)
			(effects
				(font
					(size 1.27 0.9652)
					(thickness 0.000001)
				)
				(justify left)
			)
		)
		(property "Device Type" "REST4024"
			(at -0.148158 1.3462 0)
			(unlocked yes)
			(layer "F.Fab")
			(hide yes)
			(effects
				(font
					(size 1.27 0.9652)
					(thickness 0.000001)
				)
				(justify left)
			)
		)
		(duplicate_pad_numbers_are_jumpers no)
		(fp_poly
			(pts
				(xy 0.635 1.0668) (xy 0.635 -1.0668) (xy -0.635 -1.0668) (xy -0.635 1.0668)
			)
			(stroke
				(width 0)
				(type default)
			)
			(fill no)
			(layer "F.CrtYd")
		)
		(fp_line
			(start -0.254 0.508)
			(end -0.254 -0.508)
			(stroke
				(width 0.0254)
				(type default)
			)
			(layer "F.Fab")
		)
		(fp_line
			(start 0.254 0.508)
			(end -0.254 0.508)
			(stroke
				(width 0.0254)
				(type default)
			)
			(layer "F.Fab")
		)
		(fp_line
			(start -0.254 -0.508)
			(end 0.254 -0.508)
			(stroke
				(width 0.0254)
				(type default)
			)
			(layer "F.Fab")
		)
		(fp_line
			(start 0.254 -0.508)
			(end 0.254 0.508)
			(stroke
				(width 0.0254)
				(type default)
			)
			(layer "F.Fab")
		)
		(pad "1" smd rect
			(at 0 -0.4191 270)
			(size 0.508 0.5334)
			(layers "F.Cu" "F.Mask" "F.Paste")
			(net "VDD_CORE_PGOOD")
		)
		(pad "2" smd rect
			(at 0 0.4191 270)
			(size 0.508 0.5334)
			(layers "F.Cu" "F.Mask" "F.Paste")
			(net "EXT_3.3V")
		)
		(zone
			(layer "F.Cu")
			(hatch none 0.5)
			(connect_pads
				(clearance 0)
			)
			(min_thickness 0.25)
			(keepout
				(tracks not_allowed)
				(vias allowed)
				(pads allowed)
				(copperpour not_allowed)
				(footprints allowed)
			)
			(placement
				(enabled no)
				(sheetname "")
			)
			(fill
				(thermal_gap 0.5)
				(thermal_bridge_width 0.5)
				(island_removal_mode 0)
			)
			(polygon
				(pts
					(xy 25.9842 35.0774) (xy 25.9334 35.0774) (xy 25.9334 35.0266) (xy 25.9842 35.0266)
				)
			)
		)
	)
	(footprint ""
		(layer "F.Cu")
		(at 44.196 54.737)
		(property "Reference" "D5"
			(at -1.143 1.93167 0)
			(unlocked yes)
			(layer "F.SilkS")
			(effects
				(font
					(size 0.7874 0.5842)
					(thickness 0.127)
				)
				(justify left)
			)
		)
		(property "Value" "LL4148"
			(at 0.1524 -0.148158 0)
			(unlocked yes)
			(layer "F.Fab")
			(hide yes)
			(effects
				(font
					(size 1.27 0.9652)
					(thickness 0.000001)
				)
				(justify left)
			)
		)
		(property "Device Type" "DIOD0001V"
			(at 0.1524 -0.148158 0)
			(unlocked yes)
			(layer "F.Fab")
			(hide yes)
			(effects
				(font
					(size 1.27 0.9652)
					(thickness 0.000001)
				)
				(justify left)
			)
		)
		(duplicate_pad_numbers_are_jumpers no)
		(fp_line
			(start -2.667 -1.143)
			(end -2.667 1.143)
			(stroke
				(width 0.1524)
				(type default)
			)
			(layer "F.SilkS")
		)
		(fp_line
			(start -2.667 -1.143)
			(end -2.667 1.143)
			(stroke
				(width 0.1524)
				(type default)
			)
			(layer "F.SilkS")
		)
		(fp_line
			(start -2.667 1.143)
			(end -2.286 1.143)
			(stroke
				(width 0.1524)
				(type default)
			)
			(layer "F.SilkS")
		)
		(fp_line
			(start -2.54 -1.143)
			(end -2.54 1.143)
			(stroke
				(width 0.1524)
				(type default)
			)
			(layer "F.SilkS")
		)
		(fp_line
			(start -2.54 -1.143)
			(end -2.54 1.143)
			(stroke
				(width 0.1524)
				(type default)
			)
			(layer "F.SilkS")
		)
		(fp_line
			(start -2.413 -1.143)
			(end 1.778 -1.143)
			(stroke
				(width 0.1524)
				(type default)
			)
			(layer "F.SilkS")
		)
		(fp_line
			(start -2.413 1.143)
			(end -2.413 -1.143)
			(stroke
				(width 0.1524)
				(type default)
			)
			(layer "F.SilkS")
		)
		(fp_line
			(start -2.286 -1.143)
			(end -2.667 -1.143)
			(stroke
				(width 0.1524)
				(type default)
			)
			(layer "F.SilkS")
		)
		(fp_line
			(start 0.8128 1.143)
			(end -0.8128 1.143)
			(stroke
				(width 0.1524)
				(type default)
			)
			(layer "F.SilkS")
		)
		(fp_line
			(start 1.905 1.143)
			(end -2.413 1.143)
			(stroke
				(width 0.1524)
				(type default)
			)
			(layer "F.SilkS")
		)
		(fp_poly
			(pts
				(xy -2.794 -1.397) (xy 2.667 -1.397) (xy 2.667 0.762) (xy -2.794 0.762)
			)
			(stroke
				(width 0)
				(type default)
			)
			(fill no)
			(layer "F.CrtYd")
		)
		(fp_line
			(start -1.8542 -0.8001)
			(end -1.8542 0.8001)
			(stroke
				(width 0.1524)
				(type default)
			)
			(layer "F.Fab")
		)
		(fp_line
			(start -1.8542 0.8001)
			(end 1.8542 0.8001)
			(stroke
				(width 0.1524)
				(type default)
			)
			(layer "F.Fab")
		)
		(fp_line
			(start -1.397 -0.762)
			(end -1.143 -0.762)
			(stroke
				(width 0.1524)
				(type default)
			)
			(layer "F.Fab")
		)
		(fp_line
			(start -1.397 0.762)
			(end -1.397 -0.762)
			(stroke
				(width 0.1524)
				(type default)
			)
			(layer "F.Fab")
		)
		(fp_line
			(start -1.143 -0.762)
			(end -1.143 0.762)
			(stroke
				(width 0.1524)
				(type default)
			)
			(layer "F.Fab")
		)
		(fp_line
			(start 1.8542 -0.8001)
			(end -1.8542 -0.8001)
			(stroke
				(width 0.1524)
				(type default)
			)
			(layer "F.Fab")
		)
		(fp_line
			(start 1.8542 0.8001)
			(end 1.8542 -0.8001)
			(stroke
				(width 0.1524)
				(type default)
			)
			(layer "F.Fab")
		)
		(fp_poly
			(pts
				(xy -1.8542 -0.7874) (xy -1.8542 0.8128) (xy -1.143 0.8128) (xy -1.143 -0.7874)
			)
			(stroke
				(width 0)
				(type default)
			)
			(fill yes)
			(layer "F.Fab")
		)
		(fp_text user "C"
			(at -3.7846 0.196012 0)
			(unlocked yes)
			(layer "F.SilkS")
			(effects
				(font
					(size 0.7874 0.5842)
					(thickness 0.127)
				)
				(justify left)
			)
		)
		(fp_text user "A"
			(at 2.3114 0.196012 0)
			(unlocked yes)
			(layer "F.SilkS")
			(effects
				(font
					(size 0.7874 0.5842)
					(thickness 0.127)
				)
				(justify left)
			)
		)
		(fp_text user "C"
			(at -1.905 1.55067 0)
			(unlocked yes)
			(layer "F.Fab")
			(effects
				(font
					(size 0.7874 0.5842)
					(thickness 0.127)
				)
				(justify left)
			)
		)
		(fp_text user "A"
			(at 1.143 1.42367 0)
			(unlocked yes)
			(layer "F.Fab")
			(effects
				(font
					(size 0.7874 0.5842)
					(thickness 0.127)
				)
				(justify left)
			)
		)
		(pad "1" smd rect
			(at 1.651 0)
			(size 1.016 1.7018)
			(layers "F.Cu" "F.Mask" "F.Paste")
			(net "0.7V_REF")
		)
		(pad "2" smd rect
			(at -1.651 0)
			(size 1.016 1.7018)
			(layers "F.Cu" "F.Mask" "F.Paste")
			(net "GND")
		)
	)
	(footprint ""
		(layer "F.Cu")
		(at 77.978 7.874 180)
		(property "Reference" "C213"
			(at -0.762 0.35433 0)
			(unlocked yes)
			(layer "F.SilkS")
			(effects
				(font
					(size 0.7874 0.5842)
					(thickness 0.127)
				)
				(justify left)
			)
		)
		(property "Value" "1UF"
			(at -0.091846 0.2921 270)
			(unlocked yes)
			(layer "F.Fab")
			(hide yes)
			(effects
				(font
					(size 0.7874 0.5842)
					(thickness 0.2032)
				)
				(justify left)
			)
		)
		(property "Device Type" "CAPC0028"
			(at -0.091846 0.2921 270)
			(unlocked yes)
			(layer "F.Fab")
			(hide yes)
			(effects
				(font
					(size 0.7874 0.5842)
					(thickness 0.2032)
				)
				(justify left)
			)
		)
		(duplicate_pad_numbers_are_jumpers no)
		(fp_poly
			(pts
				(xy 0.635 1.0668) (xy 0.635 -1.0668) (xy -0.635 -1.0668) (xy -0.635 1.0668)
			)
			(stroke
				(width 0)
				(type default)
			)
			(fill no)
			(layer "F.CrtYd")
		)
		(fp_line
			(start 0.254 0.508)
			(end -0.254 0.508)
			(stroke
				(width 0.0254)
				(type default)
			)
			(layer "F.Fab")
		)
		(fp_line
			(start 0.254 -0.508)
			(end 0.254 0.508)
			(stroke
				(width 0.0254)
				(type default)
			)
			(layer "F.Fab")
		)
		(fp_line
			(start -0.254 0.508)
			(end -0.254 -0.508)
			(stroke
				(width 0.0254)
				(type default)
			)
			(layer "F.Fab")
		)
		(fp_line
			(start -0.254 -0.508)
			(end 0.254 -0.508)
			(stroke
				(width 0.0254)
				(type default)
			)
			(layer "F.Fab")
		)
		(pad "1" smd rect
			(at 0 -0.4191 180)
			(size 0.508 0.5334)
			(layers "F.Cu" "F.Mask" "F.Paste")
			(net "DDR_VDDQ")
		)
		(pad "2" smd rect
			(at 0 0.4191 180)
			(size 0.508 0.5334)
			(layers "F.Cu" "F.Mask" "F.Paste")
			(net "GND")
		)
		(zone
			(layer "F.Cu")
			(hatch none 0.5)
			(connect_pads
				(clearance 0)
			)
			(min_thickness 0.25)
			(keepout
				(tracks not_allowed)
				(vias allowed)
				(pads allowed)
				(copperpour not_allowed)
				(footprints allowed)
			)
			(placement
				(enabled no)
				(sheetname "")
			)
			(fill
				(thermal_gap 0.5)
				(thermal_bridge_width 0.5)
				(island_removal_mode 0)
			)
			(polygon
				(pts
					(xy 77.9526 7.8994) (xy 77.9526 7.8486) (xy 78.0034 7.8486) (xy 78.0034 7.8994)
				)
			)
		)
	)
	(footprint ""
		(layer "F.Cu")
		(at 73.406 23.495 90)
		(property "Reference" "C217"
			(at -0.78867 -0.254 0)
			(unlocked yes)
			(layer "F.SilkS")
			(effects
				(font
					(size 0.7874 0.5842)
					(thickness 0.127)
				)
				(justify left)
			)
		)
		(property "Value" "1UF"
			(at -0.091846 0.2921 180)
			(unlocked yes)
			(layer "F.Fab")
			(hide yes)
			(effects
				(font
					(size 0.7874 0.5842)
					(thickness 0.2032)
				)
				(justify left)
			)
		)
		(property "Device Type" "CAPC0028"
			(at -0.091846 0.2921 180)
			(unlocked yes)
			(layer "F.Fab")
			(hide yes)
			(effects
				(font
					(size 0.7874 0.5842)
					(thickness 0.2032)
				)
				(justify left)
			)
		)
		(duplicate_pad_numbers_are_jumpers no)
		(fp_poly
			(pts
				(xy 0.635 1.0668) (xy 0.635 -1.0668) (xy -0.635 -1.0668) (xy -0.635 1.0668)
			)
			(stroke
				(width 0)
				(type default)
			)
			(fill no)
			(layer "F.CrtYd")
		)
		(fp_line
			(start 0.254 -0.508)
			(end 0.254 0.508)
			(stroke
				(width 0.0254)
				(type default)
			)
			(layer "F.Fab")
		)
		(fp_line
			(start -0.254 -0.508)
			(end 0.254 -0.508)
			(stroke
				(width 0.0254)
				(type default)
			)
			(layer "F.Fab")
		)
		(fp_line
			(start 0.254 0.508)
			(end -0.254 0.508)
			(stroke
				(width 0.0254)
				(type default)
			)
			(layer "F.Fab")
		)
		(fp_line
			(start -0.254 0.508)
			(end -0.254 -0.508)
			(stroke
				(width 0.0254)
				(type default)
			)
			(layer "F.Fab")
		)
		(pad "1" smd rect
			(at 0 -0.4191 90)
			(size 0.508 0.5334)
			(layers "F.Cu" "F.Mask" "F.Paste")
			(net "DDR_VDDQ")
		)
		(pad "2" smd rect
			(at 0 0.4191 90)
			(size 0.508 0.5334)
			(layers "F.Cu" "F.Mask" "F.Paste")
			(net "GND")
		)
		(zone
			(layer "F.Cu")
			(hatch none 0.5)
			(connect_pads
				(clearance 0)
			)
			(min_thickness 0.25)
			(keepout
				(tracks not_allowed)
				(vias allowed)
				(pads allowed)
				(copperpour not_allowed)
				(footprints allowed)
			)
			(placement
				(enabled no)
				(sheetname "")
			)
			(fill
				(thermal_gap 0.5)
				(thermal_bridge_width 0.5)
				(island_removal_mode 0)
			)
			(polygon
				(pts
					(xy 73.3806 23.4696) (xy 73.4314 23.4696) (xy 73.4314 23.5204) (xy 73.3806 23.5204)
				)
			)
		)
	)
	(footprint ""
		(layer "F.Cu")
		(at 77.851 24.765)
		(property "Reference" "C264"
			(at 0 0 0)
			(layer "F.SilkS")
			(hide yes)
			(effects
				(font
					(size 1.27 1.27)
				)
			)
		)
		(property "Value" "1UF"
			(at -0.091846 0.2921 90)
			(unlocked yes)
			(layer "F.Fab")
			(hide yes)
			(effects
				(font
					(size 0.7874 0.5842)
					(thickness 0.2032)
				)
				(justify left)
			)
		)
		(property "Device Type" "CAPC0028"
			(at -0.091846 0.2921 90)
			(unlocked yes)
			(layer "F.Fab")
			(hide yes)
			(effects
				(font
					(size 0.7874 0.5842)
					(thickness 0.2032)
				)
				(justify left)
			)
		)
		(duplicate_pad_numbers_are_jumpers no)
		(fp_poly
			(pts
				(xy 0.635 1.0668) (xy 0.635 -1.0668) (xy -0.635 -1.0668) (xy -0.635 1.0668)
			)
			(stroke
				(width 0)
				(type default)
			)
			(fill no)
			(layer "F.CrtYd")
		)
		(fp_line
			(start -0.254 -0.508)
			(end 0.254 -0.508)
			(stroke
				(width 0.0254)
				(type default)
			)
			(layer "F.Fab")
		)
		(fp_line
			(start -0.254 0.508)
			(end -0.254 -0.508)
			(stroke
				(width 0.0254)
				(type default)
			)
			(layer "F.Fab")
		)
		(fp_line
			(start 0.254 -0.508)
			(end 0.254 0.508)
			(stroke
				(width 0.0254)
				(type default)
			)
			(layer "F.Fab")
		)
		(fp_line
			(start 0.254 0.508)
			(end -0.254 0.508)
			(stroke
				(width 0.0254)
				(type default)
			)
			(layer "F.Fab")
		)
		(pad "1" smd rect
			(at 0 -0.4191)
			(size 0.508 0.5334)
			(layers "F.Cu" "F.Mask" "F.Paste")
			(net "DDR0_32A_VREF1B")
		)
		(pad "2" smd rect
			(at 0 0.4191)
			(size 0.508 0.5334)
			(layers "F.Cu" "F.Mask" "F.Paste")
			(net "GND")
		)
		(zone
			(layer "F.Cu")
			(hatch none 0.5)
			(connect_pads
				(clearance 0)
			)
			(min_thickness 0.25)
			(keepout
				(tracks not_allowed)
				(vias allowed)
				(pads allowed)
				(copperpour not_allowed)
				(footprints allowed)
			)
			(placement
				(enabled no)
				(sheetname "")
			)
			(fill
				(thermal_gap 0.5)
				(thermal_bridge_width 0.5)
				(island_removal_mode 0)
			)
			(polygon
				(pts
					(xy 77.8764 24.7396) (xy 77.8764 24.7904) (xy 77.8256 24.7904) (xy 77.8256 24.7396)
				)
			)
		)
	)
	(footprint ""
		(layer "F.Cu")
		(at 64.516 52.07 90)
		(property "Reference" "C126"
			(at 0 0 90)
			(layer "F.SilkS")
			(hide yes)
			(effects
				(font
					(size 1.27 1.27)
				)
			)
		)
		(property "Value" "0.1UF"
			(at -0.091846 0.2921 180)
			(unlocked yes)
			(layer "F.Fab")
			(hide yes)
			(effects
				(font
					(size 0.7874 0.5842)
					(thickness 0.2032)
				)
				(justify left)
			)
		)
		(property "Device Type" "CAPC0073"
			(at -0.091846 0.2921 180)
			(unlocked yes)
			(layer "F.Fab")
			(hide yes)
			(effects
				(font
					(size 0.7874 0.5842)
					(thickness 0.2032)
				)
				(justify left)
			)
		)
		(duplicate_pad_numbers_are_jumpers no)
		(fp_poly
			(pts
				(xy 0.635 1.0668) (xy 0.635 -1.0668) (xy -0.635 -1.0668) (xy -0.635 1.0668)
			)
			(stroke
				(width 0)
				(type default)
			)
			(fill no)
			(layer "F.CrtYd")
		)
		(fp_line
			(start 0.254 -0.508)
			(end 0.254 0.508)
			(stroke
				(width 0.0254)
				(type default)
			)
			(layer "F.Fab")
		)
		(fp_line
			(start -0.254 -0.508)
			(end 0.254 -0.508)
			(stroke
				(width 0.0254)
				(type default)
			)
			(layer "F.Fab")
		)
		(fp_line
			(start 0.254 0.508)
			(end -0.254 0.508)
			(stroke
				(width 0.0254)
				(type default)
			)
			(layer "F.Fab")
		)
		(fp_line
			(start -0.254 0.508)
			(end -0.254 -0.508)
			(stroke
				(width 0.0254)
				(type default)
			)
			(layer "F.Fab")
		)
		(pad "1" smd rect
			(at 0 -0.4191 90)
			(size 0.508 0.5334)
			(layers "F.Cu" "F.Mask" "F.Paste")
			(net "EXT_12.0V")
		)
		(pad "2" smd rect
			(at 0 0.4191 90)
			(size 0.508 0.5334)
			(layers "F.Cu" "F.Mask" "F.Paste")
			(net "GND")
		)
		(zone
			(layer "F.Cu")
			(hatch none 0.5)
			(connect_pads
				(clearance 0)
			)
			(min_thickness 0.25)
			(keepout
				(tracks not_allowed)
				(vias allowed)
				(pads allowed)
				(copperpour not_allowed)
				(footprints allowed)
			)
			(placement
				(enabled no)
				(sheetname "")
			)
			(fill
				(thermal_gap 0.5)
				(thermal_bridge_width 0.5)
				(island_removal_mode 0)
			)
			(polygon
				(pts
					(xy 64.4906 52.0446) (xy 64.5414 52.0446) (xy 64.5414 52.0954) (xy 64.4906 52.0954)
				)
			)
		)
	)
	(footprint ""
		(layer "F.Cu")
		(at 65.405 41.5417 -90)
		(property "Reference" "L17"
			(at -4.93903 5.842 0)
			(unlocked yes)
			(layer "F.SilkS")
			(effects
				(font
					(size 0.7874 0.5842)
					(thickness 0.127)
				)
				(justify left)
			)
		)
		(property "Value" "300NH"
			(at -0.4826 1.121918 270)
			(unlocked yes)
			(layer "F.Fab")
			(hide yes)
			(effects
				(font
					(size 1.27 0.9652)
					(thickness 0.000001)
				)
				(justify left)
			)
		)
		(property "Device Type" "INDS0042"
			(at -0.4826 1.121918 270)
			(unlocked yes)
			(layer "F.Fab")
			(hide yes)
			(effects
				(font
					(size 1.27 0.9652)
					(thickness 0.000001)
				)
				(justify left)
			)
		)
		(duplicate_pad_numbers_are_jumpers no)
		(fp_line
			(start -4.191 5.842)
			(end -2.8956 5.842)
			(stroke
				(width 0.2032)
				(type default)
			)
			(layer "F.SilkS")
		)
		(fp_line
			(start -4.191 5.842)
			(end -1.524 5.842)
			(stroke
				(width 0.2032)
				(type default)
			)
			(layer "F.SilkS")
		)
		(fp_line
			(start 4.0259 5.842)
			(end 2.8702 5.842)
			(stroke
				(width 0.2032)
				(type default)
			)
			(layer "F.SilkS")
		)
		(fp_line
			(start 4.191 5.842)
			(end 1.524 5.842)
			(stroke
				(width 0.2032)
				(type default)
			)
			(layer "F.SilkS")
		)
		(fp_line
			(start -4.191 3.768369)
			(end -4.191 5.842)
			(stroke
				(width 0.2032)
				(type default)
			)
			(layer "F.SilkS")
		)
		(fp_line
			(start -4.191 1.4224)
			(end -4.191 2.581631)
			(stroke
				(width 0.2032)
				(type default)
			)
			(layer "F.SilkS")
		)
		(fp_line
			(start -4.191 -4.975225)
			(end -4.191 -2.4384)
			(stroke
				(width 0.2032)
				(type default)
			)
			(layer "F.SilkS")
		)
		(fp_line
			(start -4.191 -5.842)
			(end -4.191 5.842)
			(stroke
				(width 0.2032)
				(type default)
			)
			(layer "F.SilkS")
		)
		(fp_line
			(start -1.5367 -5.842)
			(end -3.346831 -5.842)
			(stroke
				(width 0.2032)
				(type default)
			)
			(layer "F.SilkS")
		)
		(fp_line
			(start -1.524 -5.842)
			(end -4.191 -5.842)
			(stroke
				(width 0.2032)
				(type default)
			)
			(layer "F.SilkS")
		)
		(fp_line
			(start 1.524 -5.842)
			(end 4.191 -5.842)
			(stroke
				(width 0.2032)
				(type default)
			)
			(layer "F.SilkS")
		)
		(fp_line
			(start 1.5367 -5.842)
			(end 4.191 -5.842)
			(stroke
				(width 0.2032)
				(type default)
			)
			(layer "F.SilkS")
		)
		(fp_line
			(start 4.191 -5.842)
			(end 4.191 5.842)
			(stroke
				(width 0.2032)
				(type default)
			)
			(layer "F.SilkS")
		)
		(fp_line
			(start 4.191 -5.842)
			(end 4.191 -1.7526)
			(stroke
				(width 0.2032)
				(type default)
			)
			(layer "F.SilkS")
		)
		(fp_poly
			(pts
				(xy -4.445 -6.096) (xy -1.778 -6.096) (xy -1.778 -6.35) (xy 1.778 -6.35) (xy 1.778 -6.096) (xy 4.445 -6.096)
				(xy 4.445 6.096) (xy 1.778 6.096) (xy 1.778 6.35) (xy -1.778 6.35) (xy -1.778 6.096) (xy -4.445 6.096)
			)
			(stroke
				(width 0)
				(type default)
			)
			(fill no)
			(layer "F.CrtYd")
		)
		(fp_line
			(start -3.8227 5.4991)
			(end 3.8227 5.4991)
			(stroke
				(width 0.2032)
				(type default)
			)
			(layer "F.Fab")
		)
		(fp_line
			(start 3.8227 5.4991)
			(end 3.8227 -5.4991)
			(stroke
				(width 0.2032)
				(type default)
			)
			(layer "F.Fab")
		)
		(fp_line
			(start -3.8227 -5.4991)
			(end -3.8227 5.4991)
			(stroke
				(width 0.2032)
				(type default)
			)
			(layer "F.Fab")
		)
		(fp_line
			(start 3.8227 -5.4991)
			(end -3.8227 -5.4991)
			(stroke
				(width 0.2032)
				(type default)
			)
			(layer "F.Fab")
		)
		(pad "1" smd rect
			(at 0 -4.1783 270)
			(size 2.3622 3.4036)
			(layers "F.Cu" "F.Mask" "F.Paste")
			(net "L_1_CORE_PHASE")
		)
		(pad "2" smd rect
			(at 0 4.1783 270)
			(size 2.3622 3.4036)
			(layers "F.Cu" "F.Mask" "F.Paste")
			(net "VDD_CORE")
		)
	)
	(footprint ""
		(layer "F.Cu")
		(at 17.399 1.397)
		(property "Reference" "R73"
			(at 0.78867 -0.762 90)
			(unlocked yes)
			(layer "F.SilkS")
			(effects
				(font
					(size 0.7874 0.5842)
					(thickness 0.127)
				)
				(justify left)
			)
		)
		(property "Value" "4.75K"
			(at -0.148158 1.3462 90)
			(unlocked yes)
			(layer "F.Fab")
			(hide yes)
			(effects
				(font
					(size 1.27 0.9652)
					(thickness 0.000001)
				)
				(justify left)
			)
		)
		(property "Device Type" "REST4024"
			(at -0.148158 1.3462 90)
			(unlocked yes)
			(layer "F.Fab")
			(hide yes)
			(effects
				(font
					(size 1.27 0.9652)
					(thickness 0.000001)
				)
				(justify left)
			)
		)
		(duplicate_pad_numbers_are_jumpers no)
		(fp_poly
			(pts
				(xy 0.635 1.0668) (xy 0.635 -1.0668) (xy -0.635 -1.0668) (xy -0.635 1.0668)
			)
			(stroke
				(width 0)
				(type default)
			)
			(fill no)
			(layer "F.CrtYd")
		)
		(fp_line
			(start -0.254 -0.508)
			(end 0.254 -0.508)
			(stroke
				(width 0.0254)
				(type default)
			)
			(layer "F.Fab")
		)
		(fp_line
			(start -0.254 0.508)
			(end -0.254 -0.508)
			(stroke
				(width 0.0254)
				(type default)
			)
			(layer "F.Fab")
		)
		(fp_line
			(start 0.254 -0.508)
			(end 0.254 0.508)
			(stroke
				(width 0.0254)
				(type default)
			)
			(layer "F.Fab")
		)
		(fp_line
			(start 0.254 0.508)
			(end -0.254 0.508)
			(stroke
				(width 0.0254)
				(type default)
			)
			(layer "F.Fab")
		)
		(pad "1" smd rect
			(at 0 -0.4191)
			(size 0.508 0.5334)
			(layers "F.Cu" "F.Mask" "F.Paste")
			(net "EXT_3.3V")
		)
		(pad "2" smd rect
			(at 0 0.4191)
			(size 0.508 0.5334)
			(layers "F.Cu" "F.Mask" "F.Paste")
			(net "PCIE0_RST_L")
		)
		(zone
			(layer "F.Cu")
			(hatch none 0.5)
			(connect_pads
				(clearance 0)
			)
			(min_thickness 0.25)
			(keepout
				(tracks not_allowed)
				(vias allowed)
				(pads allowed)
				(copperpour not_allowed)
				(footprints allowed)
			)
			(placement
				(enabled no)
				(sheetname "")
			)
			(fill
				(thermal_gap 0.5)
				(thermal_bridge_width 0.5)
				(island_removal_mode 0)
			)
			(polygon
				(pts
					(xy 17.4244 1.3716) (xy 17.4244 1.4224) (xy 17.3736 1.4224) (xy 17.3736 1.3716)
				)
			)
		)
	)
	(footprint ""
		(layer "F.Cu")
		(at 65.024 36.957 -90)
		(property "Reference" "R166"
			(at -0.86233 2.667 0)
			(unlocked yes)
			(layer "F.SilkS")
			(effects
				(font
					(size 0.7874 0.5842)
					(thickness 0.127)
				)
				(justify left)
			)
		)
		(property "Value" "0"
			(at -0.148158 1.3462 0)
			(unlocked yes)
			(layer "F.Fab")
			(hide yes)
			(effects
				(font
					(size 1.27 0.9652)
					(thickness 0.000001)
				)
				(justify left)
			)
		)
		(property "Device Type" "REST1111"
			(at -0.148158 1.3462 0)
			(unlocked yes)
			(layer "F.Fab")
			(hide yes)
			(effects
				(font
					(size 1.27 0.9652)
					(thickness 0.000001)
				)
				(justify left)
			)
		)
		(duplicate_pad_numbers_are_jumpers no)
		(fp_poly
			(pts
				(xy 0.635 1.0668) (xy 0.635 -1.0668) (xy -0.635 -1.0668) (xy -0.635 1.0668)
			)
			(stroke
				(width 0)
				(type default)
			)
			(fill no)
			(layer "F.CrtYd")
		)
		(fp_line
			(start -0.254 0.508)
			(end -0.254 -0.508)
			(stroke
				(width 0.0254)
				(type default)
			)
			(layer "F.Fab")
		)
		(fp_line
			(start 0.254 0.508)
			(end -0.254 0.508)
			(stroke
				(width 0.0254)
				(type default)
			)
			(layer "F.Fab")
		)
		(fp_line
			(start -0.254 -0.508)
			(end 0.254 -0.508)
			(stroke
				(width 0.0254)
				(type default)
			)
			(layer "F.Fab")
		)
		(fp_line
			(start 0.254 -0.508)
			(end 0.254 0.508)
			(stroke
				(width 0.0254)
				(type default)
			)
			(layer "F.Fab")
		)
		(pad "1" smd rect
			(at 0 -0.4191 270)
			(size 0.508 0.5334)
			(layers "F.Cu" "F.Mask" "F.Paste")
			(net "VDD_CORE")
		)
		(pad "2" smd rect
			(at 0 0.4191 270)
			(size 0.508 0.5334)
			(layers "F.Cu" "F.Mask" "F.Paste")
			(net "NFP_VDD_CORE_ISEN1_N")
		)
		(zone
			(layer "F.Cu")
			(hatch none 0.5)
			(connect_pads
				(clearance 0)
			)
			(min_thickness 0.25)
			(keepout
				(tracks not_allowed)
				(vias allowed)
				(pads allowed)
				(copperpour not_allowed)
				(footprints allowed)
			)
			(placement
				(enabled no)
				(sheetname "")
			)
			(fill
				(thermal_gap 0.5)
				(thermal_bridge_width 0.5)
				(island_removal_mode 0)
			)
			(polygon
				(pts
					(xy 65.0494 36.9824) (xy 64.9986 36.9824) (xy 64.9986 36.9316) (xy 65.0494 36.9316)
				)
			)
		)
	)
	(footprint ""
		(layer "F.Cu")
		(at 17.78 47.498 180)
		(property "Reference" "TP50"
			(at 3.556 -2.05867 0)
			(unlocked yes)
			(layer "F.SilkS")
			(effects
				(font
					(size 0.7874 0.5842)
					(thickness 0.127)
				)
				(justify left)
			)
		)
		(property "Value" "*"
			(at -0.4826 -0.14732 180)
			(unlocked yes)
			(layer "F.Fab")
			(hide yes)
			(effects
				(font
					(size 1.27 0.9652)
					(thickness 0.000001)
				)
				(justify left)
			)
		)
		(property "Device Type" "TP_SMALL"
			(at -0.4826 -0.14732 180)
			(unlocked yes)
			(layer "F.Fab")
			(hide yes)
			(effects
				(font
					(size 1.27 0.9652)
					(thickness 0.000001)
				)
				(justify left)
			)
		)
		(duplicate_pad_numbers_are_jumpers no)
		(fp_line
			(start 0.8636 0.8636)
			(end 0.8636 -0.8636)
			(stroke
				(width 0.1524)
				(type default)
			)
			(layer "F.SilkS")
		)
		(fp_line
			(start 0.8636 -0.8636)
			(end -0.8636 -0.8636)
			(stroke
				(width 0.1524)
				(type default)
			)
			(layer "F.SilkS")
		)
		(fp_line
			(start -0.8636 0.8636)
			(end 0.8636 0.8636)
			(stroke
				(width 0.1524)
				(type default)
			)
			(layer "F.SilkS")
		)
		(fp_line
			(start -0.8636 -0.8636)
			(end -0.8636 0.8636)
			(stroke
				(width 0.1524)
				(type default)
			)
			(layer "F.SilkS")
		)
		(fp_poly
			(pts
				(xy -0.635 -0.635) (xy -0.635 0.635) (xy 0.635 0.635) (xy 0.635 -0.635)
			)
			(stroke
				(width 0)
				(type default)
			)
			(fill no)
			(layer "F.CrtYd")
		)
		(pad "1" smd rect
			(at 0 0 180)
			(size 1.27 1.27)
			(layers "F.Cu" "F.Mask" "F.Paste")
			(net "VDD_1.8V")
		)
	)
	(footprint ""
		(layer "F.Cu")
		(at 16.383 42.2021 -90)
		(property "Reference" "C19"
			(at -0.13843 3.683 0)
			(unlocked yes)
			(layer "F.SilkS")
			(effects
				(font
					(size 0.7874 0.5842)
					(thickness 0.127)
				)
				(justify left)
			)
		)
		(property "Value" "22UF"
			(at -0.148158 1.7526 0)
			(unlocked yes)
			(layer "F.Fab")
			(hide yes)
			(effects
				(font
					(size 1.27 0.9652)
					(thickness 0.000001)
				)
				(justify left)
			)
		)
		(property "Device Type" "CAPC0063"
			(at -0.148158 1.7526 0)
			(unlocked yes)
			(layer "F.Fab")
			(hide yes)
			(effects
				(font
					(size 1.27 0.9652)
					(thickness 0.000001)
				)
				(justify left)
			)
		)
		(duplicate_pad_numbers_are_jumpers no)
		(fp_circle
			(center 0 0)
			(end 0 -0.127)
			(stroke
				(width 0.2032)
				(type default)
			)
			(fill no)
			(layer "F.SilkS")
		)
		(fp_poly
			(pts
				(xy 0.7874 -1.6637) (xy -0.7874 -1.6637) (xy -0.7874 1.6637) (xy 0.7874 1.6637)
			)
			(stroke
				(width 0)
				(type default)
			)
			(fill no)
			(layer "F.CrtYd")
		)
		(fp_line
			(start -0.4064 0.8128)
			(end -0.4064 -0.7874)
			(stroke
				(width 0.0254)
				(type default)
			)
			(layer "F.Fab")
		)
		(fp_line
			(start 0.4064 0.8128)
			(end -0.4064 0.8128)
			(stroke
				(width 0.0254)
				(type default)
			)
			(layer "F.Fab")
		)
		(fp_line
			(start -0.4064 -0.7874)
			(end 0.4064 -0.7874)
			(stroke
				(width 0.0254)
				(type default)
			)
			(layer "F.Fab")
		)
		(fp_line
			(start 0.4064 -0.7874)
			(end 0.4064 0.8128)
			(stroke
				(width 0.0254)
				(type default)
			)
			(layer "F.Fab")
		)
		(pad "1" smd rect
			(at 0 -0.8001 270)
			(size 0.8636 0.9652)
			(layers "F.Cu" "F.Mask" "F.Paste")
			(net "VDD_1.8V")
		)
		(pad "2" smd rect
			(at 0 0.8001 270)
			(size 0.8636 0.9652)
			(layers "F.Cu" "F.Mask" "F.Paste")
			(net "GND")
		)
		(zone
			(layer "F.Cu")
			(hatch none 0.5)
			(connect_pads
				(clearance 0)
			)
			(min_thickness 0.25)
			(keepout
				(tracks not_allowed)
				(vias allowed)
				(pads allowed)
				(copperpour not_allowed)
				(footprints allowed)
			)
			(placement
				(enabled no)
				(sheetname "")
			)
			(fill
				(thermal_gap 0.5)
				(thermal_bridge_width 0.5)
				(island_removal_mode 0)
			)
			(polygon
				(pts
					(xy 16.637 42.1386) (xy 16.637 42.2656) (xy 16.129 42.2656) (xy 16.129 42.1386)
				)
			)
		)
	)
	(footprint ""
		(layer "F.Cu")
		(at 73.05101 19.055994)
		(property "Reference" "V_A-DQ25"
			(at 0 0 0)
			(layer "F.SilkS")
			(hide yes)
			(effects
				(font
					(size 1.27 1.27)
				)
			)
		)
		(property "Value" ""
			(at 0 0 0)
			(layer "F.Fab")
			(effects
				(font
					(size 1.27 1.27)
				)
			)
		)
		(duplicate_pad_numbers_are_jumpers no)
		(pad "1" thru_hole circle
			(at 0 0)
			(size 0.762 0.762)
			(drill 0.20574)
			(layers "*.Cu" "*.Mask")
			(remove_unused_layers no)
			(net "DDR0_32A_DQ25")
			(clearance 0.127)
			(thermal_gap 0.127)
			(padstack
				(mode front_inner_back)
				(layer "Inner"
					(shape circle)
					(size 0.4572 0.4572)
					(clearance 0.1143)
				)
				(layer "B.Cu"
					(shape circle)
					(size 0.4572 0.4572)
					(clearance 0.1143)
				)
			)
		)
	)
	(footprint ""
		(layer "F.Cu")
		(at 19.685 6.5278)
		(property "Reference" "R393"
			(at 0 0 0)
			(layer "F.SilkS")
			(hide yes)
			(effects
				(font
					(size 1.27 1.27)
				)
			)
		)
		(property "Value" "240"
			(at -0.148158 1.3462 90)
			(unlocked yes)
			(layer "F.Fab")
			(hide yes)
			(effects
				(font
					(size 1.27 0.9652)
					(thickness 0.000001)
				)
				(justify left)
			)
		)
		(property "Device Type" "REST0009"
			(at -0.148158 1.3462 90)
			(unlocked yes)
			(layer "F.Fab")
			(hide yes)
			(effects
				(font
					(size 1.27 0.9652)
					(thickness 0.000001)
				)
				(justify left)
			)
		)
		(duplicate_pad_numbers_are_jumpers no)
		(fp_poly
			(pts
				(xy 0.635 1.0668) (xy 0.635 -1.0668) (xy -0.635 -1.0668) (xy -0.635 1.0668)
			)
			(stroke
				(width 0)
				(type default)
			)
			(fill no)
			(layer "F.CrtYd")
		)
		(fp_line
			(start -0.254 -0.508)
			(end 0.254 -0.508)
			(stroke
				(width 0.0254)
				(type default)
			)
			(layer "F.Fab")
		)
		(fp_line
			(start -0.254 0.508)
			(end -0.254 -0.508)
			(stroke
				(width 0.0254)
				(type default)
			)
			(layer "F.Fab")
		)
		(fp_line
			(start 0.254 -0.508)
			(end 0.254 0.508)
			(stroke
				(width 0.0254)
				(type default)
			)
			(layer "F.Fab")
		)
		(fp_line
			(start 0.254 0.508)
			(end -0.254 0.508)
			(stroke
				(width 0.0254)
				(type default)
			)
			(layer "F.Fab")
		)
		(pad "1" smd rect
			(at 0 -0.4191)
			(size 0.508 0.5334)
			(layers "F.Cu" "F.Mask" "F.Paste")
			(net "13N4321")
		)
		(pad "2" smd rect
			(at 0 0.4191)
			(size 0.508 0.5334)
			(layers "F.Cu" "F.Mask" "F.Paste")
			(net "VDD_3.3V")
		)
		(zone
			(layer "F.Cu")
			(hatch none 0.5)
			(connect_pads
				(clearance 0)
			)
			(min_thickness 0.25)
			(keepout
				(tracks not_allowed)
				(vias allowed)
				(pads allowed)
				(copperpour not_allowed)
				(footprints allowed)
			)
			(placement
				(enabled no)
				(sheetname "")
			)
			(fill
				(thermal_gap 0.5)
				(thermal_bridge_width 0.5)
				(island_removal_mode 0)
			)
			(polygon
				(pts
					(xy 19.7104 6.5024) (xy 19.7104 6.5532) (xy 19.6596 6.5532) (xy 19.6596 6.5024)
				)
			)
		)
	)
	(footprint ""
		(layer "F.Cu")
		(at 75.451005 13.456006)
		(property "Reference" "V_A-DQ21"
			(at 0 0 0)
			(layer "F.SilkS")
			(hide yes)
			(effects
				(font
					(size 1.27 1.27)
				)
			)
		)
		(property "Value" ""
			(at 0 0 0)
			(layer "F.Fab")
			(effects
				(font
					(size 1.27 1.27)
				)
			)
		)
		(duplicate_pad_numbers_are_jumpers no)
		(pad "1" thru_hole circle
			(at 0 0)
			(size 0.762 0.762)
			(drill 0.20574)
			(layers "*.Cu" "*.Mask")
			(remove_unused_layers no)
			(net "DDR0_32A_DQ21")
			(clearance 0.127)
			(thermal_gap 0.127)
			(padstack
				(mode front_inner_back)
				(layer "Inner"
					(shape circle)
					(size 0.4572 0.4572)
					(clearance 0.1143)
				)
				(layer "B.Cu"
					(shape circle)
					(size 0.4572 0.4572)
					(clearance 0.1143)
				)
			)
		)
	)
	(footprint ""
		(layer "F.Cu")
		(at 17.653 12.192 180)
		(property "Reference" "R350"
			(at -0.02667 -3.937 90)
			(unlocked yes)
			(layer "F.SilkS")
			(effects
				(font
					(size 0.7874 0.5842)
					(thickness 0.127)
				)
				(justify left)
			)
		)
		(property "Value" "0"
			(at -0.148158 1.3462 270)
			(unlocked yes)
			(layer "F.Fab")
			(hide yes)
			(effects
				(font
					(size 1.27 0.9652)
					(thickness 0.000001)
				)
				(justify left)
			)
		)
		(property "Device Type" "REST1111"
			(at -0.148158 1.3462 270)
			(unlocked yes)
			(layer "F.Fab")
			(hide yes)
			(effects
				(font
					(size 1.27 0.9652)
					(thickness 0.000001)
				)
				(justify left)
			)
		)
		(duplicate_pad_numbers_are_jumpers no)
		(fp_poly
			(pts
				(xy 0.635 1.0668) (xy 0.635 -1.0668) (xy -0.635 -1.0668) (xy -0.635 1.0668)
			)
			(stroke
				(width 0)
				(type default)
			)
			(fill no)
			(layer "F.CrtYd")
		)
		(fp_line
			(start 0.254 0.508)
			(end -0.254 0.508)
			(stroke
				(width 0.0254)
				(type default)
			)
			(layer "F.Fab")
		)
		(fp_line
			(start 0.254 -0.508)
			(end 0.254 0.508)
			(stroke
				(width 0.0254)
				(type default)
			)
			(layer "F.Fab")
		)
		(fp_line
			(start -0.254 0.508)
			(end -0.254 -0.508)
			(stroke
				(width 0.0254)
				(type default)
			)
			(layer "F.Fab")
		)
		(fp_line
			(start -0.254 -0.508)
			(end 0.254 -0.508)
			(stroke
				(width 0.0254)
				(type default)
			)
			(layer "F.Fab")
		)
		(pad "1" smd rect
			(at 0 -0.4191 180)
			(size 0.508 0.5334)
			(layers "F.Cu" "F.Mask" "F.Paste")
			(net "CPLD_SMBUS_SDA")
		)
		(pad "2" smd rect
			(at 0 0.4191 180)
			(size 0.508 0.5334)
			(layers "F.Cu" "F.Mask" "F.Paste")
			(net "SMBUS_SDA")
		)
		(zone
			(layer "F.Cu")
			(hatch none 0.5)
			(connect_pads
				(clearance 0)
			)
			(min_thickness 0.25)
			(keepout
				(tracks not_allowed)
				(vias allowed)
				(pads allowed)
				(copperpour not_allowed)
				(footprints allowed)
			)
			(placement
				(enabled no)
				(sheetname "")
			)
			(fill
				(thermal_gap 0.5)
				(thermal_bridge_width 0.5)
				(island_removal_mode 0)
			)
			(polygon
				(pts
					(xy 17.6276 12.2174) (xy 17.6276 12.1666) (xy 17.6784 12.1666) (xy 17.6784 12.2174)
				)
			)
		)
	)
	(footprint ""
		(layer "F.Cu")
		(at 63.5 49.784 90)
		(property "Reference" "U13"
			(at -2.43967 -2.032 0)
			(unlocked yes)
			(layer "F.SilkS")
			(effects
				(font
					(size 0.7874 0.5842)
					(thickness 0.127)
				)
				(justify left)
			)
		)
		(property "Value" "VAL"
			(at 0 2.010918 90)
			(unlocked yes)
			(layer "F.Fab")
			(hide yes)
			(effects
				(font
					(size 1.27 0.964946)
					(thickness 0.000001)
				)
			)
		)
		(property "Tolerance" "TOL"
			(at 0 3.915918 90)
			(unlocked yes)
			(layer "Cmts.User")
			(hide yes)
			(effects
				(font
					(size 1.27 0.964946)
					(thickness 0.000001)
				)
			)
		)
		(property "User Part Number" "PN"
			(at 0 -3.704082 90)
			(unlocked yes)
			(layer "Cmts.User")
			(hide yes)
			(effects
				(font
					(size 1.27 0.964946)
					(thickness 0.000001)
				)
			)
		)
		(property "Device Type" "DCDC0066"
			(at 0 -1.799082 90)
			(unlocked yes)
			(layer "F.Fab")
			(hide yes)
			(effects
				(font
					(size 1.27 0.964946)
					(thickness 0.000001)
				)
			)
		)
		(duplicate_pad_numbers_are_jumpers no)
		(fp_line
			(start 1.601216 -1.601216)
			(end 1.601216 -1.169162)
			(stroke
				(width 0.1524)
				(type default)
			)
			(layer "F.SilkS")
		)
		(fp_line
			(start 1.169162 -1.601216)
			(end 1.601216 -1.601216)
			(stroke
				(width 0.1524)
				(type default)
			)
			(layer "F.SilkS")
		)
		(fp_line
			(start -1.220216 -1.601216)
			(end -1.169162 -1.601216)
			(stroke
				(width 0.1524)
				(type default)
			)
			(layer "F.SilkS")
		)
		(fp_line
			(start -1.601216 -1.220216)
			(end -1.220216 -1.601216)
			(stroke
				(width 0.1524)
				(type default)
			)
			(layer "F.SilkS")
		)
		(fp_line
			(start -1.601216 -1.169162)
			(end -1.601216 -1.220216)
			(stroke
				(width 0.1524)
				(type default)
			)
			(layer "F.SilkS")
		)
		(fp_line
			(start 1.601216 1.169162)
			(end 1.601216 1.601216)
			(stroke
				(width 0.1524)
				(type default)
			)
			(layer "F.SilkS")
		)
		(fp_line
			(start 1.601216 1.601216)
			(end 1.169162 1.601216)
			(stroke
				(width 0.1524)
				(type default)
			)
			(layer "F.SilkS")
		)
		(fp_line
			(start -1.169162 1.601216)
			(end -1.601216 1.601216)
			(stroke
				(width 0.1524)
				(type default)
			)
			(layer "F.SilkS")
		)
		(fp_line
			(start -1.601216 1.601216)
			(end -1.601216 1.169162)
			(stroke
				(width 0.1524)
				(type default)
			)
			(layer "F.SilkS")
		)
		(fp_arc
			(start -1.677492 -1.893037)
			(mid -1.497852 -1.818614)
			(end -1.423416 -1.63896)
			(stroke
				(width 0.1524)
				(type default)
			)
			(layer "F.SilkS")
		)
		(fp_arc
			(start -1.832153 -1.840535)
			(mid -1.759157 -1.879554)
			(end -1.677492 -1.893037)
			(stroke
				(width 0.1524)
				(type default)
			)
			(layer "F.SilkS")
		)
		(fp_arc
			(start -1.423416 -1.63896)
			(mid -1.497847 -1.459324)
			(end -1.677492 -1.384884)
			(stroke
				(width 0.1524)
				(type default)
			)
			(layer "F.SilkS")
		)
		(fp_arc
			(start -1.677492 -1.384884)
			(mid -1.802412 -1.41776)
			(end -1.895043 -1.507795)
			(stroke
				(width 0.1524)
				(type default)
			)
			(layer "F.SilkS")
		)
		(fp_circle
			(center -1.677492 -1.63896)
			(end -1.677492 -1.384884)
			(stroke
				(width 0.1524)
				(type default)
			)
			(fill no)
			(layer "F.SilkS")
		)
		(fp_poly
			(pts
				(xy -1.91897 -1.91897) (xy -1.91897 1.91897) (xy 1.91897 1.91897) (xy 1.91897 -1.91897)
			)
			(stroke
				(width 0)
				(type default)
			)
			(fill no)
			(layer "F.CrtYd")
		)
		(fp_line
			(start 1.525016 -1.525016)
			(end -1.144016 -1.525016)
			(stroke
				(width 0.0254)
				(type default)
			)
			(layer "F.Fab")
		)
		(fp_line
			(start -1.144016 -1.525016)
			(end -1.525016 -1.144016)
			(stroke
				(width 0.0254)
				(type default)
			)
			(layer "F.Fab")
		)
		(fp_line
			(start -1.525016 -1.144016)
			(end -1.525016 1.525016)
			(stroke
				(width 0.0254)
				(type default)
			)
			(layer "F.Fab")
		)
		(fp_line
			(start 1.525016 1.525016)
			(end 1.525016 -1.525016)
			(stroke
				(width 0.0254)
				(type default)
			)
			(layer "F.Fab")
		)
		(fp_line
			(start -1.525016 1.525016)
			(end 1.525016 1.525016)
			(stroke
				(width 0.0254)
				(type default)
			)
			(layer "F.Fab")
		)
		(fp_circle
			(center -1.046734 -0.74996)
			(end -1.046734 -0.49596)
			(stroke
				(width 0.0254)
				(type default)
			)
			(fill no)
			(layer "F.Fab")
		)
		(pad "1" smd rect
			(at -1.359916 -0.750062)
			(size 0.279908 0.483108)
			(layers "F.Cu" "F.Mask" "F.Paste")
			(net "11N1952")
		)
		(pad "2" smd rect
			(at -1.359916 -0.249936)
			(size 0.279908 0.483108)
			(layers "F.Cu" "F.Mask" "F.Paste")
			(net "EXT_12.0V")
		)
		(pad "3" smd rect
			(at -1.359916 0.249936)
			(size 0.279908 0.483108)
			(layers "F.Cu" "F.Mask" "F.Paste")
			(net "EXT_12.0V")
		)
		(pad "4" smd rect
			(at -1.359916 0.750062)
			(size 0.279908 0.483108)
			(layers "F.Cu" "F.Mask" "F.Paste")
			(net "GND")
		)
		(pad "5" smd rect
			(at -0.750062 1.359916 90)
			(size 0.279908 0.483108)
			(layers "F.Cu" "F.Mask" "F.Paste")
			(net "11N1953")
		)
		(pad "6" smd rect
			(at -0.249936 1.359916 90)
			(size 0.279908 0.483108)
			(layers "F.Cu" "F.Mask" "F.Paste")
			(net "_NC_MIC24085_NC1")
		)
		(pad "7" smd rect
			(at 0.249936 1.359916 90)
			(size 0.279908 0.483108)
			(layers "F.Cu" "F.Mask" "F.Paste")
			(net "_NC_MIC24085_NC2")
		)
		(pad "8" smd rect
			(at 0.750062 1.359916 90)
			(size 0.279908 0.483108)
			(layers "F.Cu" "F.Mask" "F.Paste")
			(net "VDD_5.0V_PGOOD")
		)
		(pad "9" smd rect
			(at 1.359916 0.750062)
			(size 0.279908 0.483108)
			(layers "F.Cu" "F.Mask" "F.Paste")
			(net "VDD_5.0V_EN")
		)
		(pad "10" smd rect
			(at 1.359916 0.249936)
			(size 0.279908 0.483108)
			(layers "F.Cu" "F.Mask" "F.Paste")
			(net "11N1981")
		)
		(pad "11" smd rect
			(at 1.359916 -0.249936)
			(size 0.279908 0.483108)
			(layers "F.Cu" "F.Mask" "F.Paste")
			(net "EXT_12.0V")
		)
		(pad "12" smd rect
			(at 1.359916 -0.750062)
			(size 0.279908 0.483108)
			(layers "F.Cu" "F.Mask" "F.Paste")
			(net "11N1952")
		)
		(pad "13" smd rect
			(at 0.750062 -1.359916 90)
			(size 0.279908 0.483108)
			(layers "F.Cu" "F.Mask" "F.Paste")
			(net "11N1952")
		)
		(pad "14" smd rect
			(at 0.249936 -1.359916 90)
			(size 0.279908 0.483108)
			(layers "F.Cu" "F.Mask" "F.Paste")
			(net "GND")
		)
		(pad "15" smd rect
			(at -0.249936 -1.359916 90)
			(size 0.279908 0.483108)
			(layers "F.Cu" "F.Mask" "F.Paste")
			(net "GND")
		)
		(pad "16" smd rect
			(at -0.750062 -1.359916 90)
			(size 0.279908 0.483108)
			(layers "F.Cu" "F.Mask" "F.Paste")
			(net "11N1952")
		)
		(pad "17" smd rect
			(at 0 0 90)
			(size 1.700022 1.700022)
			(layers "F.Cu" "F.Mask" "F.Paste")
			(net "GND")
		)
	)
	(footprint ""
		(layer "F.Cu")
		(at 19.304 5.207 -90)
		(property "Reference" "R372"
			(at 0 0 270)
			(layer "F.SilkS")
			(hide yes)
			(effects
				(font
					(size 1.27 1.27)
				)
			)
		)
		(property "Value" "4.75K"
			(at -0.148158 1.3462 0)
			(unlocked yes)
			(layer "F.Fab")
			(hide yes)
			(effects
				(font
					(size 1.27 0.9652)
					(thickness 0.000001)
				)
				(justify left)
			)
		)
		(property "Device Type" "REST4024"
			(at -0.148158 1.3462 0)
			(unlocked yes)
			(layer "F.Fab")
			(hide yes)
			(effects
				(font
					(size 1.27 0.9652)
					(thickness 0.000001)
				)
				(justify left)
			)
		)
		(duplicate_pad_numbers_are_jumpers no)
		(fp_poly
			(pts
				(xy 0.635 1.0668) (xy 0.635 -1.0668) (xy -0.635 -1.0668) (xy -0.635 1.0668)
			)
			(stroke
				(width 0)
				(type default)
			)
			(fill no)
			(layer "F.CrtYd")
		)
		(fp_line
			(start -0.254 0.508)
			(end -0.254 -0.508)
			(stroke
				(width 0.0254)
				(type default)
			)
			(layer "F.Fab")
		)
		(fp_line
			(start 0.254 0.508)
			(end -0.254 0.508)
			(stroke
				(width 0.0254)
				(type default)
			)
			(layer "F.Fab")
		)
		(fp_line
			(start -0.254 -0.508)
			(end 0.254 -0.508)
			(stroke
				(width 0.0254)
				(type default)
			)
			(layer "F.Fab")
		)
		(fp_line
			(start 0.254 -0.508)
			(end 0.254 0.508)
			(stroke
				(width 0.0254)
				(type default)
			)
			(layer "F.Fab")
		)
		(pad "1" smd rect
			(at 0 -0.4191 270)
			(size 0.508 0.5334)
			(layers "F.Cu" "F.Mask" "F.Paste")
			(net "13N4321")
		)
		(pad "2" smd rect
			(at 0 0.4191 270)
			(size 0.508 0.5334)
			(layers "F.Cu" "F.Mask" "F.Paste")
			(net "GND")
		)
		(zone
			(layer "F.Cu")
			(hatch none 0.5)
			(connect_pads
				(clearance 0)
			)
			(min_thickness 0.25)
			(keepout
				(tracks not_allowed)
				(vias allowed)
				(pads allowed)
				(copperpour not_allowed)
				(footprints allowed)
			)
			(placement
				(enabled no)
				(sheetname "")
			)
			(fill
				(thermal_gap 0.5)
				(thermal_bridge_width 0.5)
				(island_removal_mode 0)
			)
			(polygon
				(pts
					(xy 19.3294 5.2324) (xy 19.2786 5.2324) (xy 19.2786 5.1816) (xy 19.3294 5.1816)
				)
			)
		)
	)
	(footprint ""
		(layer "F.Cu")
		(at 76.708 28.194 -90)
		(property "Reference" "R8"
			(at -0.73533 1.143 0)
			(unlocked yes)
			(layer "F.SilkS")
			(effects
				(font
					(size 0.7874 0.5842)
					(thickness 0.127)
				)
				(justify left)
			)
		)
		(property "Value" "36.0"
			(at -0.148158 1.3462 0)
			(unlocked yes)
			(layer "F.Fab")
			(hide yes)
			(effects
				(font
					(size 1.27 0.9652)
					(thickness 0.000001)
				)
				(justify left)
			)
		)
		(property "Device Type" "REST0125"
			(at -0.148158 1.3462 0)
			(unlocked yes)
			(layer "F.Fab")
			(hide yes)
			(effects
				(font
					(size 1.27 0.9652)
					(thickness 0.000001)
				)
				(justify left)
			)
		)
		(duplicate_pad_numbers_are_jumpers no)
		(fp_poly
			(pts
				(xy 0.635 1.0668) (xy 0.635 -1.0668) (xy -0.635 -1.0668) (xy -0.635 1.0668)
			)
			(stroke
				(width 0)
				(type default)
			)
			(fill no)
			(layer "F.CrtYd")
		)
		(fp_line
			(start -0.254 0.508)
			(end -0.254 -0.508)
			(stroke
				(width 0.0254)
				(type default)
			)
			(layer "F.Fab")
		)
		(fp_line
			(start 0.254 0.508)
			(end -0.254 0.508)
			(stroke
				(width 0.0254)
				(type default)
			)
			(layer "F.Fab")
		)
		(fp_line
			(start -0.254 -0.508)
			(end 0.254 -0.508)
			(stroke
				(width 0.0254)
				(type default)
			)
			(layer "F.Fab")
		)
		(fp_line
			(start 0.254 -0.508)
			(end 0.254 0.508)
			(stroke
				(width 0.0254)
				(type default)
			)
			(layer "F.Fab")
		)
		(pad "1" smd rect
			(at 0 -0.4191 270)
			(size 0.508 0.5334)
			(layers "F.Cu" "F.Mask" "F.Paste")
			(net "DDR0_32A_CK0_N")
		)
		(pad "2" smd rect
			(at 0 0.4191 270)
			(size 0.508 0.5334)
			(layers "F.Cu" "F.Mask" "F.Paste")
			(net "6N4748")
		)
		(zone
			(layer "F.Cu")
			(hatch none 0.5)
			(connect_pads
				(clearance 0)
			)
			(min_thickness 0.25)
			(keepout
				(tracks not_allowed)
				(vias allowed)
				(pads allowed)
				(copperpour not_allowed)
				(footprints allowed)
			)
			(placement
				(enabled no)
				(sheetname "")
			)
			(fill
				(thermal_gap 0.5)
				(thermal_bridge_width 0.5)
				(island_removal_mode 0)
			)
			(polygon
				(pts
					(xy 76.7334 28.2194) (xy 76.6826 28.2194) (xy 76.6826 28.1686) (xy 76.7334 28.1686)
				)
			)
		)
	)
	(footprint ""
		(layer "F.Cu")
		(at 81.407 23.368 -90)
		(property "Reference" "C220"
			(at 0 0 270)
			(layer "F.SilkS")
			(hide yes)
			(effects
				(font
					(size 1.27 1.27)
				)
			)
		)
		(property "Value" "1UF"
			(at -0.091846 0.2921 0)
			(unlocked yes)
			(layer "F.Fab")
			(hide yes)
			(effects
				(font
					(size 0.7874 0.5842)
					(thickness 0.2032)
				)
				(justify left)
			)
		)
		(property "Device Type" "CAPC0028"
			(at -0.091846 0.2921 0)
			(unlocked yes)
			(layer "F.Fab")
			(hide yes)
			(effects
				(font
					(size 0.7874 0.5842)
					(thickness 0.2032)
				)
				(justify left)
			)
		)
		(duplicate_pad_numbers_are_jumpers no)
		(fp_poly
			(pts
				(xy 0.635 1.0668) (xy 0.635 -1.0668) (xy -0.635 -1.0668) (xy -0.635 1.0668)
			)
			(stroke
				(width 0)
				(type default)
			)
			(fill no)
			(layer "F.CrtYd")
		)
		(fp_line
			(start -0.254 0.508)
			(end -0.254 -0.508)
			(stroke
				(width 0.0254)
				(type default)
			)
			(layer "F.Fab")
		)
		(fp_line
			(start 0.254 0.508)
			(end -0.254 0.508)
			(stroke
				(width 0.0254)
				(type default)
			)
			(layer "F.Fab")
		)
		(fp_line
			(start -0.254 -0.508)
			(end 0.254 -0.508)
			(stroke
				(width 0.0254)
				(type default)
			)
			(layer "F.Fab")
		)
		(fp_line
			(start 0.254 -0.508)
			(end 0.254 0.508)
			(stroke
				(width 0.0254)
				(type default)
			)
			(layer "F.Fab")
		)
		(pad "1" smd rect
			(at 0 -0.4191 270)
			(size 0.508 0.5334)
			(layers "F.Cu" "F.Mask" "F.Paste")
			(net "DDR_VDDQ")
		)
		(pad "2" smd rect
			(at 0 0.4191 270)
			(size 0.508 0.5334)
			(layers "F.Cu" "F.Mask" "F.Paste")
			(net "GND")
		)
		(zone
			(layer "F.Cu")
			(hatch none 0.5)
			(connect_pads
				(clearance 0)
			)
			(min_thickness 0.25)
			(keepout
				(tracks not_allowed)
				(vias allowed)
				(pads allowed)
				(copperpour not_allowed)
				(footprints allowed)
			)
			(placement
				(enabled no)
				(sheetname "")
			)
			(fill
				(thermal_gap 0.5)
				(thermal_bridge_width 0.5)
				(island_removal_mode 0)
			)
			(polygon
				(pts
					(xy 81.4324 23.3934) (xy 81.3816 23.3934) (xy 81.3816 23.3426) (xy 81.4324 23.3426)
				)
			)
		)
	)
	(footprint ""
		(layer "F.Cu")
		(at 75.8952 42.799 -90)
		(property "Reference" "TP52"
			(at -1.143 -0.15367 90)
			(unlocked yes)
			(layer "F.SilkS")
			(effects
				(font
					(size 0.7874 0.5842)
					(thickness 0.127)
				)
				(justify left)
			)
		)
		(property "Value" "*"
			(at -0.4826 -0.14732 270)
			(unlocked yes)
			(layer "F.Fab")
			(hide yes)
			(effects
				(font
					(size 1.27 0.9652)
					(thickness 0.000001)
				)
				(justify left)
			)
		)
		(property "Device Type" "TP_SMALL"
			(at -0.4826 -0.14732 270)
			(unlocked yes)
			(layer "F.Fab")
			(hide yes)
			(effects
				(font
					(size 1.27 0.9652)
					(thickness 0.000001)
				)
				(justify left)
			)
		)
		(duplicate_pad_numbers_are_jumpers no)
		(fp_line
			(start -0.8636 0.8636)
			(end 0.8636 0.8636)
			(stroke
				(width 0.1524)
				(type default)
			)
			(layer "F.SilkS")
		)
		(fp_line
			(start 0.8636 0.8636)
			(end 0.8636 -0.8636)
			(stroke
				(width 0.1524)
				(type default)
			)
			(layer "F.SilkS")
		)
		(fp_line
			(start -0.8636 -0.8636)
			(end -0.8636 0.8636)
			(stroke
				(width 0.1524)
				(type default)
			)
			(layer "F.SilkS")
		)
		(fp_line
			(start 0.8636 -0.8636)
			(end -0.8636 -0.8636)
			(stroke
				(width 0.1524)
				(type default)
			)
			(layer "F.SilkS")
		)
		(fp_poly
			(pts
				(xy -0.635 -0.635) (xy -0.635 0.635) (xy 0.635 0.635) (xy 0.635 -0.635)
			)
			(stroke
				(width 0)
				(type default)
			)
			(fill no)
			(layer "F.CrtYd")
		)
		(pad "1" smd rect
			(at 0 0 270)
			(size 1.27 1.27)
			(layers "F.Cu" "F.Mask" "F.Paste")
			(net "DDR_VTT")
		)
	)
	(footprint ""
		(layer "F.Cu")
		(at 10.033 37.592)
		(property "Reference" "C135"
			(at 1.16967 0.381 90)
			(unlocked yes)
			(layer "F.SilkS")
			(effects
				(font
					(size 0.7874 0.5842)
					(thickness 0.127)
				)
				(justify left)
			)
		)
		(property "Value" "10UF"
			(at -0.148158 1.7526 90)
			(unlocked yes)
			(layer "F.Fab")
			(hide yes)
			(effects
				(font
					(size 1.27 0.9652)
					(thickness 0.000001)
				)
				(justify left)
			)
		)
		(property "Device Type" "CAPC0058"
			(at -0.148158 1.7526 90)
			(unlocked yes)
			(layer "F.Fab")
			(hide yes)
			(effects
				(font
					(size 1.27 0.9652)
					(thickness 0.000001)
				)
				(justify left)
			)
		)
		(duplicate_pad_numbers_are_jumpers no)
		(fp_circle
			(center 0 0)
			(end 0.127 0)
			(stroke
				(width 0.2032)
				(type default)
			)
			(fill no)
			(layer "F.SilkS")
		)
		(fp_poly
			(pts
				(xy 0.7874 -1.6637) (xy -0.7874 -1.6637) (xy -0.7874 1.6637) (xy 0.7874 1.6637)
			)
			(stroke
				(width 0)
				(type default)
			)
			(fill no)
			(layer "F.CrtYd")
		)
		(fp_line
			(start -0.4064 -0.7874)
			(end 0.4064 -0.7874)
			(stroke
				(width 0.0254)
				(type default)
			)
			(layer "F.Fab")
		)
		(fp_line
			(start -0.4064 0.8128)
			(end -0.4064 -0.7874)
			(stroke
				(width 0.0254)
				(type default)
			)
			(layer "F.Fab")
		)
		(fp_line
			(start 0.4064 -0.7874)
			(end 0.4064 0.8128)
			(stroke
				(width 0.0254)
				(type default)
			)
			(layer "F.Fab")
		)
		(fp_line
			(start 0.4064 0.8128)
			(end -0.4064 0.8128)
			(stroke
				(width 0.0254)
				(type default)
			)
			(layer "F.Fab")
		)
		(pad "1" smd rect
			(at 0 -0.8001)
			(size 0.8636 0.9652)
			(layers "F.Cu" "F.Mask" "F.Paste")
			(net "VDD_5.0V")
		)
		(pad "2" smd rect
			(at 0 0.8001)
			(size 0.8636 0.9652)
			(layers "F.Cu" "F.Mask" "F.Paste")
			(net "GND")
		)
		(zone
			(layer "F.Cu")
			(hatch none 0.5)
			(connect_pads
				(clearance 0)
			)
			(min_thickness 0.25)
			(keepout
				(tracks not_allowed)
				(vias allowed)
				(pads allowed)
				(copperpour not_allowed)
				(footprints allowed)
			)
			(placement
				(enabled no)
				(sheetname "")
			)
			(fill
				(thermal_gap 0.5)
				(thermal_bridge_width 0.5)
				(island_removal_mode 0)
			)
			(polygon
				(pts
					(xy 9.9695 37.338) (xy 10.0965 37.338) (xy 10.0965 37.846) (xy 9.9695 37.846)
				)
			)
		)
	)
	(footprint ""
		(layer "F.Cu")
		(at 78.359 26.924)
		(property "Reference" "R225"
			(at 0 0 0)
			(layer "F.SilkS")
			(hide yes)
			(effects
				(font
					(size 1.27 1.27)
				)
			)
		)
		(property "Value" "39.0"
			(at -0.148158 1.3462 90)
			(unlocked yes)
			(layer "F.Fab")
			(hide yes)
			(effects
				(font
					(size 1.27 0.9652)
					(thickness 0.000001)
				)
				(justify left)
			)
		)
		(property "Device Type" "REST0108"
			(at -0.148158 1.3462 90)
			(unlocked yes)
			(layer "F.Fab")
			(hide yes)
			(effects
				(font
					(size 1.27 0.9652)
					(thickness 0.000001)
				)
				(justify left)
			)
		)
		(duplicate_pad_numbers_are_jumpers no)
		(fp_poly
			(pts
				(xy 0.635 1.0668) (xy 0.635 -1.0668) (xy -0.635 -1.0668) (xy -0.635 1.0668)
			)
			(stroke
				(width 0)
				(type default)
			)
			(fill no)
			(layer "F.CrtYd")
		)
		(fp_line
			(start -0.254 -0.508)
			(end 0.254 -0.508)
			(stroke
				(width 0.0254)
				(type default)
			)
			(layer "F.Fab")
		)
		(fp_line
			(start -0.254 0.508)
			(end -0.254 -0.508)
			(stroke
				(width 0.0254)
				(type default)
			)
			(layer "F.Fab")
		)
		(fp_line
			(start 0.254 -0.508)
			(end 0.254 0.508)
			(stroke
				(width 0.0254)
				(type default)
			)
			(layer "F.Fab")
		)
		(fp_line
			(start 0.254 0.508)
			(end -0.254 0.508)
			(stroke
				(width 0.0254)
				(type default)
			)
			(layer "F.Fab")
		)
		(pad "1" smd rect
			(at 0 -0.4191)
			(size 0.508 0.5334)
			(layers "F.Cu" "F.Mask" "F.Paste")
			(net "DDR0_32A_RAS_L")
		)
		(pad "2" smd rect
			(at 0 0.4191)
			(size 0.508 0.5334)
			(layers "F.Cu" "F.Mask" "F.Paste")
			(net "DDR_VTT")
		)
		(zone
			(layer "F.Cu")
			(hatch none 0.5)
			(connect_pads
				(clearance 0)
			)
			(min_thickness 0.25)
			(keepout
				(tracks not_allowed)
				(vias allowed)
				(pads allowed)
				(copperpour not_allowed)
				(footprints allowed)
			)
			(placement
				(enabled no)
				(sheetname "")
			)
			(fill
				(thermal_gap 0.5)
				(thermal_bridge_width 0.5)
				(island_removal_mode 0)
			)
			(polygon
				(pts
					(xy 78.3844 26.8986) (xy 78.3844 26.9494) (xy 78.3336 26.9494) (xy 78.3336 26.8986)
				)
			)
		)
	)
	(footprint ""
		(layer "F.Cu")
		(at 39.243 37.4015 90)
		(property "Reference" "C143"
			(at -0.47117 2.032 0)
			(unlocked yes)
			(layer "F.SilkS")
			(effects
				(font
					(size 0.7874 0.5842)
					(thickness 0.127)
				)
				(justify left)
			)
		)
		(property "Value" "4.7UF"
			(at -0.783158 2.3876 180)
			(unlocked yes)
			(layer "F.Fab")
			(hide yes)
			(effects
				(font
					(size 1.27 0.9652)
					(thickness 0.000001)
				)
				(justify left)
			)
		)
		(property "Device Type" "CAPC0029"
			(at -0.783158 2.3876 180)
			(unlocked yes)
			(layer "F.Fab")
			(hide yes)
			(effects
				(font
					(size 1.27 0.9652)
					(thickness 0.000001)
				)
				(justify left)
			)
		)
		(duplicate_pad_numbers_are_jumpers no)
		(fp_arc
			(start 0.156058 -0.0889)
			(mid 0.173617 -0.045983)
			(end 0.179603 0)
			(stroke
				(width 0.2032)
				(type default)
			)
			(layer "F.SilkS")
		)
		(fp_arc
			(start 0.179603 0)
			(mid 0.173617 0.045983)
			(end 0.156058 0.0889)
			(stroke
				(width 0.2032)
				(type default)
			)
			(layer "F.SilkS")
		)
		(fp_arc
			(start -0.179603 0)
			(mid -0.173617 -0.045983)
			(end -0.156058 -0.0889)
			(stroke
				(width 0.2032)
				(type default)
			)
			(layer "F.SilkS")
		)
		(fp_arc
			(start -0.156058 0.0889)
			(mid -0.173617 0.045983)
			(end -0.179603 0)
			(stroke
				(width 0.2032)
				(type default)
			)
			(layer "F.SilkS")
		)
		(fp_circle
			(center 0 0)
			(end 0 0.179603)
			(stroke
				(width 0.2032)
				(type default)
			)
			(fill no)
			(layer "F.SilkS")
		)
		(fp_poly
			(pts
				(xy -1.2192 2.3495) (xy 1.2192 2.3495) (xy 1.2192 -2.3495) (xy -1.2192 -2.3495)
			)
			(stroke
				(width 0)
				(type default)
			)
			(fill no)
			(layer "F.CrtYd")
		)
		(fp_line
			(start 0.762 -1.143)
			(end 0.762 1.143)
			(stroke
				(width 0.0254)
				(type default)
			)
			(layer "F.Fab")
		)
		(fp_line
			(start -0.762 -1.143)
			(end 0.762 -1.143)
			(stroke
				(width 0.0254)
				(type default)
			)
			(layer "F.Fab")
		)
		(fp_line
			(start 0.762 1.143)
			(end -0.762 1.143)
			(stroke
				(width 0.0254)
				(type default)
			)
			(layer "F.Fab")
		)
		(fp_line
			(start -0.762 1.143)
			(end -0.762 -1.143)
			(stroke
				(width 0.0254)
				(type default)
			)
			(layer "F.Fab")
		)
		(pad "1" smd rect
			(at 0 -1.143 90)
			(size 1.4224 1.397)
			(layers "F.Cu" "F.Mask" "F.Paste")
			(net "10N2370")
		)
		(pad "2" smd rect
			(at 0 1.143 90)
			(size 1.4224 1.397)
			(layers "F.Cu" "F.Mask" "F.Paste")
			(net "GND")
		)
		(zone
			(layer "F.Cu")
			(hatch none 0.5)
			(connect_pads
				(clearance 0)
			)
			(min_thickness 0.25)
			(keepout
				(tracks allowed)
				(vias not_allowed)
				(pads allowed)
				(copperpour not_allowed)
				(footprints allowed)
			)
			(placement
				(enabled no)
				(sheetname "")
			)
			(fill
				(thermal_gap 0.5)
				(thermal_bridge_width 0.5)
				(island_removal_mode 0)
			)
			(polygon
				(pts
					(xy 38.862 38.0365) (xy 38.862 36.7665) (xy 39.624 36.7665) (xy 39.624 38.0365)
				)
			)
		)
	)
	(footprint ""
		(layer "F.Cu")
		(at 59.3725 46.609)
		(property "Reference" "R411"
			(at -0.67183 0.508 90)
			(unlocked yes)
			(layer "F.SilkS")
			(effects
				(font
					(size 0.7874 0.5842)
					(thickness 0.127)
				)
				(justify left)
			)
		)
		(property "Value" "1.0K"
			(at -0.148158 1.3462 90)
			(unlocked yes)
			(layer "F.Fab")
			(hide yes)
			(effects
				(font
					(size 1.27 0.9652)
					(thickness 0.000001)
				)
				(justify left)
			)
		)
		(property "Device Type" "REST0025"
			(at -0.148158 1.3462 90)
			(unlocked yes)
			(layer "F.Fab")
			(hide yes)
			(effects
				(font
					(size 1.27 0.9652)
					(thickness 0.000001)
				)
				(justify left)
			)
		)
		(duplicate_pad_numbers_are_jumpers no)
		(fp_poly
			(pts
				(xy 0.635 1.0668) (xy 0.635 -1.0668) (xy -0.635 -1.0668) (xy -0.635 1.0668)
			)
			(stroke
				(width 0)
				(type default)
			)
			(fill no)
			(layer "F.CrtYd")
		)
		(fp_line
			(start -0.254 -0.508)
			(end 0.254 -0.508)
			(stroke
				(width 0.0254)
				(type default)
			)
			(layer "F.Fab")
		)
		(fp_line
			(start -0.254 0.508)
			(end -0.254 -0.508)
			(stroke
				(width 0.0254)
				(type default)
			)
			(layer "F.Fab")
		)
		(fp_line
			(start 0.254 -0.508)
			(end 0.254 0.508)
			(stroke
				(width 0.0254)
				(type default)
			)
			(layer "F.Fab")
		)
		(fp_line
			(start 0.254 0.508)
			(end -0.254 0.508)
			(stroke
				(width 0.0254)
				(type default)
			)
			(layer "F.Fab")
		)
		(pad "1" smd rect
			(at 0 -0.4191)
			(size 0.508 0.5334)
			(layers "F.Cu" "F.Mask" "F.Paste")
			(net "GND")
		)
		(pad "2" smd rect
			(at 0 0.4191)
			(size 0.508 0.5334)
			(layers "F.Cu" "F.Mask" "F.Paste")
			(net "VDD_5.0V")
		)
		(zone
			(layer "F.Cu")
			(hatch none 0.5)
			(connect_pads
				(clearance 0)
			)
			(min_thickness 0.25)
			(keepout
				(tracks not_allowed)
				(vias allowed)
				(pads allowed)
				(copperpour not_allowed)
				(footprints allowed)
			)
			(placement
				(enabled no)
				(sheetname "")
			)
			(fill
				(thermal_gap 0.5)
				(thermal_bridge_width 0.5)
				(island_removal_mode 0)
			)
			(polygon
				(pts
					(xy 59.3979 46.5836) (xy 59.3979 46.6344) (xy 59.3471 46.6344) (xy 59.3471 46.5836)
				)
			)
		)
	)
	(footprint ""
		(layer "F.Cu")
		(at 83.82 50.419 90)
		(property "Reference" "C130"
			(at -0.02667 0.889 0)
			(unlocked yes)
			(layer "F.SilkS")
			(effects
				(font
					(size 0.7874 0.5842)
					(thickness 0.127)
				)
				(justify left)
			)
		)
		(property "Value" "0.1UF"
			(at -0.091846 0.2921 180)
			(unlocked yes)
			(layer "F.Fab")
			(hide yes)
			(effects
				(font
					(size 0.7874 0.5842)
					(thickness 0.2032)
				)
				(justify left)
			)
		)
		(property "Device Type" "CAPC0073"
			(at -0.091846 0.2921 180)
			(unlocked yes)
			(layer "F.Fab")
			(hide yes)
			(effects
				(font
					(size 0.7874 0.5842)
					(thickness 0.2032)
				)
				(justify left)
			)
		)
		(duplicate_pad_numbers_are_jumpers no)
		(fp_poly
			(pts
				(xy 0.635 1.0668) (xy 0.635 -1.0668) (xy -0.635 -1.0668) (xy -0.635 1.0668)
			)
			(stroke
				(width 0)
				(type default)
			)
			(fill no)
			(layer "F.CrtYd")
		)
		(fp_line
			(start 0.254 -0.508)
			(end 0.254 0.508)
			(stroke
				(width 0.0254)
				(type default)
			)
			(layer "F.Fab")
		)
		(fp_line
			(start -0.254 -0.508)
			(end 0.254 -0.508)
			(stroke
				(width 0.0254)
				(type default)
			)
			(layer "F.Fab")
		)
		(fp_line
			(start 0.254 0.508)
			(end -0.254 0.508)
			(stroke
				(width 0.0254)
				(type default)
			)
			(layer "F.Fab")
		)
		(fp_line
			(start -0.254 0.508)
			(end -0.254 -0.508)
			(stroke
				(width 0.0254)
				(type default)
			)
			(layer "F.Fab")
		)
		(pad "1" smd rect
			(at 0 -0.4191 90)
			(size 0.508 0.5334)
			(layers "F.Cu" "F.Mask" "F.Paste")
			(net "EXT_12.0V")
		)
		(pad "2" smd rect
			(at 0 0.4191 90)
			(size 0.508 0.5334)
			(layers "F.Cu" "F.Mask" "F.Paste")
			(net "GND")
		)
		(zone
			(layer "F.Cu")
			(hatch none 0.5)
			(connect_pads
				(clearance 0)
			)
			(min_thickness 0.25)
			(keepout
				(tracks not_allowed)
				(vias allowed)
				(pads allowed)
				(copperpour not_allowed)
				(footprints allowed)
			)
			(placement
				(enabled no)
				(sheetname "")
			)
			(fill
				(thermal_gap 0.5)
				(thermal_bridge_width 0.5)
				(island_removal_mode 0)
			)
			(polygon
				(pts
					(xy 83.7946 50.3936) (xy 83.8454 50.3936) (xy 83.8454 50.4444) (xy 83.7946 50.4444)
				)
			)
		)
	)
	(footprint ""
		(layer "F.Cu")
		(at 25.9588 35.941 -90)
		(property "Reference" "R86"
			(at 0 0 270)
			(layer "F.SilkS")
			(hide yes)
			(effects
				(font
					(size 1.27 1.27)
				)
			)
		)
		(property "Value" "4.75K"
			(at -0.148158 1.3462 0)
			(unlocked yes)
			(layer "F.Fab")
			(hide yes)
			(effects
				(font
					(size 1.27 0.9652)
					(thickness 0.000001)
				)
				(justify left)
			)
		)
		(property "Device Type" "REST4024"
			(at -0.148158 1.3462 0)
			(unlocked yes)
			(layer "F.Fab")
			(hide yes)
			(effects
				(font
					(size 1.27 0.9652)
					(thickness 0.000001)
				)
				(justify left)
			)
		)
		(duplicate_pad_numbers_are_jumpers no)
		(fp_poly
			(pts
				(xy 0.635 1.0668) (xy 0.635 -1.0668) (xy -0.635 -1.0668) (xy -0.635 1.0668)
			)
			(stroke
				(width 0)
				(type default)
			)
			(fill no)
			(layer "F.CrtYd")
		)
		(fp_line
			(start -0.254 0.508)
			(end -0.254 -0.508)
			(stroke
				(width 0.0254)
				(type default)
			)
			(layer "F.Fab")
		)
		(fp_line
			(start 0.254 0.508)
			(end -0.254 0.508)
			(stroke
				(width 0.0254)
				(type default)
			)
			(layer "F.Fab")
		)
		(fp_line
			(start -0.254 -0.508)
			(end 0.254 -0.508)
			(stroke
				(width 0.0254)
				(type default)
			)
			(layer "F.Fab")
		)
		(fp_line
			(start 0.254 -0.508)
			(end 0.254 0.508)
			(stroke
				(width 0.0254)
				(type default)
			)
			(layer "F.Fab")
		)
		(pad "1" smd rect
			(at 0 -0.4191 270)
			(size 0.508 0.5334)
			(layers "F.Cu" "F.Mask" "F.Paste")
			(net "CORE_FB_ALERT_L")
		)
		(pad "2" smd rect
			(at 0 0.4191 270)
			(size 0.508 0.5334)
			(layers "F.Cu" "F.Mask" "F.Paste")
			(net "EXT_3.3V")
		)
		(zone
			(layer "F.Cu")
			(hatch none 0.5)
			(connect_pads
				(clearance 0)
			)
			(min_thickness 0.25)
			(keepout
				(tracks not_allowed)
				(vias allowed)
				(pads allowed)
				(copperpour not_allowed)
				(footprints allowed)
			)
			(placement
				(enabled no)
				(sheetname "")
			)
			(fill
				(thermal_gap 0.5)
				(thermal_bridge_width 0.5)
				(island_removal_mode 0)
			)
			(polygon
				(pts
					(xy 25.9842 35.9664) (xy 25.9334 35.9664) (xy 25.9334 35.9156) (xy 25.9842 35.9156)
				)
			)
		)
	)
	(footprint ""
		(layer "F.Cu")
		(at 32.258 43.942)
		(property "Reference" "R287"
			(at 0 0 0)
			(layer "F.SilkS")
			(hide yes)
			(effects
				(font
					(size 1.27 1.27)
				)
			)
		)
		(property "Value" "100"
			(at -0.148158 1.3462 90)
			(unlocked yes)
			(layer "F.Fab")
			(hide yes)
			(effects
				(font
					(size 1.27 0.9652)
					(thickness 0.000001)
				)
				(justify left)
			)
		)
		(property "Device Type" "REST4030"
			(at -0.148158 1.3462 90)
			(unlocked yes)
			(layer "F.Fab")
			(hide yes)
			(effects
				(font
					(size 1.27 0.9652)
					(thickness 0.000001)
				)
				(justify left)
			)
		)
		(duplicate_pad_numbers_are_jumpers no)
		(fp_poly
			(pts
				(xy 0.635 1.0668) (xy 0.635 -1.0668) (xy -0.635 -1.0668) (xy -0.635 1.0668)
			)
			(stroke
				(width 0)
				(type default)
			)
			(fill no)
			(layer "F.CrtYd")
		)
		(fp_line
			(start -0.254 -0.508)
			(end 0.254 -0.508)
			(stroke
				(width 0.0254)
				(type default)
			)
			(layer "F.Fab")
		)
		(fp_line
			(start -0.254 0.508)
			(end -0.254 -0.508)
			(stroke
				(width 0.0254)
				(type default)
			)
			(layer "F.Fab")
		)
		(fp_line
			(start 0.254 -0.508)
			(end 0.254 0.508)
			(stroke
				(width 0.0254)
				(type default)
			)
			(layer "F.Fab")
		)
		(fp_line
			(start 0.254 0.508)
			(end -0.254 0.508)
			(stroke
				(width 0.0254)
				(type default)
			)
			(layer "F.Fab")
		)
		(pad "1" smd rect
			(at 0 -0.4191)
			(size 0.508 0.5334)
			(layers "F.Cu" "F.Mask" "F.Paste")
			(net "10N2535")
		)
		(pad "2" smd rect
			(at 0 0.4191)
			(size 0.508 0.5334)
			(layers "F.Cu" "F.Mask" "F.Paste")
			(net "10N2410")
		)
		(zone
			(layer "F.Cu")
			(hatch none 0.5)
			(connect_pads
				(clearance 0)
			)
			(min_thickness 0.25)
			(keepout
				(tracks not_allowed)
				(vias allowed)
				(pads allowed)
				(copperpour not_allowed)
				(footprints allowed)
			)
			(placement
				(enabled no)
				(sheetname "")
			)
			(fill
				(thermal_gap 0.5)
				(thermal_bridge_width 0.5)
				(island_removal_mode 0)
			)
			(polygon
				(pts
					(xy 32.2834 43.9166) (xy 32.2834 43.9674) (xy 32.2326 43.9674) (xy 32.2326 43.9166)
				)
			)
		)
	)
	(footprint ""
		(layer "F.Cu")
		(at 14.351 1.397)
		(property "Reference" "R389"
			(at -0.86233 -1.016 90)
			(unlocked yes)
			(layer "F.SilkS")
			(effects
				(font
					(size 0.7874 0.5842)
					(thickness 0.127)
				)
				(justify left)
			)
		)
		(property "Value" "0"
			(at -0.148158 1.3462 90)
			(unlocked yes)
			(layer "F.Fab")
			(hide yes)
			(effects
				(font
					(size 1.27 0.9652)
					(thickness 0.000001)
				)
				(justify left)
			)
		)
		(property "Device Type" "REST1111"
			(at -0.148158 1.3462 90)
			(unlocked yes)
			(layer "F.Fab")
			(hide yes)
			(effects
				(font
					(size 1.27 0.9652)
					(thickness 0.000001)
				)
				(justify left)
			)
		)
		(duplicate_pad_numbers_are_jumpers no)
		(fp_poly
			(pts
				(xy 0.635 1.0668) (xy 0.635 -1.0668) (xy -0.635 -1.0668) (xy -0.635 1.0668)
			)
			(stroke
				(width 0)
				(type default)
			)
			(fill no)
			(layer "F.CrtYd")
		)
		(fp_line
			(start -0.254 -0.508)
			(end 0.254 -0.508)
			(stroke
				(width 0.0254)
				(type default)
			)
			(layer "F.Fab")
		)
		(fp_line
			(start -0.254 0.508)
			(end -0.254 -0.508)
			(stroke
				(width 0.0254)
				(type default)
			)
			(layer "F.Fab")
		)
		(fp_line
			(start 0.254 -0.508)
			(end 0.254 0.508)
			(stroke
				(width 0.0254)
				(type default)
			)
			(layer "F.Fab")
		)
		(fp_line
			(start 0.254 0.508)
			(end -0.254 0.508)
			(stroke
				(width 0.0254)
				(type default)
			)
			(layer "F.Fab")
		)
		(pad "1" smd rect
			(at 0 -0.4191)
			(size 0.508 0.5334)
			(layers "F.Cu" "F.Mask" "F.Paste")
			(net "NFP_SMBUS_SCL")
		)
		(pad "2" smd rect
			(at 0 0.4191)
			(size 0.508 0.5334)
			(layers "F.Cu" "F.Mask" "F.Paste")
			(net "SMBUS_SCL")
		)
		(zone
			(layer "F.Cu")
			(hatch none 0.5)
			(connect_pads
				(clearance 0)
			)
			(min_thickness 0.25)
			(keepout
				(tracks not_allowed)
				(vias allowed)
				(pads allowed)
				(copperpour not_allowed)
				(footprints allowed)
			)
			(placement
				(enabled no)
				(sheetname "")
			)
			(fill
				(thermal_gap 0.5)
				(thermal_bridge_width 0.5)
				(island_removal_mode 0)
			)
			(polygon
				(pts
					(xy 14.3764 1.3716) (xy 14.3764 1.4224) (xy 14.3256 1.4224) (xy 14.3256 1.3716)
				)
			)
		)
	)
	(footprint ""
		(layer "F.Cu")
		(at 26.543 46.99)
		(property "Reference" "TP59"
			(at 1.55067 2.54 90)
			(unlocked yes)
			(layer "F.SilkS")
			(effects
				(font
					(size 0.7874 0.5842)
					(thickness 0.127)
				)
				(justify left)
			)
		)
		(property "Value" "*"
			(at -0.4826 -0.14732 0)
			(unlocked yes)
			(layer "F.Fab")
			(hide yes)
			(effects
				(font
					(size 1.27 0.9652)
					(thickness 0.000001)
				)
				(justify left)
			)
		)
		(property "Device Type" "TP_SMALL"
			(at -0.4826 -0.14732 0)
			(unlocked yes)
			(layer "F.Fab")
			(hide yes)
			(effects
				(font
					(size 1.27 0.9652)
					(thickness 0.000001)
				)
				(justify left)
			)
		)
		(duplicate_pad_numbers_are_jumpers no)
		(fp_line
			(start -0.8636 -0.8636)
			(end -0.8636 0.8636)
			(stroke
				(width 0.1524)
				(type default)
			)
			(layer "F.SilkS")
		)
		(fp_line
			(start -0.8636 0.8636)
			(end 0.8636 0.8636)
			(stroke
				(width 0.1524)
				(type default)
			)
			(layer "F.SilkS")
		)
		(fp_line
			(start 0.8636 -0.8636)
			(end -0.8636 -0.8636)
			(stroke
				(width 0.1524)
				(type default)
			)
			(layer "F.SilkS")
		)
		(fp_line
			(start 0.8636 0.8636)
			(end 0.8636 -0.8636)
			(stroke
				(width 0.1524)
				(type default)
			)
			(layer "F.SilkS")
		)
		(fp_poly
			(pts
				(xy -0.635 -0.635) (xy -0.635 0.635) (xy 0.635 0.635) (xy 0.635 -0.635)
			)
			(stroke
				(width 0)
				(type default)
			)
			(fill no)
			(layer "F.CrtYd")
		)
		(pad "1" smd rect
			(at 0 0)
			(size 1.27 1.27)
			(layers "F.Cu" "F.Mask" "F.Paste")
			(net "VDD_CORE_PGOOD")
		)
	)
	(footprint ""
		(layer "F.Cu")
		(at 66.802 56.134)
		(property "Reference" "TP67"
			(at 1.397 0.66167 0)
			(unlocked yes)
			(layer "F.SilkS")
			(effects
				(font
					(size 0.7874 0.5842)
					(thickness 0.127)
				)
				(justify left)
			)
		)
		(property "Value" "*"
			(at -0.4826 -0.14732 0)
			(unlocked yes)
			(layer "F.Fab")
			(hide yes)
			(effects
				(font
					(size 1.27 0.9652)
					(thickness 0.000001)
				)
				(justify left)
			)
		)
		(property "Device Type" "TP_SMALL"
			(at -0.4826 -0.14732 0)
			(unlocked yes)
			(layer "F.Fab")
			(hide yes)
			(effects
				(font
					(size 1.27 0.9652)
					(thickness 0.000001)
				)
				(justify left)
			)
		)
		(duplicate_pad_numbers_are_jumpers no)
		(fp_line
			(start -0.8636 -0.8636)
			(end -0.8636 0.8636)
			(stroke
				(width 0.1524)
				(type default)
			)
			(layer "F.SilkS")
		)
		(fp_line
			(start -0.8636 0.8636)
			(end 0.8636 0.8636)
			(stroke
				(width 0.1524)
				(type default)
			)
			(layer "F.SilkS")
		)
		(fp_line
			(start 0.8636 -0.8636)
			(end -0.8636 -0.8636)
			(stroke
				(width 0.1524)
				(type default)
			)
			(layer "F.SilkS")
		)
		(fp_line
			(start 0.8636 0.8636)
			(end 0.8636 -0.8636)
			(stroke
				(width 0.1524)
				(type default)
			)
			(layer "F.SilkS")
		)
		(fp_poly
			(pts
				(xy -0.635 -0.635) (xy -0.635 0.635) (xy 0.635 0.635) (xy 0.635 -0.635)
			)
			(stroke
				(width 0)
				(type default)
			)
			(fill no)
			(layer "F.CrtYd")
		)
		(pad "1" smd rect
			(at 0 0)
			(size 1.27 1.27)
			(layers "F.Cu" "F.Mask" "F.Paste")
			(net "VDD_5.0V_EN")
		)
	)
	(footprint ""
		(layer "F.Cu")
		(at 81.407 37.973 180)
		(property "Reference" "R106"
			(at 0 0 180)
			(layer "F.SilkS")
			(hide yes)
			(effects
				(font
					(size 1.27 1.27)
				)
			)
		)
		(property "Value" "4.75K"
			(at -0.148158 1.3462 270)
			(unlocked yes)
			(layer "F.Fab")
			(hide yes)
			(effects
				(font
					(size 1.27 0.9652)
					(thickness 0.000001)
				)
				(justify left)
			)
		)
		(property "Device Type" "REST4024"
			(at -0.148158 1.3462 270)
			(unlocked yes)
			(layer "F.Fab")
			(hide yes)
			(effects
				(font
					(size 1.27 0.9652)
					(thickness 0.000001)
				)
				(justify left)
			)
		)
		(duplicate_pad_numbers_are_jumpers no)
		(fp_poly
			(pts
				(xy 0.635 1.0668) (xy 0.635 -1.0668) (xy -0.635 -1.0668) (xy -0.635 1.0668)
			)
			(stroke
				(width 0)
				(type default)
			)
			(fill no)
			(layer "F.CrtYd")
		)
		(fp_line
			(start 0.254 0.508)
			(end -0.254 0.508)
			(stroke
				(width 0.0254)
				(type default)
			)
			(layer "F.Fab")
		)
		(fp_line
			(start 0.254 -0.508)
			(end 0.254 0.508)
			(stroke
				(width 0.0254)
				(type default)
			)
			(layer "F.Fab")
		)
		(fp_line
			(start -0.254 0.508)
			(end -0.254 -0.508)
			(stroke
				(width 0.0254)
				(type default)
			)
			(layer "F.Fab")
		)
		(fp_line
			(start -0.254 -0.508)
			(end 0.254 -0.508)
			(stroke
				(width 0.0254)
				(type default)
			)
			(layer "F.Fab")
		)
		(pad "1" smd rect
			(at 0 -0.4191 180)
			(size 0.508 0.5334)
			(layers "F.Cu" "F.Mask" "F.Paste")
			(net "VDDQ_VTT_PGOOD")
		)
		(pad "2" smd rect
			(at 0 0.4191 180)
			(size 0.508 0.5334)
			(layers "F.Cu" "F.Mask" "F.Paste")
			(net "EXT_3.3V")
		)
		(zone
			(layer "F.Cu")
			(hatch none 0.5)
			(connect_pads
				(clearance 0)
			)
			(min_thickness 0.25)
			(keepout
				(tracks not_allowed)
				(vias allowed)
				(pads allowed)
				(copperpour not_allowed)
				(footprints allowed)
			)
			(placement
				(enabled no)
				(sheetname "")
			)
			(fill
				(thermal_gap 0.5)
				(thermal_bridge_width 0.5)
				(island_removal_mode 0)
			)
			(polygon
				(pts
					(xy 81.3816 37.9984) (xy 81.3816 37.9476) (xy 81.4324 37.9476) (xy 81.4324 37.9984)
				)
			)
		)
	)
	(footprint ""
		(layer "F.Cu")
		(at 7.2898 2.6416 180)
		(property "Reference" "DS1"
			(at 2.13233 1.143 90)
			(unlocked yes)
			(layer "F.SilkS")
			(effects
				(font
					(size 0.7874 0.5842)
					(thickness 0.127)
				)
				(justify left)
			)
		)
		(property "Value" "*"
			(at -0.2921 0.670154 180)
			(unlocked yes)
			(layer "F.Fab")
			(hide yes)
			(effects
				(font
					(size 0.7874 0.5842)
					(thickness 0.2032)
				)
				(justify left)
			)
		)
		(property "Device Type" "LEDS0007"
			(at -0.2921 0.670154 180)
			(unlocked yes)
			(layer "F.Fab")
			(hide yes)
			(effects
				(font
					(size 0.7874 0.5842)
					(thickness 0.2032)
				)
				(justify left)
			)
		)
		(duplicate_pad_numbers_are_jumpers no)
		(fp_line
			(start 2.413 0.762)
			(end 2.413 -0.762)
			(stroke
				(width 0.1524)
				(type default)
			)
			(layer "F.SilkS")
		)
		(fp_line
			(start 2.413 -0.762)
			(end 0.762 -0.762)
			(stroke
				(width 0.1524)
				(type default)
			)
			(layer "F.SilkS")
		)
		(fp_line
			(start 1.397 1.651)
			(end 1.397 0.762)
			(stroke
				(width 0.1524)
				(type default)
			)
			(layer "F.SilkS")
		)
		(fp_line
			(start 1.397 0.762)
			(end 2.413 0.762)
			(stroke
				(width 0.1524)
				(type default)
			)
			(layer "F.SilkS")
		)
		(fp_line
			(start 1.27 1.651)
			(end 1.397 1.651)
			(stroke
				(width 0.1524)
				(type default)
			)
			(layer "F.SilkS")
		)
		(fp_line
			(start 0.762 -0.762)
			(end 0.762 -1.143)
			(stroke
				(width 0.1524)
				(type default)
			)
			(layer "F.SilkS")
		)
		(fp_line
			(start 0.762 -1.143)
			(end -0.762 -1.143)
			(stroke
				(width 0.1524)
				(type default)
			)
			(layer "F.SilkS")
		)
		(fp_line
			(start -0.762 -0.762)
			(end -2.413 -0.762)
			(stroke
				(width 0.1524)
				(type default)
			)
			(layer "F.SilkS")
		)
		(fp_line
			(start -0.762 -0.762)
			(end -2.413 -0.762)
			(stroke
				(width 0.1524)
				(type default)
			)
			(layer "F.SilkS")
		)
		(fp_line
			(start -0.762 -0.889)
			(end -0.762 -0.762)
			(stroke
				(width 0.1524)
				(type default)
			)
			(layer "F.SilkS")
		)
		(fp_line
			(start -0.762 -1.143)
			(end -0.762 -0.762)
			(stroke
				(width 0.1524)
				(type default)
			)
			(layer "F.SilkS")
		)
		(fp_line
			(start -1.397 1.651)
			(end -1.27 1.651)
			(stroke
				(width 0.1524)
				(type default)
			)
			(layer "F.SilkS")
		)
		(fp_line
			(start -1.397 0.889)
			(end -1.397 0.762)
			(stroke
				(width 0.1524)
				(type default)
			)
			(layer "F.SilkS")
		)
		(fp_line
			(start -1.397 0.7747)
			(end -1.397 1.651)
			(stroke
				(width 0.1524)
				(type default)
			)
			(layer "F.SilkS")
		)
		(fp_line
			(start -1.397 0.762)
			(end -1.397 1.651)
			(stroke
				(width 0.1524)
				(type default)
			)
			(layer "F.SilkS")
		)
		(fp_line
			(start -2.286 0.889)
			(end -1.397 0.889)
			(stroke
				(width 0.1524)
				(type default)
			)
			(layer "F.SilkS")
		)
		(fp_line
			(start -2.413 0.762)
			(end -1.397 0.762)
			(stroke
				(width 0.1524)
				(type default)
			)
			(layer "F.SilkS")
		)
		(fp_line
			(start -2.413 -0.762)
			(end -2.413 0.762)
			(stroke
				(width 0.1524)
				(type default)
			)
			(layer "F.SilkS")
		)
		(fp_line
			(start -2.413 -0.762)
			(end -2.54 -0.889)
			(stroke
				(width 0.1524)
				(type default)
			)
			(layer "F.SilkS")
		)
		(fp_line
			(start -2.54 0.889)
			(end -1.397 0.889)
			(stroke
				(width 0.1524)
				(type default)
			)
			(layer "F.SilkS")
		)
		(fp_line
			(start -2.54 -0.889)
			(end -0.762 -0.889)
			(stroke
				(width 0.1524)
				(type default)
			)
			(layer "F.SilkS")
		)
		(fp_line
			(start -2.54 -0.889)
			(end -0.8255 -0.889)
			(stroke
				(width 0.1524)
				(type default)
			)
			(layer "F.SilkS")
		)
		(fp_line
			(start -2.54 -0.889)
			(end -2.54 0.889)
			(stroke
				(width 0.1524)
				(type default)
			)
			(layer "F.SilkS")
		)
		(fp_arc
			(start 1.27 1.651)
			(mid 0.898026 2.549026)
			(end 0 2.921)
			(stroke
				(width 0.1524)
				(type default)
			)
			(layer "F.SilkS")
		)
		(fp_arc
			(start 1.257986 1.825269)
			(mid 0.834139 2.608659)
			(end 0 2.921)
			(stroke
				(width 0.1524)
				(type default)
			)
			(layer "F.SilkS")
		)
		(fp_arc
			(start 0 2.921)
			(mid -0.898026 2.549026)
			(end -1.27 1.651)
			(stroke
				(width 0.1524)
				(type default)
			)
			(layer "F.SilkS")
		)
		(fp_poly
			(pts
				(arc
					(start 1.502689 1.905)
					(mid 1.396411 2.261432)
					(end 1.206957 2.581504)
				)
				(xy -0.889 2.581504) (xy -0.889 1.651) (xy -1.016 1.524) (xy -1.143 1.524) (xy -1.143 1.397) (xy -2.032 0.508)
				(xy -2.350872 0.508) (xy -2.350872 -1.016) (xy -1.016 -1.016) (xy -1.016 -1.397) (xy 1.016 -1.397)
				(xy 1.016 -1.016) (xy 2.667 -1.016) (xy 2.667 1.016) (xy 1.651 1.016) (xy 1.651 1.905)
			)
			(stroke
				(width 0)
				(type default)
			)
			(fill no)
			(layer "F.CrtYd")
		)
		(fp_line
			(start 1.4986 0.254)
			(end 1.4986 -0.254)
			(stroke
				(width 0.1524)
				(type default)
			)
			(layer "F.Fab")
		)
		(fp_line
			(start 1.4986 -0.254)
			(end -1.4986 -0.254)
			(stroke
				(width 0.1524)
				(type default)
			)
			(layer "F.Fab")
		)
		(fp_line
			(start 1.1049 1.3462)
			(end 1.1049 0.254)
			(stroke
				(width 0.1524)
				(type default)
			)
			(layer "F.Fab")
		)
		(fp_line
			(start 1.1049 0.254)
			(end -1.1049 0.254)
			(stroke
				(width 0.1524)
				(type default)
			)
			(layer "F.Fab")
		)
		(fp_line
			(start 0.9525 1.6002)
			(end 0.9525 1.3462)
			(stroke
				(width 0.1524)
				(type default)
			)
			(layer "F.Fab")
		)
		(fp_line
			(start 0.9525 1.3462)
			(end -0.9525 1.3462)
			(stroke
				(width 0.1524)
				(type default)
			)
			(layer "F.Fab")
		)
		(fp_line
			(start -0.0127 2.54)
			(end 0.0127 2.54)
			(stroke
				(width 0.1524)
				(type default)
			)
			(layer "F.Fab")
		)
		(fp_line
			(start -0.9525 1.3462)
			(end -0.9525 1.6002)
			(stroke
				(width 0.1524)
				(type default)
			)
			(layer "F.Fab")
		)
		(fp_line
			(start -1.1049 1.3462)
			(end 1.1049 1.3462)
			(stroke
				(width 0.1524)
				(type default)
			)
			(layer "F.Fab")
		)
		(fp_line
			(start -1.1049 0.254)
			(end -1.1049 1.3462)
			(stroke
				(width 0.1524)
				(type default)
			)
			(layer "F.Fab")
		)
		(fp_line
			(start -1.4986 0.254)
			(end 1.4986 0.254)
			(stroke
				(width 0.1524)
				(type default)
			)
			(layer "F.Fab")
		)
		(fp_line
			(start -1.4986 -0.254)
			(end -1.4986 0.254)
			(stroke
				(width 0.1524)
				(type default)
			)
			(layer "F.Fab")
		)
		(fp_arc
			(start 0.9525 1.6002)
			(mid 0.677239 2.264739)
			(end 0.0127 2.54)
			(stroke
				(width 0.1524)
				(type default)
			)
			(layer "F.Fab")
		)
		(fp_arc
			(start -0.0127 2.54)
			(mid -0.677239 2.264739)
			(end -0.9525 1.6002)
			(stroke
				(width 0.1524)
				(type default)
			)
			(layer "F.Fab")
		)
		(fp_text user "A"
			(at 3.175 -0.53467 0)
			(unlocked yes)
			(layer "F.SilkS")
			(effects
				(font
					(size 0.7874 0.5842)
					(thickness 0.127)
				)
				(justify left)
			)
		)
		(fp_text user "C"
			(at -1.651 1.49733 0)
			(unlocked yes)
			(layer "F.SilkS")
			(effects
				(font
					(size 0.7874 0.5842)
					(thickness 0.127)
				)
				(justify left)
			)
		)
		(fp_text user "A"
			(at 1.905 -0.91567 0)
			(unlocked yes)
			(layer "F.Fab")
			(effects
				(font
					(size 0.7874 0.5842)
					(thickness 0.127)
				)
				(justify left)
			)
		)
		(fp_text user "C"
			(at -1.143 -0.91567 0)
			(unlocked yes)
			(layer "F.Fab")
			(effects
				(font
					(size 0.7874 0.5842)
					(thickness 0.127)
				)
				(justify left)
			)
		)
		(pad "1" smd rect
			(at 1.4986 0 180)
			(size 1.1938 0.889)
			(layers "F.Cu" "F.Mask" "F.Paste")
			(net "EXT_3.3V")
		)
		(pad "2" smd rect
			(at 0 -0.4445 180)
			(size 0.9906 0.889)
			(layers "F.Cu" "F.Mask" "F.Paste")
			(net "9N2141")
		)
		(pad "3" smd rect
			(at -1.4986 0 180)
			(size 1.1938 0.889)
			(layers "F.Cu" "F.Mask" "F.Paste")
			(net "9N2152")
		)
	)
	(footprint ""
		(layer "F.Cu")
		(at 66.548 46.609)
		(property "Reference" "R113"
			(at 0 0 0)
			(layer "F.SilkS")
			(hide yes)
			(effects
				(font
					(size 1.27 1.27)
				)
			)
		)
		(property "Value" "732"
			(at -0.148158 1.3462 90)
			(unlocked yes)
			(layer "F.Fab")
			(hide yes)
			(effects
				(font
					(size 1.27 0.9652)
					(thickness 0.000001)
				)
				(justify left)
			)
		)
		(property "Device Type" "REST0289"
			(at -0.148158 1.3462 90)
			(unlocked yes)
			(layer "F.Fab")
			(hide yes)
			(effects
				(font
					(size 1.27 0.9652)
					(thickness 0.000001)
				)
				(justify left)
			)
		)
		(duplicate_pad_numbers_are_jumpers no)
		(fp_poly
			(pts
				(xy 0.635 1.0668) (xy 0.635 -1.0668) (xy -0.635 -1.0668) (xy -0.635 1.0668)
			)
			(stroke
				(width 0)
				(type default)
			)
			(fill no)
			(layer "F.CrtYd")
		)
		(fp_line
			(start -0.254 -0.508)
			(end 0.254 -0.508)
			(stroke
				(width 0.0254)
				(type default)
			)
			(layer "F.Fab")
		)
		(fp_line
			(start -0.254 0.508)
			(end -0.254 -0.508)
			(stroke
				(width 0.0254)
				(type default)
			)
			(layer "F.Fab")
		)
		(fp_line
			(start 0.254 -0.508)
			(end 0.254 0.508)
			(stroke
				(width 0.0254)
				(type default)
			)
			(layer "F.Fab")
		)
		(fp_line
			(start 0.254 0.508)
			(end -0.254 0.508)
			(stroke
				(width 0.0254)
				(type default)
			)
			(layer "F.Fab")
		)
		(pad "1" smd rect
			(at 0 -0.4191)
			(size 0.508 0.5334)
			(layers "F.Cu" "F.Mask" "F.Paste")
			(net "GND")
		)
		(pad "2" smd rect
			(at 0 0.4191)
			(size 0.508 0.5334)
			(layers "F.Cu" "F.Mask" "F.Paste")
			(net "11N1953")
		)
		(zone
			(layer "F.Cu")
			(hatch none 0.5)
			(connect_pads
				(clearance 0)
			)
			(min_thickness 0.25)
			(keepout
				(tracks not_allowed)
				(vias allowed)
				(pads allowed)
				(copperpour not_allowed)
				(footprints allowed)
			)
			(placement
				(enabled no)
				(sheetname "")
			)
			(fill
				(thermal_gap 0.5)
				(thermal_bridge_width 0.5)
				(island_removal_mode 0)
			)
			(polygon
				(pts
					(xy 66.5734 46.5836) (xy 66.5734 46.6344) (xy 66.5226 46.6344) (xy 66.5226 46.5836)
				)
			)
		)
	)
	(footprint ""
		(layer "F.Cu")
		(at 75.438 11.557)
		(property "Reference" "R362"
			(at -0.73533 1.778 90)
			(unlocked yes)
			(layer "F.SilkS")
			(effects
				(font
					(size 0.7874 0.5842)
					(thickness 0.127)
				)
				(justify left)
			)
		)
		(property "Value" "100"
			(at -0.148158 1.3462 90)
			(unlocked yes)
			(layer "F.Fab")
			(hide yes)
			(effects
				(font
					(size 1.27 0.9652)
					(thickness 0.000001)
				)
				(justify left)
			)
		)
		(property "Device Type" "REST4030"
			(at -0.148158 1.3462 90)
			(unlocked yes)
			(layer "F.Fab")
			(hide yes)
			(effects
				(font
					(size 1.27 0.9652)
					(thickness 0.000001)
				)
				(justify left)
			)
		)
		(duplicate_pad_numbers_are_jumpers no)
		(fp_poly
			(pts
				(xy 0.635 1.0668) (xy 0.635 -1.0668) (xy -0.635 -1.0668) (xy -0.635 1.0668)
			)
			(stroke
				(width 0)
				(type default)
			)
			(fill no)
			(layer "F.CrtYd")
		)
		(fp_line
			(start -0.254 -0.508)
			(end 0.254 -0.508)
			(stroke
				(width 0.0254)
				(type default)
			)
			(layer "F.Fab")
		)
		(fp_line
			(start -0.254 0.508)
			(end -0.254 -0.508)
			(stroke
				(width 0.0254)
				(type default)
			)
			(layer "F.Fab")
		)
		(fp_line
			(start 0.254 -0.508)
			(end 0.254 0.508)
			(stroke
				(width 0.0254)
				(type default)
			)
			(layer "F.Fab")
		)
		(fp_line
			(start 0.254 0.508)
			(end -0.254 0.508)
			(stroke
				(width 0.0254)
				(type default)
			)
			(layer "F.Fab")
		)
		(pad "1" smd rect
			(at 0 -0.4191)
			(size 0.508 0.5334)
			(layers "F.Cu" "F.Mask" "F.Paste")
			(net "DDR0_32A_VREF1B")
		)
		(pad "2" smd rect
			(at 0 0.4191)
			(size 0.508 0.5334)
			(layers "F.Cu" "F.Mask" "F.Paste")
			(net "DDR_VDDQ")
		)
		(zone
			(layer "F.Cu")
			(hatch none 0.5)
			(connect_pads
				(clearance 0)
			)
			(min_thickness 0.25)
			(keepout
				(tracks not_allowed)
				(vias allowed)
				(pads allowed)
				(copperpour not_allowed)
				(footprints allowed)
			)
			(placement
				(enabled no)
				(sheetname "")
			)
			(fill
				(thermal_gap 0.5)
				(thermal_bridge_width 0.5)
				(island_removal_mode 0)
			)
			(polygon
				(pts
					(xy 75.4634 11.5316) (xy 75.4634 11.5824) (xy 75.4126 11.5824) (xy 75.4126 11.5316)
				)
			)
		)
	)
	(footprint ""
		(layer "F.Cu")
		(at 53.086 46.99 -90)
		(property "Reference" "C62"
			(at 1.29667 -0.254 0)
			(unlocked yes)
			(layer "F.SilkS")
			(effects
				(font
					(size 0.7874 0.5842)
					(thickness 0.127)
				)
				(justify left)
			)
		)
		(property "Value" "100UF"
			(at -0.78232 0.4826 0)
			(unlocked yes)
			(layer "F.Fab")
			(hide yes)
			(effects
				(font
					(size 1.27 0.9652)
					(thickness 0.000001)
				)
				(justify left)
			)
		)
		(property "Device Type" "CAPC0087"
			(at -0.78232 0.4826 0)
			(unlocked yes)
			(layer "F.Fab")
			(hide yes)
			(effects
				(font
					(size 1.27 0.9652)
					(thickness 0.000001)
				)
				(justify left)
			)
		)
		(duplicate_pad_numbers_are_jumpers no)
		(fp_circle
			(center 0 0)
			(end 0 -0.508)
			(stroke
				(width 0.2032)
				(type default)
			)
			(fill no)
			(layer "F.SilkS")
		)
		(fp_circle
			(center 0 0)
			(end 0 -0.508)
			(stroke
				(width 0.2032)
				(type default)
			)
			(fill no)
			(layer "F.SilkS")
		)
		(fp_poly
			(pts
				(xy -1.27 2.9464) (xy 1.27 2.9464) (xy 1.27 -2.9464) (xy -1.27 -2.9464)
			)
			(stroke
				(width 0)
				(type default)
			)
			(fill no)
			(layer "F.CrtYd")
		)
		(fp_line
			(start -1.016 2.794)
			(end -1.016 -2.794)
			(stroke
				(width 0.0254)
				(type default)
			)
			(layer "F.Fab")
		)
		(fp_line
			(start 1.016 2.794)
			(end -1.016 2.794)
			(stroke
				(width 0.0254)
				(type default)
			)
			(layer "F.Fab")
		)
		(fp_line
			(start -1.016 -2.794)
			(end 1.016 -2.794)
			(stroke
				(width 0.0254)
				(type default)
			)
			(layer "F.Fab")
		)
		(fp_line
			(start 1.016 -2.794)
			(end 1.016 2.794)
			(stroke
				(width 0.0254)
				(type default)
			)
			(layer "F.Fab")
		)
		(pad "1" smd rect
			(at 0 -1.6764 270)
			(size 1.524 1.524)
			(layers "F.Cu" "F.Mask" "F.Paste")
			(net "VDD_CORE")
		)
		(pad "2" smd rect
			(at 0 1.6764 270)
			(size 1.524 1.524)
			(layers "F.Cu" "F.Mask" "F.Paste")
			(net "GND")
		)
		(zone
			(layer "F.Cu")
			(hatch none 0.5)
			(connect_pads
				(clearance 0)
			)
			(min_thickness 0.25)
			(keepout
				(tracks allowed)
				(vias not_allowed)
				(pads allowed)
				(copperpour not_allowed)
				(footprints allowed)
			)
			(placement
				(enabled no)
				(sheetname "")
			)
			(fill
				(thermal_gap 0.5)
				(thermal_bridge_width 0.5)
				(island_removal_mode 0)
			)
			(polygon
				(pts
					(xy 51.4858 46.2026) (xy 51.4858 47.7774) (xy 54.6862 47.7774) (xy 54.6862 46.2026)
				)
			)
		)
		(zone
			(layer "F.Cu")
			(hatch none 0.5)
			(connect_pads
				(clearance 0)
			)
			(min_thickness 0.25)
			(keepout
				(tracks not_allowed)
				(vias allowed)
				(pads allowed)
				(copperpour not_allowed)
				(footprints allowed)
			)
			(placement
				(enabled no)
				(sheetname "")
			)
			(fill
				(thermal_gap 0.5)
				(thermal_bridge_width 0.5)
				(island_removal_mode 0)
			)
			(polygon
				(pts
					(xy 52.3494 46.2026) (xy 52.3494 47.7774) (xy 52.197 47.7774) (xy 52.197 46.2026)
				)
			)
		)
		(zone
			(layer "F.Cu")
			(hatch none 0.5)
			(connect_pads
				(clearance 0)
			)
			(min_thickness 0.25)
			(keepout
				(tracks not_allowed)
				(vias allowed)
				(pads allowed)
				(copperpour not_allowed)
				(footprints allowed)
			)
			(placement
				(enabled no)
				(sheetname "")
			)
			(fill
				(thermal_gap 0.5)
				(thermal_bridge_width 0.5)
				(island_removal_mode 0)
			)
			(polygon
				(pts
					(xy 53.975 46.2026) (xy 53.975 47.7774) (xy 53.8226 47.7774) (xy 53.8226 46.2026)
				)
			)
		)
	)
	(footprint ""
		(layer "F.Cu")
		(at 7.112 40.64)
		(property "Reference" "TP23"
			(at -0.48133 4.064 90)
			(unlocked yes)
			(layer "F.SilkS")
			(effects
				(font
					(size 0.7874 0.5842)
					(thickness 0.127)
				)
				(justify left)
			)
		)
		(property "Value" "*"
			(at -0.4826 -0.14732 0)
			(unlocked yes)
			(layer "F.Fab")
			(hide yes)
			(effects
				(font
					(size 1.27 0.9652)
					(thickness 0.000001)
				)
				(justify left)
			)
		)
		(property "Device Type" "TP_SMALL"
			(at -0.4826 -0.14732 0)
			(unlocked yes)
			(layer "F.Fab")
			(hide yes)
			(effects
				(font
					(size 1.27 0.9652)
					(thickness 0.000001)
				)
				(justify left)
			)
		)
		(duplicate_pad_numbers_are_jumpers no)
		(fp_line
			(start -0.8636 -0.8636)
			(end -0.8636 0.8636)
			(stroke
				(width 0.1524)
				(type default)
			)
			(layer "F.SilkS")
		)
		(fp_line
			(start -0.8636 0.8636)
			(end 0.8636 0.8636)
			(stroke
				(width 0.1524)
				(type default)
			)
			(layer "F.SilkS")
		)
		(fp_line
			(start 0.8636 -0.8636)
			(end -0.8636 -0.8636)
			(stroke
				(width 0.1524)
				(type default)
			)
			(layer "F.SilkS")
		)
		(fp_line
			(start 0.8636 0.8636)
			(end 0.8636 -0.8636)
			(stroke
				(width 0.1524)
				(type default)
			)
			(layer "F.SilkS")
		)
		(fp_poly
			(pts
				(xy -0.635 -0.635) (xy -0.635 0.635) (xy 0.635 0.635) (xy 0.635 -0.635)
			)
			(stroke
				(width 0)
				(type default)
			)
			(fill no)
			(layer "F.CrtYd")
		)
		(pad "1" smd rect
			(at 0 0)
			(size 1.27 1.27)
			(layers "F.Cu" "F.Mask" "F.Paste")
			(net "CPLD_GPIO_3")
		)
	)
	(footprint ""
		(layer "F.Cu")
		(at 77.47 26.8732 180)
		(property "Reference" "C110"
			(at 0 0 180)
			(layer "F.SilkS")
			(hide yes)
			(effects
				(font
					(size 1.27 1.27)
				)
			)
		)
		(property "Value" "0.1UF"
			(at -0.091846 0.2921 270)
			(unlocked yes)
			(layer "F.Fab")
			(hide yes)
			(effects
				(font
					(size 0.7874 0.5842)
					(thickness 0.2032)
				)
				(justify left)
			)
		)
		(property "Device Type" "CAPC0073"
			(at -0.091846 0.2921 270)
			(unlocked yes)
			(layer "F.Fab")
			(hide yes)
			(effects
				(font
					(size 0.7874 0.5842)
					(thickness 0.2032)
				)
				(justify left)
			)
		)
		(duplicate_pad_numbers_are_jumpers no)
		(fp_poly
			(pts
				(xy 0.635 1.0668) (xy 0.635 -1.0668) (xy -0.635 -1.0668) (xy -0.635 1.0668)
			)
			(stroke
				(width 0)
				(type default)
			)
			(fill no)
			(layer "F.CrtYd")
		)
		(fp_line
			(start 0.254 0.508)
			(end -0.254 0.508)
			(stroke
				(width 0.0254)
				(type default)
			)
			(layer "F.Fab")
		)
		(fp_line
			(start 0.254 -0.508)
			(end 0.254 0.508)
			(stroke
				(width 0.0254)
				(type default)
			)
			(layer "F.Fab")
		)
		(fp_line
			(start -0.254 0.508)
			(end -0.254 -0.508)
			(stroke
				(width 0.0254)
				(type default)
			)
			(layer "F.Fab")
		)
		(fp_line
			(start -0.254 -0.508)
			(end 0.254 -0.508)
			(stroke
				(width 0.0254)
				(type default)
			)
			(layer "F.Fab")
		)
		(pad "1" smd rect
			(at 0 -0.4191 180)
			(size 0.508 0.5334)
			(layers "F.Cu" "F.Mask" "F.Paste")
			(net "DDR_VTT")
		)
		(pad "2" smd rect
			(at 0 0.4191 180)
			(size 0.508 0.5334)
			(layers "F.Cu" "F.Mask" "F.Paste")
			(net "GND")
		)
		(zone
			(layer "F.Cu")
			(hatch none 0.5)
			(connect_pads
				(clearance 0)
			)
			(min_thickness 0.25)
			(keepout
				(tracks not_allowed)
				(vias allowed)
				(pads allowed)
				(copperpour not_allowed)
				(footprints allowed)
			)
			(placement
				(enabled no)
				(sheetname "")
			)
			(fill
				(thermal_gap 0.5)
				(thermal_bridge_width 0.5)
				(island_removal_mode 0)
			)
			(polygon
				(pts
					(xy 77.4446 26.8986) (xy 77.4446 26.8478) (xy 77.4954 26.8478) (xy 77.4954 26.8986)
				)
			)
		)
	)
	(footprint ""
		(layer "F.Cu")
		(at 80.137 32.576414 180)
		(property "Reference" "R353"
			(at -0.02667 -4.507586 90)
			(unlocked yes)
			(layer "F.SilkS")
			(effects
				(font
					(size 0.7874 0.5842)
					(thickness 0.127)
				)
				(justify left)
			)
		)
		(property "Value" "240"
			(at -0.148158 1.3462 270)
			(unlocked yes)
			(layer "F.Fab")
			(hide yes)
			(effects
				(font
					(size 1.27 0.9652)
					(thickness 0.000001)
				)
				(justify left)
			)
		)
		(property "Device Type" "REST0009"
			(at -0.148158 1.3462 270)
			(unlocked yes)
			(layer "F.Fab")
			(hide yes)
			(effects
				(font
					(size 1.27 0.9652)
					(thickness 0.000001)
				)
				(justify left)
			)
		)
		(duplicate_pad_numbers_are_jumpers no)
		(fp_poly
			(pts
				(xy 0.635 1.0668) (xy 0.635 -1.0668) (xy -0.635 -1.0668) (xy -0.635 1.0668)
			)
			(stroke
				(width 0)
				(type default)
			)
			(fill no)
			(layer "F.CrtYd")
		)
		(fp_line
			(start 0.254 0.508)
			(end -0.254 0.508)
			(stroke
				(width 0.0254)
				(type default)
			)
			(layer "F.Fab")
		)
		(fp_line
			(start 0.254 -0.508)
			(end 0.254 0.508)
			(stroke
				(width 0.0254)
				(type default)
			)
			(layer "F.Fab")
		)
		(fp_line
			(start -0.254 0.508)
			(end -0.254 -0.508)
			(stroke
				(width 0.0254)
				(type default)
			)
			(layer "F.Fab")
		)
		(fp_line
			(start -0.254 -0.508)
			(end 0.254 -0.508)
			(stroke
				(width 0.0254)
				(type default)
			)
			(layer "F.Fab")
		)
		(pad "1" smd rect
			(at 0 -0.4191 180)
			(size 0.508 0.5334)
			(layers "F.Cu" "F.Mask" "F.Paste")
			(net "GND")
		)
		(pad "2" smd rect
			(at 0 0.4191 180)
			(size 0.508 0.5334)
			(layers "F.Cu" "F.Mask" "F.Paste")
			(net "12N3220")
		)
		(zone
			(layer "F.Cu")
			(hatch none 0.5)
			(connect_pads
				(clearance 0)
			)
			(min_thickness 0.25)
			(keepout
				(tracks not_allowed)
				(vias allowed)
				(pads allowed)
				(copperpour not_allowed)
				(footprints allowed)
			)
			(placement
				(enabled no)
				(sheetname "")
			)
			(fill
				(thermal_gap 0.5)
				(thermal_bridge_width 0.5)
				(island_removal_mode 0)
			)
			(polygon
				(pts
					(xy 80.1116 32.601814) (xy 80.1116 32.551014) (xy 80.1624 32.551014) (xy 80.1624 32.601814)
				)
			)
		)
	)
	(footprint ""
		(layer "F.Cu")
		(at 81.153 35.687 180)
		(property "Reference" "R335"
			(at 0 0 180)
			(layer "F.SilkS")
			(hide yes)
			(effects
				(font
					(size 1.27 1.27)
				)
			)
		)
		(property "Value" "0"
			(at -0.148158 1.3462 270)
			(unlocked yes)
			(layer "F.Fab")
			(hide yes)
			(effects
				(font
					(size 1.27 0.9652)
					(thickness 0.000001)
				)
				(justify left)
			)
		)
		(property "Device Type" "REST1111"
			(at -0.148158 1.3462 270)
			(unlocked yes)
			(layer "F.Fab")
			(hide yes)
			(effects
				(font
					(size 1.27 0.9652)
					(thickness 0.000001)
				)
				(justify left)
			)
		)
		(duplicate_pad_numbers_are_jumpers no)
		(fp_poly
			(pts
				(xy 0.635 1.0668) (xy 0.635 -1.0668) (xy -0.635 -1.0668) (xy -0.635 1.0668)
			)
			(stroke
				(width 0)
				(type default)
			)
			(fill no)
			(layer "F.CrtYd")
		)
		(fp_line
			(start 0.254 0.508)
			(end -0.254 0.508)
			(stroke
				(width 0.0254)
				(type default)
			)
			(layer "F.Fab")
		)
		(fp_line
			(start 0.254 -0.508)
			(end 0.254 0.508)
			(stroke
				(width 0.0254)
				(type default)
			)
			(layer "F.Fab")
		)
		(fp_line
			(start -0.254 0.508)
			(end -0.254 -0.508)
			(stroke
				(width 0.0254)
				(type default)
			)
			(layer "F.Fab")
		)
		(fp_line
			(start -0.254 -0.508)
			(end 0.254 -0.508)
			(stroke
				(width 0.0254)
				(type default)
			)
			(layer "F.Fab")
		)
		(pad "1" smd rect
			(at 0 -0.4191 180)
			(size 0.508 0.5334)
			(layers "F.Cu" "F.Mask" "F.Paste")
			(net "11N2191")
		)
		(pad "2" smd rect
			(at 0 0.4191 180)
			(size 0.508 0.5334)
			(layers "F.Cu" "F.Mask" "F.Paste")
			(net "DDR_VDDQ")
		)
		(zone
			(layer "F.Cu")
			(hatch none 0.5)
			(connect_pads
				(clearance 0)
			)
			(min_thickness 0.25)
			(keepout
				(tracks not_allowed)
				(vias allowed)
				(pads allowed)
				(copperpour not_allowed)
				(footprints allowed)
			)
			(placement
				(enabled no)
				(sheetname "")
			)
			(fill
				(thermal_gap 0.5)
				(thermal_bridge_width 0.5)
				(island_removal_mode 0)
			)
			(polygon
				(pts
					(xy 81.1276 35.7124) (xy 81.1276 35.6616) (xy 81.1784 35.6616) (xy 81.1784 35.7124)
				)
			)
		)
	)
	(footprint ""
		(layer "F.Cu")
		(at 20.701 16.8529 180)
		(property "Reference" "C87"
			(at 2.54 -0.44577 0)
			(unlocked yes)
			(layer "F.SilkS")
			(effects
				(font
					(size 0.7874 0.5842)
					(thickness 0.127)
				)
				(justify left)
			)
		)
		(property "Value" "0.1UF"
			(at -0.091846 0.2921 270)
			(unlocked yes)
			(layer "F.Fab")
			(hide yes)
			(effects
				(font
					(size 0.7874 0.5842)
					(thickness 0.2032)
				)
				(justify left)
			)
		)
		(property "Device Type" "CAPC0073"
			(at -0.091846 0.2921 270)
			(unlocked yes)
			(layer "F.Fab")
			(hide yes)
			(effects
				(font
					(size 0.7874 0.5842)
					(thickness 0.2032)
				)
				(justify left)
			)
		)
		(duplicate_pad_numbers_are_jumpers no)
		(fp_poly
			(pts
				(xy 0.635 1.0668) (xy 0.635 -1.0668) (xy -0.635 -1.0668) (xy -0.635 1.0668)
			)
			(stroke
				(width 0)
				(type default)
			)
			(fill no)
			(layer "F.CrtYd")
		)
		(fp_line
			(start 0.254 0.508)
			(end -0.254 0.508)
			(stroke
				(width 0.0254)
				(type default)
			)
			(layer "F.Fab")
		)
		(fp_line
			(start 0.254 -0.508)
			(end 0.254 0.508)
			(stroke
				(width 0.0254)
				(type default)
			)
			(layer "F.Fab")
		)
		(fp_line
			(start -0.254 0.508)
			(end -0.254 -0.508)
			(stroke
				(width 0.0254)
				(type default)
			)
			(layer "F.Fab")
		)
		(fp_line
			(start -0.254 -0.508)
			(end 0.254 -0.508)
			(stroke
				(width 0.0254)
				(type default)
			)
			(layer "F.Fab")
		)
		(pad "1" smd rect
			(at 0 -0.4191 180)
			(size 0.508 0.5334)
			(layers "F.Cu" "F.Mask" "F.Paste")
			(net "VDD_3.3V")
		)
		(pad "2" smd rect
			(at 0 0.4191 180)
			(size 0.508 0.5334)
			(layers "F.Cu" "F.Mask" "F.Paste")
			(net "GND")
		)
		(zone
			(layer "F.Cu")
			(hatch none 0.5)
			(connect_pads
				(clearance 0)
			)
			(min_thickness 0.25)
			(keepout
				(tracks not_allowed)
				(vias allowed)
				(pads allowed)
				(copperpour not_allowed)
				(footprints allowed)
			)
			(placement
				(enabled no)
				(sheetname "")
			)
			(fill
				(thermal_gap 0.5)
				(thermal_bridge_width 0.5)
				(island_removal_mode 0)
			)
			(polygon
				(pts
					(xy 20.6756 16.8783) (xy 20.6756 16.8275) (xy 20.7264 16.8275) (xy 20.7264 16.8783)
				)
			)
		)
	)
	(footprint ""
		(layer "F.Cu")
		(at 76.251003 25.813004)
		(property "Reference" "V_A-DQS4-N"
			(at 0 0 0)
			(layer "F.SilkS")
			(hide yes)
			(effects
				(font
					(size 1.27 1.27)
				)
			)
		)
		(property "Value" ""
			(at 0 0 0)
			(layer "F.Fab")
			(effects
				(font
					(size 1.27 1.27)
				)
			)
		)
		(duplicate_pad_numbers_are_jumpers no)
		(pad "1" thru_hole circle
			(at 0 0)
			(size 0.762 0.762)
			(drill 0.20574)
			(layers "*.Cu" "*.Mask")
			(remove_unused_layers no)
			(net "DDR0_32A_DQS4_N")
			(clearance 0.127)
			(thermal_gap 0.127)
			(padstack
				(mode front_inner_back)
				(layer "Inner"
					(shape circle)
					(size 0.4572 0.4572)
					(clearance 0.1143)
				)
				(layer "B.Cu"
					(shape circle)
					(size 0.4572 0.4572)
					(clearance 0.1143)
				)
			)
		)
	)
	(footprint ""
		(layer "F.Cu")
		(at 27.432 32.639)
		(property "Reference" "R83"
			(at 0 0 0)
			(layer "F.SilkS")
			(hide yes)
			(effects
				(font
					(size 1.27 1.27)
				)
			)
		)
		(property "Value" "4.75K"
			(at -0.148158 1.3462 90)
			(unlocked yes)
			(layer "F.Fab")
			(hide yes)
			(effects
				(font
					(size 1.27 0.9652)
					(thickness 0.000001)
				)
				(justify left)
			)
		)
		(property "Device Type" "REST4024"
			(at -0.148158 1.3462 90)
			(unlocked yes)
			(layer "F.Fab")
			(hide yes)
			(effects
				(font
					(size 1.27 0.9652)
					(thickness 0.000001)
				)
				(justify left)
			)
		)
		(duplicate_pad_numbers_are_jumpers no)
		(fp_poly
			(pts
				(xy 0.635 1.0668) (xy 0.635 -1.0668) (xy -0.635 -1.0668) (xy -0.635 1.0668)
			)
			(stroke
				(width 0)
				(type default)
			)
			(fill no)
			(layer "F.CrtYd")
		)
		(fp_line
			(start -0.254 -0.508)
			(end 0.254 -0.508)
			(stroke
				(width 0.0254)
				(type default)
			)
			(layer "F.Fab")
		)
		(fp_line
			(start -0.254 0.508)
			(end -0.254 -0.508)
			(stroke
				(width 0.0254)
				(type default)
			)
			(layer "F.Fab")
		)
		(fp_line
			(start 0.254 -0.508)
			(end 0.254 0.508)
			(stroke
				(width 0.0254)
				(type default)
			)
			(layer "F.Fab")
		)
		(fp_line
			(start 0.254 0.508)
			(end -0.254 0.508)
			(stroke
				(width 0.0254)
				(type default)
			)
			(layer "F.Fab")
		)
		(pad "1" smd rect
			(at 0 -0.4191)
			(size 0.508 0.5334)
			(layers "F.Cu" "F.Mask" "F.Paste")
			(net "GND")
		)
		(pad "2" smd rect
			(at 0 0.4191)
			(size 0.508 0.5334)
			(layers "F.Cu" "F.Mask" "F.Paste")
			(net "_NFP_CORE_VID0")
		)
		(zone
			(layer "F.Cu")
			(hatch none 0.5)
			(connect_pads
				(clearance 0)
			)
			(min_thickness 0.25)
			(keepout
				(tracks not_allowed)
				(vias allowed)
				(pads allowed)
				(copperpour not_allowed)
				(footprints allowed)
			)
			(placement
				(enabled no)
				(sheetname "")
			)
			(fill
				(thermal_gap 0.5)
				(thermal_bridge_width 0.5)
				(island_removal_mode 0)
			)
			(polygon
				(pts
					(xy 27.4574 32.6136) (xy 27.4574 32.6644) (xy 27.4066 32.6644) (xy 27.4066 32.6136)
				)
			)
		)
	)
	(footprint ""
		(layer "F.Cu")
		(at 23.6601 1.397 -90)
		(property "Reference" "R383"
			(at -0.86233 0.8001 0)
			(unlocked yes)
			(layer "F.SilkS")
			(effects
				(font
					(size 0.7874 0.5842)
					(thickness 0.127)
				)
				(justify left)
			)
		)
		(property "Value" "0"
			(at -0.148158 1.3462 0)
			(unlocked yes)
			(layer "F.Fab")
			(hide yes)
			(effects
				(font
					(size 1.27 0.9652)
					(thickness 0.000001)
				)
				(justify left)
			)
		)
		(property "Device Type" "REST1111"
			(at -0.148158 1.3462 0)
			(unlocked yes)
			(layer "F.Fab")
			(hide yes)
			(effects
				(font
					(size 1.27 0.9652)
					(thickness 0.000001)
				)
				(justify left)
			)
		)
		(duplicate_pad_numbers_are_jumpers no)
		(fp_poly
			(pts
				(xy 0.635 1.0668) (xy 0.635 -1.0668) (xy -0.635 -1.0668) (xy -0.635 1.0668)
			)
			(stroke
				(width 0)
				(type default)
			)
			(fill no)
			(layer "F.CrtYd")
		)
		(fp_line
			(start -0.254 0.508)
			(end -0.254 -0.508)
			(stroke
				(width 0.0254)
				(type default)
			)
			(layer "F.Fab")
		)
		(fp_line
			(start 0.254 0.508)
			(end -0.254 0.508)
			(stroke
				(width 0.0254)
				(type default)
			)
			(layer "F.Fab")
		)
		(fp_line
			(start -0.254 -0.508)
			(end 0.254 -0.508)
			(stroke
				(width 0.0254)
				(type default)
			)
			(layer "F.Fab")
		)
		(fp_line
			(start 0.254 -0.508)
			(end 0.254 0.508)
			(stroke
				(width 0.0254)
				(type default)
			)
			(layer "F.Fab")
		)
		(pad "1" smd rect
			(at 0 -0.4191 270)
			(size 0.508 0.5334)
			(layers "F.Cu" "F.Mask" "F.Paste")
			(net "NFP_SMBUS_SCL")
		)
		(pad "2" smd rect
			(at 0 0.4191 270)
			(size 0.508 0.5334)
			(layers "F.Cu" "F.Mask" "F.Paste")
			(net "MUX_NFP_SMBUS_SCL")
		)
		(zone
			(layer "F.Cu")
			(hatch none 0.5)
			(connect_pads
				(clearance 0)
			)
			(min_thickness 0.25)
			(keepout
				(tracks not_allowed)
				(vias allowed)
				(pads allowed)
				(copperpour not_allowed)
				(footprints allowed)
			)
			(placement
				(enabled no)
				(sheetname "")
			)
			(fill
				(thermal_gap 0.5)
				(thermal_bridge_width 0.5)
				(island_removal_mode 0)
			)
			(polygon
				(pts
					(xy 23.6855 1.4224) (xy 23.6347 1.4224) (xy 23.6347 1.3716) (xy 23.6855 1.3716)
				)
			)
		)
	)
	(footprint ""
		(layer "F.Cu")
		(at 10.16 1.397)
		(property "Reference" "R367"
			(at 0.196012 -1.4732 90)
			(unlocked yes)
			(layer "F.SilkS")
			(effects
				(font
					(size 0.7874 0.5842)
					(thickness 0.127)
				)
				(justify left)
			)
		)
		(property "Value" "0"
			(at -0.148158 1.3462 90)
			(unlocked yes)
			(layer "F.Fab")
			(hide yes)
			(effects
				(font
					(size 1.27 0.9652)
					(thickness 0.000001)
				)
				(justify left)
			)
		)
		(property "Device Type" "REST1111"
			(at -0.148158 1.3462 90)
			(unlocked yes)
			(layer "F.Fab")
			(hide yes)
			(effects
				(font
					(size 1.27 0.9652)
					(thickness 0.000001)
				)
				(justify left)
			)
		)
		(duplicate_pad_numbers_are_jumpers no)
		(fp_poly
			(pts
				(xy 0.635 1.0668) (xy 0.635 -1.0668) (xy -0.635 -1.0668) (xy -0.635 1.0668)
			)
			(stroke
				(width 0)
				(type default)
			)
			(fill no)
			(layer "F.CrtYd")
		)
		(fp_line
			(start -0.254 -0.508)
			(end 0.254 -0.508)
			(stroke
				(width 0.0254)
				(type default)
			)
			(layer "F.Fab")
		)
		(fp_line
			(start -0.254 0.508)
			(end -0.254 -0.508)
			(stroke
				(width 0.0254)
				(type default)
			)
			(layer "F.Fab")
		)
		(fp_line
			(start 0.254 -0.508)
			(end 0.254 0.508)
			(stroke
				(width 0.0254)
				(type default)
			)
			(layer "F.Fab")
		)
		(fp_line
			(start 0.254 0.508)
			(end -0.254 0.508)
			(stroke
				(width 0.0254)
				(type default)
			)
			(layer "F.Fab")
		)
		(pad "1" smd rect
			(at 0 -0.4191)
			(size 0.508 0.5334)
			(layers "F.Cu" "F.Mask" "F.Paste")
			(net "CPLD_PCIE0_WAKE_L")
		)
		(pad "2" smd rect
			(at 0 0.4191)
			(size 0.508 0.5334)
			(layers "F.Cu" "F.Mask" "F.Paste")
			(net "PCIE0_WAKE_L")
		)
		(zone
			(layer "F.Cu")
			(hatch none 0.5)
			(connect_pads
				(clearance 0)
			)
			(min_thickness 0.25)
			(keepout
				(tracks not_allowed)
				(vias allowed)
				(pads allowed)
				(copperpour not_allowed)
				(footprints allowed)
			)
			(placement
				(enabled no)
				(sheetname "")
			)
			(fill
				(thermal_gap 0.5)
				(thermal_bridge_width 0.5)
				(island_removal_mode 0)
			)
			(polygon
				(pts
					(xy 10.1854 1.3716) (xy 10.1854 1.4224) (xy 10.1346 1.4224) (xy 10.1346 1.3716)
				)
			)
		)
	)
	(footprint ""
		(layer "F.Cu")
		(at 81.026 28.702 180)
		(property "Reference" "R223"
			(at 0 0 180)
			(layer "F.SilkS")
			(hide yes)
			(effects
				(font
					(size 1.27 1.27)
				)
			)
		)
		(property "Value" "39.0"
			(at -0.148158 1.3462 270)
			(unlocked yes)
			(layer "F.Fab")
			(hide yes)
			(effects
				(font
					(size 1.27 0.9652)
					(thickness 0.000001)
				)
				(justify left)
			)
		)
		(property "Device Type" "REST0108"
			(at -0.148158 1.3462 270)
			(unlocked yes)
			(layer "F.Fab")
			(hide yes)
			(effects
				(font
					(size 1.27 0.9652)
					(thickness 0.000001)
				)
				(justify left)
			)
		)
		(duplicate_pad_numbers_are_jumpers no)
		(fp_poly
			(pts
				(xy 0.635 1.0668) (xy 0.635 -1.0668) (xy -0.635 -1.0668) (xy -0.635 1.0668)
			)
			(stroke
				(width 0)
				(type default)
			)
			(fill no)
			(layer "F.CrtYd")
		)
		(fp_line
			(start 0.254 0.508)
			(end -0.254 0.508)
			(stroke
				(width 0.0254)
				(type default)
			)
			(layer "F.Fab")
		)
		(fp_line
			(start 0.254 -0.508)
			(end 0.254 0.508)
			(stroke
				(width 0.0254)
				(type default)
			)
			(layer "F.Fab")
		)
		(fp_line
			(start -0.254 0.508)
			(end -0.254 -0.508)
			(stroke
				(width 0.0254)
				(type default)
			)
			(layer "F.Fab")
		)
		(fp_line
			(start -0.254 -0.508)
			(end 0.254 -0.508)
			(stroke
				(width 0.0254)
				(type default)
			)
			(layer "F.Fab")
		)
		(pad "1" smd rect
			(at 0 -0.4191 180)
			(size 0.508 0.5334)
			(layers "F.Cu" "F.Mask" "F.Paste")
			(net "DDR0_32A_BA1")
		)
		(pad "2" smd rect
			(at 0 0.4191 180)
			(size 0.508 0.5334)
			(layers "F.Cu" "F.Mask" "F.Paste")
			(net "DDR_VTT")
		)
		(zone
			(layer "F.Cu")
			(hatch none 0.5)
			(connect_pads
				(clearance 0)
			)
			(min_thickness 0.25)
			(keepout
				(tracks not_allowed)
				(vias allowed)
				(pads allowed)
				(copperpour not_allowed)
				(footprints allowed)
			)
			(placement
				(enabled no)
				(sheetname "")
			)
			(fill
				(thermal_gap 0.5)
				(thermal_bridge_width 0.5)
				(island_removal_mode 0)
			)
			(polygon
				(pts
					(xy 81.0006 28.7274) (xy 81.0006 28.6766) (xy 81.0514 28.6766) (xy 81.0514 28.7274)
				)
			)
		)
	)
	(footprint ""
		(layer "F.Cu")
		(at 84.582 28.702 180)
		(property "Reference" "R220"
			(at -0.91567 -1.651 90)
			(unlocked yes)
			(layer "F.SilkS")
			(effects
				(font
					(size 0.7874 0.5842)
					(thickness 0.127)
				)
				(justify left)
			)
		)
		(property "Value" "39.0"
			(at -0.148158 1.3462 270)
			(unlocked yes)
			(layer "F.Fab")
			(hide yes)
			(effects
				(font
					(size 1.27 0.9652)
					(thickness 0.000001)
				)
				(justify left)
			)
		)
		(property "Device Type" "REST0108"
			(at -0.148158 1.3462 270)
			(unlocked yes)
			(layer "F.Fab")
			(hide yes)
			(effects
				(font
					(size 1.27 0.9652)
					(thickness 0.000001)
				)
				(justify left)
			)
		)
		(duplicate_pad_numbers_are_jumpers no)
		(fp_poly
			(pts
				(xy 0.635 1.0668) (xy 0.635 -1.0668) (xy -0.635 -1.0668) (xy -0.635 1.0668)
			)
			(stroke
				(width 0)
				(type default)
			)
			(fill no)
			(layer "F.CrtYd")
		)
		(fp_line
			(start 0.254 0.508)
			(end -0.254 0.508)
			(stroke
				(width 0.0254)
				(type default)
			)
			(layer "F.Fab")
		)
		(fp_line
			(start 0.254 -0.508)
			(end 0.254 0.508)
			(stroke
				(width 0.0254)
				(type default)
			)
			(layer "F.Fab")
		)
		(fp_line
			(start -0.254 0.508)
			(end -0.254 -0.508)
			(stroke
				(width 0.0254)
				(type default)
			)
			(layer "F.Fab")
		)
		(fp_line
			(start -0.254 -0.508)
			(end 0.254 -0.508)
			(stroke
				(width 0.0254)
				(type default)
			)
			(layer "F.Fab")
		)
		(pad "1" smd rect
			(at 0 -0.4191 180)
			(size 0.508 0.5334)
			(layers "F.Cu" "F.Mask" "F.Paste")
			(net "DDR0_32A_A14")
		)
		(pad "2" smd rect
			(at 0 0.4191 180)
			(size 0.508 0.5334)
			(layers "F.Cu" "F.Mask" "F.Paste")
			(net "DDR_VTT")
		)
		(zone
			(layer "F.Cu")
			(hatch none 0.5)
			(connect_pads
				(clearance 0)
			)
			(min_thickness 0.25)
			(keepout
				(tracks not_allowed)
				(vias allowed)
				(pads allowed)
				(copperpour not_allowed)
				(footprints allowed)
			)
			(placement
				(enabled no)
				(sheetname "")
			)
			(fill
				(thermal_gap 0.5)
				(thermal_bridge_width 0.5)
				(island_removal_mode 0)
			)
			(polygon
				(pts
					(xy 84.5566 28.7274) (xy 84.5566 28.6766) (xy 84.6074 28.6766) (xy 84.6074 28.7274)
				)
			)
		)
	)
	(footprint ""
		(layer "F.Cu")
		(at 77.978 9.271 90)
		(property "Reference" "R189"
			(at 0 0 90)
			(layer "F.SilkS")
			(hide yes)
			(effects
				(font
					(size 1.27 1.27)
				)
			)
		)
		(property "Value" "240"
			(at -0.148158 1.3462 180)
			(unlocked yes)
			(layer "F.Fab")
			(hide yes)
			(effects
				(font
					(size 1.27 0.9652)
					(thickness 0.000001)
				)
				(justify left)
			)
		)
		(property "Device Type" "REST0009"
			(at -0.148158 1.3462 180)
			(unlocked yes)
			(layer "F.Fab")
			(hide yes)
			(effects
				(font
					(size 1.27 0.9652)
					(thickness 0.000001)
				)
				(justify left)
			)
		)
		(duplicate_pad_numbers_are_jumpers no)
		(fp_poly
			(pts
				(xy 0.635 1.0668) (xy 0.635 -1.0668) (xy -0.635 -1.0668) (xy -0.635 1.0668)
			)
			(stroke
				(width 0)
				(type default)
			)
			(fill no)
			(layer "F.CrtYd")
		)
		(fp_line
			(start 0.254 -0.508)
			(end 0.254 0.508)
			(stroke
				(width 0.0254)
				(type default)
			)
			(layer "F.Fab")
		)
		(fp_line
			(start -0.254 -0.508)
			(end 0.254 -0.508)
			(stroke
				(width 0.0254)
				(type default)
			)
			(layer "F.Fab")
		)
		(fp_line
			(start 0.254 0.508)
			(end -0.254 0.508)
			(stroke
				(width 0.0254)
				(type default)
			)
			(layer "F.Fab")
		)
		(fp_line
			(start -0.254 0.508)
			(end -0.254 -0.508)
			(stroke
				(width 0.0254)
				(type default)
			)
			(layer "F.Fab")
		)
		(pad "1" smd rect
			(at 0 -0.4191 90)
			(size 0.508 0.5334)
			(layers "F.Cu" "F.Mask" "F.Paste")
			(net "GND")
		)
		(pad "2" smd rect
			(at 0 0.4191 90)
			(size 0.508 0.5334)
			(layers "F.Cu" "F.Mask" "F.Paste")
			(net "12N2312")
		)
		(zone
			(layer "F.Cu")
			(hatch none 0.5)
			(connect_pads
				(clearance 0)
			)
			(min_thickness 0.25)
			(keepout
				(tracks not_allowed)
				(vias allowed)
				(pads allowed)
				(copperpour not_allowed)
				(footprints allowed)
			)
			(placement
				(enabled no)
				(sheetname "")
			)
			(fill
				(thermal_gap 0.5)
				(thermal_bridge_width 0.5)
				(island_removal_mode 0)
			)
			(polygon
				(pts
					(xy 77.9526 9.2456) (xy 78.0034 9.2456) (xy 78.0034 9.2964) (xy 77.9526 9.2964)
				)
			)
		)
	)
	(footprint ""
		(layer "F.Cu")
		(at 77.851 53.975 180)
		(property "Reference" "C184"
			(at -2.94767 -1.524 90)
			(unlocked yes)
			(layer "F.SilkS")
			(effects
				(font
					(size 0.7874 0.5842)
					(thickness 0.127)
				)
				(justify left)
			)
		)
		(property "Value" ""
			(at 0 0 180)
			(layer "F.Fab")
			(effects
				(font
					(size 1.27 1.27)
				)
			)
		)
		(duplicate_pad_numbers_are_jumpers no)
		(fp_arc
			(start 0.381 0.336017)
			(mid 0.20901 0.463015)
			(end 0 0.508)
			(stroke
				(width 0.2032)
				(type default)
			)
			(layer "F.SilkS")
		)
		(fp_arc
			(start 0 0.508)
			(mid -0.209008 0.463011)
			(end -0.381 0.336017)
			(stroke
				(width 0.2032)
				(type default)
			)
			(layer "F.SilkS")
		)
		(fp_arc
			(start 0 -0.508)
			(mid 0.209 -0.463015)
			(end 0.381 -0.336042)
			(stroke
				(width 0.2032)
				(type default)
			)
			(layer "F.SilkS")
		)
		(fp_arc
			(start -0.381 -0.335991)
			(mid -0.209012 -0.462996)
			(end 0 -0.508)
			(stroke
				(width 0.2032)
				(type default)
			)
			(layer "F.SilkS")
		)
		(fp_circle
			(center 0 0)
			(end -0.508 0)
			(stroke
				(width 0.2032)
				(type default)
			)
			(fill no)
			(layer "F.SilkS")
		)
		(fp_poly
			(pts
				(xy -2.286 1.778) (xy -2.286 -1.524) (xy 2.286 -1.524) (xy 2.286 1.778)
			)
			(stroke
				(width 0)
				(type default)
			)
			(fill no)
			(layer "F.CrtYd")
		)
		(fp_line
			(start 1.524 1.27)
			(end -1.524 1.27)
			(stroke
				(width 0.0254)
				(type default)
			)
			(layer "F.Fab")
		)
		(fp_line
			(start 1.524 -1.27)
			(end 1.524 1.27)
			(stroke
				(width 0.0254)
				(type default)
			)
			(layer "F.Fab")
		)
		(fp_line
			(start -1.524 1.27)
			(end -1.524 -1.27)
			(stroke
				(width 0.0254)
				(type default)
			)
			(layer "F.Fab")
		)
		(fp_line
			(start -1.524 -1.27)
			(end 1.524 -1.27)
			(stroke
				(width 0.0254)
				(type default)
			)
			(layer "F.Fab")
		)
		(pad "1" smd rect
			(at -1.4224 0 270)
			(size 2.7432 1.3716)
			(layers "F.Cu" "F.Mask" "F.Paste")
			(net "EXT_12.0V")
		)
		(pad "2" smd rect
			(at 1.4224 0 270)
			(size 2.7432 1.3716)
			(layers "F.Cu" "F.Mask" "F.Paste")
			(net "GND")
		)
	)
	(footprint ""
		(layer "F.Cu")
		(at 28.575 7.112 90)
		(property "Reference" "R15"
			(at 0.86233 -1.016 0)
			(unlocked yes)
			(layer "F.SilkS")
			(effects
				(font
					(size 0.7874 0.5842)
					(thickness 0.127)
				)
				(justify left)
			)
		)
		(property "Value" "4.75K"
			(at -0.148158 1.3462 180)
			(unlocked yes)
			(layer "F.Fab")
			(hide yes)
			(effects
				(font
					(size 1.27 0.9652)
					(thickness 0.000001)
				)
				(justify left)
			)
		)
		(property "Device Type" "REST4024"
			(at -0.148158 1.3462 180)
			(unlocked yes)
			(layer "F.Fab")
			(hide yes)
			(effects
				(font
					(size 1.27 0.9652)
					(thickness 0.000001)
				)
				(justify left)
			)
		)
		(duplicate_pad_numbers_are_jumpers no)
		(fp_poly
			(pts
				(xy 0.635 1.0668) (xy 0.635 -1.0668) (xy -0.635 -1.0668) (xy -0.635 1.0668)
			)
			(stroke
				(width 0)
				(type default)
			)
			(fill no)
			(layer "F.CrtYd")
		)
		(fp_line
			(start 0.254 -0.508)
			(end 0.254 0.508)
			(stroke
				(width 0.0254)
				(type default)
			)
			(layer "F.Fab")
		)
		(fp_line
			(start -0.254 -0.508)
			(end 0.254 -0.508)
			(stroke
				(width 0.0254)
				(type default)
			)
			(layer "F.Fab")
		)
		(fp_line
			(start 0.254 0.508)
			(end -0.254 0.508)
			(stroke
				(width 0.0254)
				(type default)
			)
			(layer "F.Fab")
		)
		(fp_line
			(start -0.254 0.508)
			(end -0.254 -0.508)
			(stroke
				(width 0.0254)
				(type default)
			)
			(layer "F.Fab")
		)
		(pad "1" smd rect
			(at 0 -0.4191 90)
			(size 0.508 0.5334)
			(layers "F.Cu" "F.Mask" "F.Paste")
			(net "EXT_3.3V")
		)
		(pad "2" smd rect
			(at 0 0.4191 90)
			(size 0.508 0.5334)
			(layers "F.Cu" "F.Mask" "F.Paste")
			(net "3N2286")
		)
		(zone
			(layer "F.Cu")
			(hatch none 0.5)
			(connect_pads
				(clearance 0)
			)
			(min_thickness 0.25)
			(keepout
				(tracks not_allowed)
				(vias allowed)
				(pads allowed)
				(copperpour not_allowed)
				(footprints allowed)
			)
			(placement
				(enabled no)
				(sheetname "")
			)
			(fill
				(thermal_gap 0.5)
				(thermal_bridge_width 0.5)
				(island_removal_mode 0)
			)
			(polygon
				(pts
					(xy 28.5496 7.0866) (xy 28.6004 7.0866) (xy 28.6004 7.1374) (xy 28.5496 7.1374)
				)
			)
		)
	)
	(footprint ""
		(layer "F.Cu")
		(at 5.334 10.16 180)
		(property "Reference" "C243"
			(at 6.32333 2.54 90)
			(unlocked yes)
			(layer "F.SilkS")
			(effects
				(font
					(size 0.7874 0.5842)
					(thickness 0.127)
				)
				(justify left)
			)
		)
		(property "Value" "220UF"
			(at -0.4826 1.37668 180)
			(unlocked yes)
			(layer "F.Fab")
			(hide yes)
			(effects
				(font
					(size 1.27 0.9652)
					(thickness 0.000001)
				)
				(justify left)
			)
		)
		(property "Device Type" "CAPE0005"
			(at -0.4826 1.37668 180)
			(unlocked yes)
			(layer "F.Fab")
			(hide yes)
			(effects
				(font
					(size 1.27 0.9652)
					(thickness 0.000001)
				)
				(justify left)
			)
		)
		(duplicate_pad_numbers_are_jumpers no)
		(fp_line
			(start 5.588 5.588)
			(end 5.588 -3.302)
			(stroke
				(width 0.2032)
				(type default)
			)
			(layer "F.SilkS")
		)
		(fp_line
			(start 5.588 5.588)
			(end 5.588 -3.302)
			(stroke
				(width 0.2032)
				(type default)
			)
			(layer "F.SilkS")
		)
		(fp_line
			(start 5.588 -3.302)
			(end 4.673041 -4.216959)
			(stroke
				(width 0.2032)
				(type default)
			)
			(layer "F.SilkS")
		)
		(fp_line
			(start 5.588 -3.302)
			(end 3.302 -5.588)
			(stroke
				(width 0.2032)
				(type default)
			)
			(layer "F.SilkS")
		)
		(fp_line
			(start 4.089959 -4.800041)
			(end 3.302 -5.588)
			(stroke
				(width 0.2032)
				(type default)
			)
			(layer "F.SilkS")
		)
		(fp_line
			(start 3.302 -5.588)
			(end 1.3081 -5.588)
			(stroke
				(width 0.2032)
				(type default)
			)
			(layer "F.SilkS")
		)
		(fp_line
			(start 3.302 -5.588)
			(end 1.27 -5.588)
			(stroke
				(width 0.2032)
				(type default)
			)
			(layer "F.SilkS")
		)
		(fp_line
			(start 2.0066 -7.1374)
			(end 2.0066 -5.8674)
			(stroke
				(width 0.2032)
				(type default)
			)
			(layer "F.SilkS")
		)
		(fp_line
			(start 2.0066 -7.1374)
			(end 2.0066 -5.8674)
			(stroke
				(width 0.2032)
				(type default)
			)
			(layer "F.SilkS")
		)
		(fp_line
			(start 1.733956 5.588)
			(end 5.588 5.588)
			(stroke
				(width 0.2032)
				(type default)
			)
			(layer "F.SilkS")
		)
		(fp_line
			(start 1.3716 -6.5024)
			(end 2.6416 -6.5024)
			(stroke
				(width 0.2032)
				(type default)
			)
			(layer "F.SilkS")
		)
		(fp_line
			(start 1.3716 -6.5024)
			(end 2.6416 -6.5024)
			(stroke
				(width 0.2032)
				(type default)
			)
			(layer "F.SilkS")
		)
		(fp_line
			(start 1.27 5.588)
			(end 5.588 5.588)
			(stroke
				(width 0.2032)
				(type default)
			)
			(layer "F.SilkS")
		)
		(fp_line
			(start -1.27 -5.588)
			(end -3.302 -5.588)
			(stroke
				(width 0.2032)
				(type default)
			)
			(layer "F.SilkS")
		)
		(fp_line
			(start -3.302 -5.588)
			(end -5.588 -3.302)
			(stroke
				(width 0.2032)
				(type default)
			)
			(layer "F.SilkS")
		)
		(fp_line
			(start -5.588 5.588)
			(end -1.27 5.588)
			(stroke
				(width 0.2032)
				(type default)
			)
			(layer "F.SilkS")
		)
		(fp_line
			(start -5.588 -3.302)
			(end -5.588 5.588)
			(stroke
				(width 0.2032)
				(type default)
			)
			(layer "F.SilkS")
		)
		(fp_line
			(start -5.588 -3.302)
			(end -5.588 5.588)
			(stroke
				(width 0.2032)
				(type default)
			)
			(layer "F.SilkS")
		)
		(fp_poly
			(pts
				(xy -5.7912 -5.842) (xy -1.524 -5.842) (xy -1.524 -7.112) (xy 1.524 -7.112) (xy 1.524 -5.842) (xy 5.261026 -5.842)
				(xy 5.261026 5.842) (xy 1.524 5.842) (xy 1.524 7.112) (xy -1.524 7.112) (xy -1.524 5.842) (xy -5.7912 5.842)
			)
			(stroke
				(width 0)
				(type default)
			)
			(fill no)
			(layer "F.CrtYd")
		)
		(fp_line
			(start 5.2578 5.2578)
			(end 5.2578 -3.2258)
			(stroke
				(width 0.2032)
				(type default)
			)
			(layer "F.Fab")
		)
		(fp_line
			(start 5.2578 -3.2258)
			(end 3.2258 -5.2578)
			(stroke
				(width 0.2032)
				(type default)
			)
			(layer "F.Fab")
		)
		(fp_line
			(start 3.2258 -5.2578)
			(end -3.2258 -5.2578)
			(stroke
				(width 0.2032)
				(type default)
			)
			(layer "F.Fab")
		)
		(fp_line
			(start 0.635 -3.937)
			(end -0.635 -3.937)
			(stroke
				(width 0.2032)
				(type default)
			)
			(layer "F.Fab")
		)
		(fp_line
			(start 0 -4.572)
			(end 0 -3.302)
			(stroke
				(width 0.2032)
				(type default)
			)
			(layer "F.Fab")
		)
		(fp_line
			(start -3.2258 -5.2578)
			(end -5.2578 -3.2258)
			(stroke
				(width 0.2032)
				(type default)
			)
			(layer "F.Fab")
		)
		(fp_line
			(start -5.2578 5.2578)
			(end 5.2578 5.2578)
			(stroke
				(width 0.2032)
				(type default)
			)
			(layer "F.Fab")
		)
		(fp_line
			(start -5.2578 -3.2258)
			(end -5.2578 5.2578)
			(stroke
				(width 0.2032)
				(type default)
			)
			(layer "F.Fab")
		)
		(pad "1" smd rect
			(at 0 -4.3561 180)
			(size 1.905 4.4196)
			(layers "F.Cu" "F.Mask" "F.Paste")
			(net "EXT_12.0V")
		)
		(pad "2" smd rect
			(at 0 4.3561 180)
			(size 1.905 4.4196)
			(layers "F.Cu" "F.Mask" "F.Paste")
			(net "GND")
		)
	)
	(footprint ""
		(layer "F.Cu")
		(at 42.291 43.307)
		(property "Reference" "C60"
			(at 1.29667 -2.159 90)
			(unlocked yes)
			(layer "F.SilkS")
			(effects
				(font
					(size 0.7874 0.5842)
					(thickness 0.127)
				)
				(justify left)
			)
		)
		(property "Value" "100UF"
			(at -0.78232 0.4826 90)
			(unlocked yes)
			(layer "F.Fab")
			(hide yes)
			(effects
				(font
					(size 1.27 0.9652)
					(thickness 0.000001)
				)
				(justify left)
			)
		)
		(property "Device Type" "CAPC0087"
			(at -0.78232 0.4826 90)
			(unlocked yes)
			(layer "F.Fab")
			(hide yes)
			(effects
				(font
					(size 1.27 0.9652)
					(thickness 0.000001)
				)
				(justify left)
			)
		)
		(duplicate_pad_numbers_are_jumpers no)
		(fp_circle
			(center 0 0)
			(end 0.508 0)
			(stroke
				(width 0.2032)
				(type default)
			)
			(fill no)
			(layer "F.SilkS")
		)
		(fp_circle
			(center 0 0)
			(end 0.508 0)
			(stroke
				(width 0.2032)
				(type default)
			)
			(fill no)
			(layer "F.SilkS")
		)
		(fp_poly
			(pts
				(xy -1.27 2.9464) (xy 1.27 2.9464) (xy 1.27 -2.9464) (xy -1.27 -2.9464)
			)
			(stroke
				(width 0)
				(type default)
			)
			(fill no)
			(layer "F.CrtYd")
		)
		(fp_line
			(start -1.016 -2.794)
			(end 1.016 -2.794)
			(stroke
				(width 0.0254)
				(type default)
			)
			(layer "F.Fab")
		)
		(fp_line
			(start -1.016 2.794)
			(end -1.016 -2.794)
			(stroke
				(width 0.0254)
				(type default)
			)
			(layer "F.Fab")
		)
		(fp_line
			(start 1.016 -2.794)
			(end 1.016 2.794)
			(stroke
				(width 0.0254)
				(type default)
			)
			(layer "F.Fab")
		)
		(fp_line
			(start 1.016 2.794)
			(end -1.016 2.794)
			(stroke
				(width 0.0254)
				(type default)
			)
			(layer "F.Fab")
		)
		(pad "1" smd rect
			(at 0 -1.6764)
			(size 1.524 1.524)
			(layers "F.Cu" "F.Mask" "F.Paste")
			(net "VDD_CORE")
		)
		(pad "2" smd rect
			(at 0 1.6764)
			(size 1.524 1.524)
			(layers "F.Cu" "F.Mask" "F.Paste")
			(net "GND")
		)
		(zone
			(layer "F.Cu")
			(hatch none 0.5)
			(connect_pads
				(clearance 0)
			)
			(min_thickness 0.25)
			(keepout
				(tracks not_allowed)
				(vias allowed)
				(pads allowed)
				(copperpour not_allowed)
				(footprints allowed)
			)
			(placement
				(enabled no)
				(sheetname "")
			)
			(fill
				(thermal_gap 0.5)
				(thermal_bridge_width 0.5)
				(island_removal_mode 0)
			)
			(polygon
				(pts
					(xy 41.5036 42.418) (xy 43.0784 42.418) (xy 43.0784 42.5704) (xy 41.5036 42.5704)
				)
			)
		)
		(zone
			(layer "F.Cu")
			(hatch none 0.5)
			(connect_pads
				(clearance 0)
			)
			(min_thickness 0.25)
			(keepout
				(tracks not_allowed)
				(vias allowed)
				(pads allowed)
				(copperpour not_allowed)
				(footprints allowed)
			)
			(placement
				(enabled no)
				(sheetname "")
			)
			(fill
				(thermal_gap 0.5)
				(thermal_bridge_width 0.5)
				(island_removal_mode 0)
			)
			(polygon
				(pts
					(xy 41.5036 44.0436) (xy 43.0784 44.0436) (xy 43.0784 44.196) (xy 41.5036 44.196)
				)
			)
		)
		(zone
			(layer "F.Cu")
			(hatch none 0.5)
			(connect_pads
				(clearance 0)
			)
			(min_thickness 0.25)
			(keepout
				(tracks allowed)
				(vias not_allowed)
				(pads allowed)
				(copperpour not_allowed)
				(footprints allowed)
			)
			(placement
				(enabled no)
				(sheetname "")
			)
			(fill
				(thermal_gap 0.5)
				(thermal_bridge_width 0.5)
				(island_removal_mode 0)
			)
			(polygon
				(pts
					(xy 41.5036 44.9072) (xy 43.0784 44.9072) (xy 43.0784 41.7068) (xy 41.5036 41.7068)
				)
			)
		)
	)
	(footprint ""
		(layer "F.Cu")
		(at 23.6601 6.35 -90)
		(property "Reference" "R382"
			(at 0.15367 -0.8509 0)
			(unlocked yes)
			(layer "F.SilkS")
			(effects
				(font
					(size 0.7874 0.5842)
					(thickness 0.127)
				)
				(justify left)
			)
		)
		(property "Value" "0"
			(at -0.148158 1.3462 0)
			(unlocked yes)
			(layer "F.Fab")
			(hide yes)
			(effects
				(font
					(size 1.27 0.9652)
					(thickness 0.000001)
				)
				(justify left)
			)
		)
		(property "Device Type" "REST1111"
			(at -0.148158 1.3462 0)
			(unlocked yes)
			(layer "F.Fab")
			(hide yes)
			(effects
				(font
					(size 1.27 0.9652)
					(thickness 0.000001)
				)
				(justify left)
			)
		)
		(duplicate_pad_numbers_are_jumpers no)
		(fp_poly
			(pts
				(xy 0.635 1.0668) (xy 0.635 -1.0668) (xy -0.635 -1.0668) (xy -0.635 1.0668)
			)
			(stroke
				(width 0)
				(type default)
			)
			(fill no)
			(layer "F.CrtYd")
		)
		(fp_line
			(start -0.254 0.508)
			(end -0.254 -0.508)
			(stroke
				(width 0.0254)
				(type default)
			)
			(layer "F.Fab")
		)
		(fp_line
			(start 0.254 0.508)
			(end -0.254 0.508)
			(stroke
				(width 0.0254)
				(type default)
			)
			(layer "F.Fab")
		)
		(fp_line
			(start -0.254 -0.508)
			(end 0.254 -0.508)
			(stroke
				(width 0.0254)
				(type default)
			)
			(layer "F.Fab")
		)
		(fp_line
			(start 0.254 -0.508)
			(end 0.254 0.508)
			(stroke
				(width 0.0254)
				(type default)
			)
			(layer "F.Fab")
		)
		(pad "1" smd rect
			(at 0 -0.4191 270)
			(size 0.508 0.5334)
			(layers "F.Cu" "F.Mask" "F.Paste")
			(net "NFP_SMBUS_SDA")
		)
		(pad "2" smd rect
			(at 0 0.4191 270)
			(size 0.508 0.5334)
			(layers "F.Cu" "F.Mask" "F.Paste")
			(net "MUX_NFP_SMBUS_SDA")
		)
		(zone
			(layer "F.Cu")
			(hatch none 0.5)
			(connect_pads
				(clearance 0)
			)
			(min_thickness 0.25)
			(keepout
				(tracks not_allowed)
				(vias allowed)
				(pads allowed)
				(copperpour not_allowed)
				(footprints allowed)
			)
			(placement
				(enabled no)
				(sheetname "")
			)
			(fill
				(thermal_gap 0.5)
				(thermal_bridge_width 0.5)
				(island_removal_mode 0)
			)
			(polygon
				(pts
					(xy 23.6855 6.3754) (xy 23.6347 6.3754) (xy 23.6347 6.3246) (xy 23.6855 6.3246)
				)
			)
		)
	)
	(footprint ""
		(layer "F.Cu")
		(at 77.343 46.863 180)
		(property "Reference" "L9"
			(at 2.25933 -0.127 90)
			(unlocked yes)
			(layer "F.SilkS")
			(effects
				(font
					(size 0.7874 0.5842)
					(thickness 0.127)
				)
				(justify left)
			)
		)
		(property "Value" "1.0UH"
			(at -0.483362 -0.148082 180)
			(unlocked yes)
			(layer "F.Fab")
			(hide yes)
			(effects
				(font
					(size 1.27 0.9652)
					(thickness 0.000001)
				)
				(justify left)
			)
		)
		(property "Device Type" "INDS0061"
			(at -0.483362 -0.148082 180)
			(unlocked yes)
			(layer "F.Fab")
			(hide yes)
			(effects
				(font
					(size 1.27 0.9652)
					(thickness 0.000001)
				)
				(justify left)
			)
		)
		(duplicate_pad_numbers_are_jumpers no)
		(fp_line
			(start 1.27 1.397)
			(end -1.27 1.397)
			(stroke
				(width 0.1524)
				(type default)
			)
			(layer "F.SilkS")
		)
		(fp_line
			(start -1.27 -1.397)
			(end 1.27 -1.397)
			(stroke
				(width 0.1524)
				(type default)
			)
			(layer "F.SilkS")
		)
		(fp_poly
			(pts
				(xy 2.159 -1.651) (xy 2.159 1.651) (xy -2.159 1.651) (xy -2.159 -1.651)
			)
			(stroke
				(width 0)
				(type default)
			)
			(fill no)
			(layer "F.CrtYd")
		)
		(fp_line
			(start 1.3462 1.1049)
			(end 1.3462 -1.1049)
			(stroke
				(width 0.1524)
				(type default)
			)
			(layer "F.Fab")
		)
		(fp_line
			(start 1.3462 -1.1049)
			(end -1.3462 -1.1049)
			(stroke
				(width 0.1524)
				(type default)
			)
			(layer "F.Fab")
		)
		(fp_line
			(start -1.3462 1.1049)
			(end 1.3462 1.1049)
			(stroke
				(width 0.1524)
				(type default)
			)
			(layer "F.Fab")
		)
		(fp_line
			(start -1.3462 -1.1049)
			(end -1.3462 1.1049)
			(stroke
				(width 0.1524)
				(type default)
			)
			(layer "F.Fab")
		)
		(pad "1" smd rect
			(at -1.1303 0 180)
			(size 1.1938 2.3368)
			(layers "F.Cu" "F.Mask" "F.Paste")
			(net "11N2253")
		)
		(pad "2" smd rect
			(at 1.1303 0 180)
			(size 1.1938 2.3368)
			(layers "F.Cu" "F.Mask" "F.Paste")
			(net "DDR_VDDQ")
		)
		(zone
			(layer "F.Cu")
			(hatch none 0.5)
			(connect_pads
				(clearance 0)
			)
			(min_thickness 0.25)
			(keepout
				(tracks allowed)
				(vias not_allowed)
				(pads allowed)
				(copperpour not_allowed)
				(footprints allowed)
			)
			(placement
				(enabled no)
				(sheetname "")
			)
			(fill
				(thermal_gap 0.5)
				(thermal_bridge_width 0.5)
				(island_removal_mode 0)
			)
			(polygon
				(pts
					(xy 78.6892 45.7581) (xy 76.327 45.7581) (xy 76.327 47.9679) (xy 78.6892 47.9679)
				)
			)
		)
	)
	(footprint ""
		(layer "F.Cu")
		(at 22.606 32.893 180)
		(property "Reference" "U12"
			(at 3.683 2.38633 0)
			(unlocked yes)
			(layer "F.SilkS")
			(effects
				(font
					(size 0.7874 0.5842)
					(thickness 0.127)
				)
				(justify left)
			)
		)
		(property "Value" "*"
			(at -0.4826 -0.148107 180)
			(unlocked yes)
			(layer "F.Fab")
			(hide yes)
			(effects
				(font
					(size 1.27 0.9652)
					(thickness 0.000001)
				)
				(justify left)
			)
		)
		(property "Device Type" "ICSO0128"
			(at -0.4826 -0.148107 180)
			(unlocked yes)
			(layer "F.Fab")
			(hide yes)
			(effects
				(font
					(size 1.27 0.9652)
					(thickness 0.000001)
				)
				(justify left)
			)
		)
		(duplicate_pad_numbers_are_jumpers no)
		(fp_line
			(start 2.159 1.651)
			(end 2.159 0.762)
			(stroke
				(width 0.1524)
				(type default)
			)
			(layer "F.SilkS")
		)
		(fp_line
			(start 2.159 1.651)
			(end 2.159 0.762)
			(stroke
				(width 0.1524)
				(type default)
			)
			(layer "F.SilkS")
		)
		(fp_line
			(start 2.159 -1.651)
			(end 2.159 -0.762)
			(stroke
				(width 0.1524)
				(type default)
			)
			(layer "F.SilkS")
		)
		(fp_line
			(start 2.159 -1.651)
			(end 2.159 -0.762)
			(stroke
				(width 0.1524)
				(type default)
			)
			(layer "F.SilkS")
		)
		(fp_line
			(start 1.778 1.651)
			(end 2.159 1.651)
			(stroke
				(width 0.1524)
				(type default)
			)
			(layer "F.SilkS")
		)
		(fp_line
			(start 1.778 -1.651)
			(end 2.159 -1.651)
			(stroke
				(width 0.1524)
				(type default)
			)
			(layer "F.SilkS")
		)
		(fp_line
			(start -1.778 1.651)
			(end -2.159 1.651)
			(stroke
				(width 0.1524)
				(type default)
			)
			(layer "F.SilkS")
		)
		(fp_line
			(start -1.778 1.651)
			(end -2.159 1.143)
			(stroke
				(width 0.1524)
				(type default)
			)
			(layer "F.SilkS")
		)
		(fp_line
			(start -1.778 -1.651)
			(end -2.159 -1.651)
			(stroke
				(width 0.1524)
				(type default)
			)
			(layer "F.SilkS")
		)
		(fp_line
			(start -2.159 1.651)
			(end -2.159 0.762)
			(stroke
				(width 0.1524)
				(type default)
			)
			(layer "F.SilkS")
		)
		(fp_line
			(start -2.159 -1.651)
			(end -2.159 -0.762)
			(stroke
				(width 0.1524)
				(type default)
			)
			(layer "F.SilkS")
		)
		(fp_arc
			(start -1.651 2.159)
			(mid -1.725395 2.338605)
			(end -1.905 2.413)
			(stroke
				(width 0.1524)
				(type default)
			)
			(layer "F.SilkS")
		)
		(fp_arc
			(start -1.70213 2.006168)
			(mid -1.664125 2.078422)
			(end -1.651 2.159)
			(stroke
				(width 0.1524)
				(type default)
			)
			(layer "F.SilkS")
		)
		(fp_arc
			(start -1.905 2.413)
			(mid -2.084605 2.338605)
			(end -2.159 2.159)
			(stroke
				(width 0.1524)
				(type default)
			)
			(layer "F.SilkS")
		)
		(fp_arc
			(start -2.159 2.159)
			(mid -2.15698 2.127227)
			(end -2.150999 2.095957)
			(stroke
				(width 0.1524)
				(type default)
			)
			(layer "F.SilkS")
		)
		(fp_circle
			(center -1.905 2.159)
			(end -2.159 2.159)
			(stroke
				(width 0.1524)
				(type default)
			)
			(fill no)
			(layer "F.SilkS")
		)
		(fp_poly
			(pts
				(xy -2.667 2.159) (xy 2.667 2.159) (xy 2.667 -2.159) (xy -2.667 -2.159)
			)
			(stroke
				(width 0)
				(type default)
			)
			(fill no)
			(layer "F.CrtYd")
		)
		(fp_line
			(start 1.8034 1.2954)
			(end 1.8034 -1.2954)
			(stroke
				(width 0.1524)
				(type default)
			)
			(layer "F.Fab")
		)
		(fp_line
			(start 1.8034 -1.2954)
			(end -1.8034 -1.2954)
			(stroke
				(width 0.1524)
				(type default)
			)
			(layer "F.Fab")
		)
		(fp_line
			(start -1.8034 1.2954)
			(end 1.8034 1.2954)
			(stroke
				(width 0.1524)
				(type default)
			)
			(layer "F.Fab")
		)
		(fp_line
			(start -1.8034 -1.2954)
			(end -1.8034 1.2954)
			(stroke
				(width 0.1524)
				(type default)
			)
			(layer "F.Fab")
		)
		(fp_circle
			(center -1.27 0.762)
			(end -1.553997 0.762)
			(stroke
				(width 0.1524)
				(type default)
			)
			(fill no)
			(layer "F.Fab")
		)
		(fp_text user "10"
			(at 3.683 -1.67767 0)
			(unlocked yes)
			(layer "F.SilkS")
			(effects
				(font
					(size 0.7874 0.5842)
					(thickness 0.127)
				)
				(justify left)
			)
		)
		(fp_text user "8"
			(at 2.8829 1.251814 0)
			(unlocked yes)
			(layer "F.SilkS")
			(effects
				(font
					(size 0.7874 0.5842)
					(thickness 0.127)
				)
				(justify left)
			)
		)
		(fp_text user "9"
			(at 2.794 -0.15367 0)
			(unlocked yes)
			(layer "F.SilkS")
			(effects
				(font
					(size 0.7874 0.5842)
					(thickness 0.127)
				)
				(justify left)
			)
		)
		(fp_text user "7"
			(at 0.86233 1.905 90)
			(unlocked yes)
			(layer "F.SilkS")
			(effects
				(font
					(size 0.7874 0.5842)
					(thickness 0.127)
				)
				(justify left)
			)
		)
		(fp_text user "2"
			(at -0.889 2.38633 0)
			(unlocked yes)
			(layer "F.SilkS")
			(effects
				(font
					(size 0.7874 0.5842)
					(thickness 0.127)
				)
				(justify left)
			)
		)
		(fp_text user "15"
			(at -1.397 -1.80467 0)
			(unlocked yes)
			(layer "F.SilkS")
			(effects
				(font
					(size 0.7874 0.5842)
					(thickness 0.127)
				)
				(justify left)
			)
		)
		(fp_text user "1"
			(at -2.159 0.60833 0)
			(unlocked yes)
			(layer "F.SilkS")
			(effects
				(font
					(size 0.7874 0.5842)
					(thickness 0.127)
				)
				(justify left)
			)
		)
		(fp_text user "16"
			(at -2.159 -0.53467 0)
			(unlocked yes)
			(layer "F.SilkS")
			(effects
				(font
					(size 0.7874 0.5842)
					(thickness 0.127)
				)
				(justify left)
			)
		)
		(pad "1" smd custom
			(at -1.7018 0.250012 90)
			(size 0.06985 0.06985)
			(layers "F.Cu" "F.Mask" "F.Paste")
			(net "CPLD_PGRM_JTAG_SEL")
			(options
				(clearance outline)
				(anchor circle)
			)
			(primitives
				(gr_poly
					(pts
						(xy 0.1397 0.4064)
						(arc
							(start 0.1397 -0.2667)
							(mid 0 -0.4064)
							(end -0.1397 -0.2667)
						)
						(xy -0.1397 0.4064)
					)
					(width 0)
					(fill yes)
				)
			)
		)
		(pad "2" smd custom
			(at -1.25001 1.1938 180)
			(size 0.06985 0.06985)
			(layers "F.Cu" "F.Mask" "F.Paste")
			(net "DEBUG_CPLD_PGRM_JTAG_TCK")
			(options
				(clearance outline)
				(anchor circle)
			)
			(primitives
				(gr_poly
					(pts
						(xy 0.1397 0.4064)
						(arc
							(start 0.1397 -0.2667)
							(mid 0 -0.4064)
							(end -0.1397 -0.2667)
						)
						(xy -0.1397 0.4064)
					)
					(width 0)
					(fill yes)
				)
			)
		)
		(pad "3" smd custom
			(at -0.750011 1.1938 180)
			(size 0.06985 0.06985)
			(layers "F.Cu" "F.Mask" "F.Paste")
			(net "NFP_CPLD_PRGM_JTAG_TCK")
			(options
				(clearance outline)
				(anchor circle)
			)
			(primitives
				(gr_poly
					(pts
						(xy 0.1397 0.4064)
						(arc
							(start 0.1397 -0.2667)
							(mid 0 -0.4064)
							(end -0.1397 -0.2667)
						)
						(xy -0.1397 0.4064)
					)
					(width 0)
					(fill yes)
				)
			)
		)
		(pad "4" smd custom
			(at -0.250012 1.1938 180)
			(size 0.06985 0.06985)
			(layers "F.Cu" "F.Mask" "F.Paste")
			(net "CPLD_PGRM_JTAG_TCK")
			(options
				(clearance outline)
				(anchor circle)
			)
			(primitives
				(gr_poly
					(pts
						(xy 0.1397 0.4064)
						(arc
							(start 0.1397 -0.2667)
							(mid 0 -0.4064)
							(end -0.1397 -0.2667)
						)
						(xy -0.1397 0.4064)
					)
					(width 0)
					(fill yes)
				)
			)
		)
		(pad "5" smd custom
			(at 0.250012 1.1938 180)
			(size 0.06985 0.06985)
			(layers "F.Cu" "F.Mask" "F.Paste")
			(net "DEBUG_CPLD_PGRM_JTAG_TDI")
			(options
				(clearance outline)
				(anchor circle)
			)
			(primitives
				(gr_poly
					(pts
						(xy 0.1397 0.4064)
						(arc
							(start 0.1397 -0.2667)
							(mid 0 -0.4064)
							(end -0.1397 -0.2667)
						)
						(xy -0.1397 0.4064)
					)
					(width 0)
					(fill yes)
				)
			)
		)
		(pad "6" smd custom
			(at 0.750011 1.1938 180)
			(size 0.06985 0.06985)
			(layers "F.Cu" "F.Mask" "F.Paste")
			(net "NFP_CPLD_PRGM_JTAG_TDI")
			(options
				(clearance outline)
				(anchor circle)
			)
			(primitives
				(gr_poly
					(pts
						(xy 0.1397 0.4064)
						(arc
							(start 0.1397 -0.2667)
							(mid 0 -0.4064)
							(end -0.1397 -0.2667)
						)
						(xy -0.1397 0.4064)
					)
					(width 0)
					(fill yes)
				)
			)
		)
		(pad "7" smd custom
			(at 1.25001 1.1938 180)
			(size 0.06985 0.06985)
			(layers "F.Cu" "F.Mask" "F.Paste")
			(net "CPLD_PGRM_JTAG_TDI")
			(options
				(clearance outline)
				(anchor circle)
			)
			(primitives
				(gr_poly
					(pts
						(xy 0.1397 0.4064)
						(arc
							(start 0.1397 -0.2667)
							(mid 0 -0.4064)
							(end -0.1397 -0.2667)
						)
						(xy -0.1397 0.4064)
					)
					(width 0)
					(fill yes)
				)
			)
		)
		(pad "8" smd custom
			(at 1.7018 0.250012 270)
			(size 0.06985 0.06985)
			(layers "F.Cu" "F.Mask" "F.Paste")
			(net "GND")
			(options
				(clearance outline)
				(anchor circle)
			)
			(primitives
				(gr_poly
					(pts
						(xy 0.1397 0.4064)
						(arc
							(start 0.1397 -0.2667)
							(mid 0 -0.4064)
							(end -0.1397 -0.2667)
						)
						(xy -0.1397 0.4064)
					)
					(width 0)
					(fill yes)
				)
			)
		)
		(pad "9" smd custom
			(at 1.7018 -0.250012 270)
			(size 0.06985 0.06985)
			(layers "F.Cu" "F.Mask" "F.Paste")
			(net "CPLD_PGRM_JTAG_TDO")
			(options
				(clearance outline)
				(anchor circle)
			)
			(primitives
				(gr_poly
					(pts
						(xy 0.1397 0.4064)
						(arc
							(start 0.1397 -0.2667)
							(mid 0 -0.4064)
							(end -0.1397 -0.2667)
						)
						(xy -0.1397 0.4064)
					)
					(width 0)
					(fill yes)
				)
			)
		)
		(pad "10" smd custom
			(at 1.25001 -1.1938)
			(size 0.06985 0.06985)
			(layers "F.Cu" "F.Mask" "F.Paste")
			(net "NFP_CPLD_PRGM_JTAG_TDO")
			(options
				(clearance outline)
				(anchor circle)
			)
			(primitives
				(gr_poly
					(pts
						(xy 0.1397 0.4064)
						(arc
							(start 0.1397 -0.2667)
							(mid 0 -0.4064)
							(end -0.1397 -0.2667)
						)
						(xy -0.1397 0.4064)
					)
					(width 0)
					(fill yes)
				)
			)
		)
		(pad "11" smd custom
			(at 0.750011 -1.1938)
			(size 0.06985 0.06985)
			(layers "F.Cu" "F.Mask" "F.Paste")
			(net "DEBUG_CPLD_PGRM_JTAG_TDO")
			(options
				(clearance outline)
				(anchor circle)
			)
			(primitives
				(gr_poly
					(pts
						(xy 0.1397 0.4064)
						(arc
							(start 0.1397 -0.2667)
							(mid 0 -0.4064)
							(end -0.1397 -0.2667)
						)
						(xy -0.1397 0.4064)
					)
					(width 0)
					(fill yes)
				)
			)
		)
		(pad "12" smd custom
			(at 0.250012 -1.1938)
			(size 0.06985 0.06985)
			(layers "F.Cu" "F.Mask" "F.Paste")
			(net "CPLD_PGRM_JTAG_TMS")
			(options
				(clearance outline)
				(anchor circle)
			)
			(primitives
				(gr_poly
					(pts
						(xy 0.1397 0.4064)
						(arc
							(start 0.1397 -0.2667)
							(mid 0 -0.4064)
							(end -0.1397 -0.2667)
						)
						(xy -0.1397 0.4064)
					)
					(width 0)
					(fill yes)
				)
			)
		)
		(pad "13" smd custom
			(at -0.250012 -1.1938)
			(size 0.06985 0.06985)
			(layers "F.Cu" "F.Mask" "F.Paste")
			(net "NFP_CPLD_PRGM_JTAG_TMS")
			(options
				(clearance outline)
				(anchor circle)
			)
			(primitives
				(gr_poly
					(pts
						(xy 0.1397 0.4064)
						(arc
							(start 0.1397 -0.2667)
							(mid 0 -0.4064)
							(end -0.1397 -0.2667)
						)
						(xy -0.1397 0.4064)
					)
					(width 0)
					(fill yes)
				)
			)
		)
		(pad "14" smd custom
			(at -0.750011 -1.1938)
			(size 0.06985 0.06985)
			(layers "F.Cu" "F.Mask" "F.Paste")
			(net "DEBUG_CPLD_PGRM_JTAG_TMS")
			(options
				(clearance outline)
				(anchor circle)
			)
			(primitives
				(gr_poly
					(pts
						(xy 0.1397 0.4064)
						(arc
							(start 0.1397 -0.2667)
							(mid 0 -0.4064)
							(end -0.1397 -0.2667)
						)
						(xy -0.1397 0.4064)
					)
					(width 0)
					(fill yes)
				)
			)
		)
		(pad "15" smd custom
			(at -1.25001 -1.1938)
			(size 0.06985 0.06985)
			(layers "F.Cu" "F.Mask" "F.Paste")
			(net "9N2032")
			(options
				(clearance outline)
				(anchor circle)
			)
			(primitives
				(gr_poly
					(pts
						(xy 0.1397 0.4064)
						(arc
							(start 0.1397 -0.2667)
							(mid 0 -0.4064)
							(end -0.1397 -0.2667)
						)
						(xy -0.1397 0.4064)
					)
					(width 0)
					(fill yes)
				)
			)
		)
		(pad "16" smd custom
			(at -1.7018 -0.250012 90)
			(size 0.06985 0.06985)
			(layers "F.Cu" "F.Mask" "F.Paste")
			(net "EXT_3.3V")
			(options
				(clearance outline)
				(anchor circle)
			)
			(primitives
				(gr_poly
					(pts
						(xy 0.1397 0.4064)
						(arc
							(start 0.1397 -0.2667)
							(mid 0 -0.4064)
							(end -0.1397 -0.2667)
						)
						(xy -0.1397 0.4064)
					)
					(width 0)
					(fill yes)
				)
			)
		)
		(pad "17" smd rect
			(at 0 0 180)
			(size 1.9812 0.9652)
			(layers "F.Cu" "F.Mask" "F.Paste")
			(net "GND")
		)
		(zone
			(layer "F.Cu")
			(hatch none 0.5)
			(connect_pads
				(clearance 0)
			)
			(min_thickness 0.25)
			(keepout
				(tracks allowed)
				(vias not_allowed)
				(pads allowed)
				(copperpour not_allowed)
				(footprints allowed)
			)
			(placement
				(enabled no)
				(sheetname "")
			)
			(fill
				(thermal_gap 0.5)
				(thermal_bridge_width 0.5)
				(island_removal_mode 0)
			)
			(polygon
				(pts
					(arc
						(start 24.8412 30.734)
						(mid 24.1808 30.734)
						(end 24.8412 30.734)
					)
				)
			)
		)
	)
	(footprint ""
		(layer "F.Cu")
		(at -1.016 33.147)
		(property "Reference" "TP64"
			(at -1.37033 1.778 90)
			(unlocked yes)
			(layer "F.SilkS")
			(effects
				(font
					(size 0.7874 0.5842)
					(thickness 0.127)
				)
				(justify left)
			)
		)
		(property "Value" "*"
			(at -0.4826 -0.14732 0)
			(unlocked yes)
			(layer "F.Fab")
			(hide yes)
			(effects
				(font
					(size 1.27 0.9652)
					(thickness 0.000001)
				)
				(justify left)
			)
		)
		(property "Device Type" "TP_SMALL"
			(at -0.4826 -0.14732 0)
			(unlocked yes)
			(layer "F.Fab")
			(hide yes)
			(effects
				(font
					(size 1.27 0.9652)
					(thickness 0.000001)
				)
				(justify left)
			)
		)
		(duplicate_pad_numbers_are_jumpers no)
		(fp_line
			(start -0.8636 -0.8636)
			(end -0.8636 0.8636)
			(stroke
				(width 0.1524)
				(type default)
			)
			(layer "F.SilkS")
		)
		(fp_line
			(start -0.8636 0.8636)
			(end 0.8636 0.8636)
			(stroke
				(width 0.1524)
				(type default)
			)
			(layer "F.SilkS")
		)
		(fp_line
			(start 0.8636 -0.8636)
			(end -0.8636 -0.8636)
			(stroke
				(width 0.1524)
				(type default)
			)
			(layer "F.SilkS")
		)
		(fp_line
			(start 0.8636 0.8636)
			(end 0.8636 -0.8636)
			(stroke
				(width 0.1524)
				(type default)
			)
			(layer "F.SilkS")
		)
		(fp_poly
			(pts
				(xy -0.635 -0.635) (xy -0.635 0.635) (xy 0.635 0.635) (xy 0.635 -0.635)
			)
			(stroke
				(width 0)
				(type default)
			)
			(fill no)
			(layer "F.CrtYd")
		)
		(pad "1" smd rect
			(at 0 0)
			(size 1.27 1.27)
			(layers "F.Cu" "F.Mask" "F.Paste")
			(net "VDD_7401_PGOOD")
		)
	)
	(footprint ""
		(layer "F.Cu")
		(at 11.303 1.397)
		(property "Reference" "R368"
			(at 0.196012 -1.4732 90)
			(unlocked yes)
			(layer "F.SilkS")
			(effects
				(font
					(size 0.7874 0.5842)
					(thickness 0.127)
				)
				(justify left)
			)
		)
		(property "Value" "0"
			(at -0.148158 1.3462 90)
			(unlocked yes)
			(layer "F.Fab")
			(hide yes)
			(effects
				(font
					(size 1.27 0.9652)
					(thickness 0.000001)
				)
				(justify left)
			)
		)
		(property "Device Type" "REST1111"
			(at -0.148158 1.3462 90)
			(unlocked yes)
			(layer "F.Fab")
			(hide yes)
			(effects
				(font
					(size 1.27 0.9652)
					(thickness 0.000001)
				)
				(justify left)
			)
		)
		(duplicate_pad_numbers_are_jumpers no)
		(fp_poly
			(pts
				(xy 0.635 1.0668) (xy 0.635 -1.0668) (xy -0.635 -1.0668) (xy -0.635 1.0668)
			)
			(stroke
				(width 0)
				(type default)
			)
			(fill no)
			(layer "F.CrtYd")
		)
		(fp_line
			(start -0.254 -0.508)
			(end 0.254 -0.508)
			(stroke
				(width 0.0254)
				(type default)
			)
			(layer "F.Fab")
		)
		(fp_line
			(start -0.254 0.508)
			(end -0.254 -0.508)
			(stroke
				(width 0.0254)
				(type default)
			)
			(layer "F.Fab")
		)
		(fp_line
			(start 0.254 -0.508)
			(end 0.254 0.508)
			(stroke
				(width 0.0254)
				(type default)
			)
			(layer "F.Fab")
		)
		(fp_line
			(start 0.254 0.508)
			(end -0.254 0.508)
			(stroke
				(width 0.0254)
				(type default)
			)
			(layer "F.Fab")
		)
		(pad "1" smd rect
			(at 0 -0.4191)
			(size 0.508 0.5334)
			(layers "F.Cu" "F.Mask" "F.Paste")
			(net "NFP_PCIE0_WAKE_L")
		)
		(pad "2" smd rect
			(at 0 0.4191)
			(size 0.508 0.5334)
			(layers "F.Cu" "F.Mask" "F.Paste")
			(net "PCIE0_WAKE_L")
		)
		(zone
			(layer "F.Cu")
			(hatch none 0.5)
			(connect_pads
				(clearance 0)
			)
			(min_thickness 0.25)
			(keepout
				(tracks not_allowed)
				(vias allowed)
				(pads allowed)
				(copperpour not_allowed)
				(footprints allowed)
			)
			(placement
				(enabled no)
				(sheetname "")
			)
			(fill
				(thermal_gap 0.5)
				(thermal_bridge_width 0.5)
				(island_removal_mode 0)
			)
			(polygon
				(pts
					(xy 11.3284 1.3716) (xy 11.3284 1.4224) (xy 11.2776 1.4224) (xy 11.2776 1.3716)
				)
			)
		)
	)
	(footprint ""
		(layer "F.Cu")
		(at 34.925 43.0276)
		(property "Reference" "R327"
			(at 0.15367 3.556 90)
			(unlocked yes)
			(layer "F.SilkS")
			(effects
				(font
					(size 0.7874 0.5842)
					(thickness 0.127)
				)
				(justify left)
			)
		)
		(property "Value" "750"
			(at -0.148158 1.3462 90)
			(unlocked yes)
			(layer "F.Fab")
			(hide yes)
			(effects
				(font
					(size 1.27 0.9652)
					(thickness 0.000001)
				)
				(justify left)
			)
		)
		(property "Device Type" "REST0185"
			(at -0.148158 1.3462 90)
			(unlocked yes)
			(layer "F.Fab")
			(hide yes)
			(effects
				(font
					(size 1.27 0.9652)
					(thickness 0.000001)
				)
				(justify left)
			)
		)
		(duplicate_pad_numbers_are_jumpers no)
		(fp_poly
			(pts
				(xy 0.635 1.0668) (xy 0.635 -1.0668) (xy -0.635 -1.0668) (xy -0.635 1.0668)
			)
			(stroke
				(width 0)
				(type default)
			)
			(fill no)
			(layer "F.CrtYd")
		)
		(fp_line
			(start -0.254 -0.508)
			(end 0.254 -0.508)
			(stroke
				(width 0.0254)
				(type default)
			)
			(layer "F.Fab")
		)
		(fp_line
			(start -0.254 0.508)
			(end -0.254 -0.508)
			(stroke
				(width 0.0254)
				(type default)
			)
			(layer "F.Fab")
		)
		(fp_line
			(start 0.254 -0.508)
			(end 0.254 0.508)
			(stroke
				(width 0.0254)
				(type default)
			)
			(layer "F.Fab")
		)
		(fp_line
			(start 0.254 0.508)
			(end -0.254 0.508)
			(stroke
				(width 0.0254)
				(type default)
			)
			(layer "F.Fab")
		)
		(pad "1" smd rect
			(at 0 -0.4191)
			(size 0.508 0.5334)
			(layers "F.Cu" "F.Mask" "F.Paste")
			(net "10N2381")
		)
		(pad "2" smd rect
			(at 0 0.4191)
			(size 0.508 0.5334)
			(layers "F.Cu" "F.Mask" "F.Paste")
			(net "NFP_VDD_CORE_TCOMPA")
		)
		(zone
			(layer "F.Cu")
			(hatch none 0.5)
			(connect_pads
				(clearance 0)
			)
			(min_thickness 0.25)
			(keepout
				(tracks not_allowed)
				(vias allowed)
				(pads allowed)
				(copperpour not_allowed)
				(footprints allowed)
			)
			(placement
				(enabled no)
				(sheetname "")
			)
			(fill
				(thermal_gap 0.5)
				(thermal_bridge_width 0.5)
				(island_removal_mode 0)
			)
			(polygon
				(pts
					(xy 34.9504 43.0022) (xy 34.9504 43.053) (xy 34.8996 43.053) (xy 34.8996 43.0022)
				)
			)
		)
	)
	(footprint ""
		(layer "F.Cu")
		(at 80.137 26.924)
		(property "Reference" "R227"
			(at 0 0 0)
			(layer "F.SilkS")
			(hide yes)
			(effects
				(font
					(size 1.27 1.27)
				)
			)
		)
		(property "Value" "39.0"
			(at -0.148158 1.3462 90)
			(unlocked yes)
			(layer "F.Fab")
			(hide yes)
			(effects
				(font
					(size 1.27 0.9652)
					(thickness 0.000001)
				)
				(justify left)
			)
		)
		(property "Device Type" "REST0108"
			(at -0.148158 1.3462 90)
			(unlocked yes)
			(layer "F.Fab")
			(hide yes)
			(effects
				(font
					(size 1.27 0.9652)
					(thickness 0.000001)
				)
				(justify left)
			)
		)
		(duplicate_pad_numbers_are_jumpers no)
		(fp_poly
			(pts
				(xy 0.635 1.0668) (xy 0.635 -1.0668) (xy -0.635 -1.0668) (xy -0.635 1.0668)
			)
			(stroke
				(width 0)
				(type default)
			)
			(fill no)
			(layer "F.CrtYd")
		)
		(fp_line
			(start -0.254 -0.508)
			(end 0.254 -0.508)
			(stroke
				(width 0.0254)
				(type default)
			)
			(layer "F.Fab")
		)
		(fp_line
			(start -0.254 0.508)
			(end -0.254 -0.508)
			(stroke
				(width 0.0254)
				(type default)
			)
			(layer "F.Fab")
		)
		(fp_line
			(start 0.254 -0.508)
			(end 0.254 0.508)
			(stroke
				(width 0.0254)
				(type default)
			)
			(layer "F.Fab")
		)
		(fp_line
			(start 0.254 0.508)
			(end -0.254 0.508)
			(stroke
				(width 0.0254)
				(type default)
			)
			(layer "F.Fab")
		)
		(pad "1" smd rect
			(at 0 -0.4191)
			(size 0.508 0.5334)
			(layers "F.Cu" "F.Mask" "F.Paste")
			(net "DDR0_32A_WE_L")
		)
		(pad "2" smd rect
			(at 0 0.4191)
			(size 0.508 0.5334)
			(layers "F.Cu" "F.Mask" "F.Paste")
			(net "DDR_VTT")
		)
		(zone
			(layer "F.Cu")
			(hatch none 0.5)
			(connect_pads
				(clearance 0)
			)
			(min_thickness 0.25)
			(keepout
				(tracks not_allowed)
				(vias allowed)
				(pads allowed)
				(copperpour not_allowed)
				(footprints allowed)
			)
			(placement
				(enabled no)
				(sheetname "")
			)
			(fill
				(thermal_gap 0.5)
				(thermal_bridge_width 0.5)
				(island_removal_mode 0)
			)
			(polygon
				(pts
					(xy 80.1624 26.8986) (xy 80.1624 26.9494) (xy 80.1116 26.9494) (xy 80.1116 26.8986)
				)
			)
		)
	)
	(footprint ""
		(layer "F.Cu")
		(at 53.086 54.5338 -90)
		(property "Reference" "C65"
			(at 1.49987 1.016 0)
			(unlocked yes)
			(layer "F.SilkS")
			(effects
				(font
					(size 0.7874 0.5842)
					(thickness 0.127)
				)
				(justify left)
			)
		)
		(property "Value" "100UF"
			(at -0.78232 0.4826 0)
			(unlocked yes)
			(layer "F.Fab")
			(hide yes)
			(effects
				(font
					(size 1.27 0.9652)
					(thickness 0.000001)
				)
				(justify left)
			)
		)
		(property "Device Type" "CAPC0087"
			(at -0.78232 0.4826 0)
			(unlocked yes)
			(layer "F.Fab")
			(hide yes)
			(effects
				(font
					(size 1.27 0.9652)
					(thickness 0.000001)
				)
				(justify left)
			)
		)
		(duplicate_pad_numbers_are_jumpers no)
		(fp_circle
			(center 0 0)
			(end 0 -0.508)
			(stroke
				(width 0.2032)
				(type default)
			)
			(fill no)
			(layer "F.SilkS")
		)
		(fp_circle
			(center 0 0)
			(end 0 -0.508)
			(stroke
				(width 0.2032)
				(type default)
			)
			(fill no)
			(layer "F.SilkS")
		)
		(fp_poly
			(pts
				(xy -1.27 2.9464) (xy 1.021664 2.9464) (xy 1.021664 -2.9464) (xy -1.27 -2.9464)
			)
			(stroke
				(width 0)
				(type default)
			)
			(fill no)
			(layer "F.CrtYd")
		)
		(fp_line
			(start -1.016 2.794)
			(end -1.016 -2.794)
			(stroke
				(width 0.0254)
				(type default)
			)
			(layer "F.Fab")
		)
		(fp_line
			(start 1.016 2.794)
			(end -1.016 2.794)
			(stroke
				(width 0.0254)
				(type default)
			)
			(layer "F.Fab")
		)
		(fp_line
			(start -1.016 -2.794)
			(end 1.016 -2.794)
			(stroke
				(width 0.0254)
				(type default)
			)
			(layer "F.Fab")
		)
		(fp_line
			(start 1.016 -2.794)
			(end 1.016 2.794)
			(stroke
				(width 0.0254)
				(type default)
			)
			(layer "F.Fab")
		)
		(pad "1" smd rect
			(at 0 -1.6764 270)
			(size 1.524 1.524)
			(layers "F.Cu" "F.Mask" "F.Paste")
			(net "VDD_CORE")
		)
		(pad "2" smd rect
			(at 0 1.6764 270)
			(size 1.524 1.524)
			(layers "F.Cu" "F.Mask" "F.Paste")
			(net "GND")
		)
		(zone
			(layer "F.Cu")
			(hatch none 0.5)
			(connect_pads
				(clearance 0)
			)
			(min_thickness 0.25)
			(keepout
				(tracks allowed)
				(vias not_allowed)
				(pads allowed)
				(copperpour not_allowed)
				(footprints allowed)
			)
			(placement
				(enabled no)
				(sheetname "")
			)
			(fill
				(thermal_gap 0.5)
				(thermal_bridge_width 0.5)
				(island_removal_mode 0)
			)
			(polygon
				(pts
					(xy 51.4858 53.7464) (xy 51.4858 55.3212) (xy 54.6862 55.3212) (xy 54.6862 53.7464)
				)
			)
		)
		(zone
			(layer "F.Cu")
			(hatch none 0.5)
			(connect_pads
				(clearance 0)
			)
			(min_thickness 0.25)
			(keepout
				(tracks not_allowed)
				(vias allowed)
				(pads allowed)
				(copperpour not_allowed)
				(footprints allowed)
			)
			(placement
				(enabled no)
				(sheetname "")
			)
			(fill
				(thermal_gap 0.5)
				(thermal_bridge_width 0.5)
				(island_removal_mode 0)
			)
			(polygon
				(pts
					(xy 52.3494 53.7464) (xy 52.3494 55.3212) (xy 52.197 55.3212) (xy 52.197 53.7464)
				)
			)
		)
		(zone
			(layer "F.Cu")
			(hatch none 0.5)
			(connect_pads
				(clearance 0)
			)
			(min_thickness 0.25)
			(keepout
				(tracks not_allowed)
				(vias allowed)
				(pads allowed)
				(copperpour not_allowed)
				(footprints allowed)
			)
			(placement
				(enabled no)
				(sheetname "")
			)
			(fill
				(thermal_gap 0.5)
				(thermal_bridge_width 0.5)
				(island_removal_mode 0)
			)
			(polygon
				(pts
					(xy 53.975 53.7464) (xy 53.975 55.3212) (xy 53.8226 55.3212) (xy 53.8226 53.7464)
				)
			)
		)
	)
	(footprint ""
		(layer "F.Cu")
		(at 36.068 34.9758 90)
		(property "Reference" "C124"
			(at 0.86233 -1.27 0)
			(unlocked yes)
			(layer "F.SilkS")
			(effects
				(font
					(size 0.7874 0.5842)
					(thickness 0.127)
				)
				(justify left)
			)
		)
		(property "Value" "0.1UF"
			(at -0.091846 0.2921 180)
			(unlocked yes)
			(layer "F.Fab")
			(hide yes)
			(effects
				(font
					(size 0.7874 0.5842)
					(thickness 0.2032)
				)
				(justify left)
			)
		)
		(property "Device Type" "CAPC0073"
			(at -0.091846 0.2921 180)
			(unlocked yes)
			(layer "F.Fab")
			(hide yes)
			(effects
				(font
					(size 0.7874 0.5842)
					(thickness 0.2032)
				)
				(justify left)
			)
		)
		(duplicate_pad_numbers_are_jumpers no)
		(fp_poly
			(pts
				(xy 0.635 1.0668) (xy 0.635 -1.0668) (xy -0.635 -1.0668) (xy -0.635 1.0668)
			)
			(stroke
				(width 0)
				(type default)
			)
			(fill no)
			(layer "F.CrtYd")
		)
		(fp_line
			(start 0.254 -0.508)
			(end 0.254 0.508)
			(stroke
				(width 0.0254)
				(type default)
			)
			(layer "F.Fab")
		)
		(fp_line
			(start -0.254 -0.508)
			(end 0.254 -0.508)
			(stroke
				(width 0.0254)
				(type default)
			)
			(layer "F.Fab")
		)
		(fp_line
			(start 0.254 0.508)
			(end -0.254 0.508)
			(stroke
				(width 0.0254)
				(type default)
			)
			(layer "F.Fab")
		)
		(fp_line
			(start -0.254 0.508)
			(end -0.254 -0.508)
			(stroke
				(width 0.0254)
				(type default)
			)
			(layer "F.Fab")
		)
		(pad "1" smd rect
			(at 0 -0.4191 90)
			(size 0.508 0.5334)
			(layers "F.Cu" "F.Mask" "F.Paste")
			(net "10N2370")
		)
		(pad "2" smd rect
			(at 0 0.4191 90)
			(size 0.508 0.5334)
			(layers "F.Cu" "F.Mask" "F.Paste")
			(net "GND")
		)
		(zone
			(layer "F.Cu")
			(hatch none 0.5)
			(connect_pads
				(clearance 0)
			)
			(min_thickness 0.25)
			(keepout
				(tracks not_allowed)
				(vias allowed)
				(pads allowed)
				(copperpour not_allowed)
				(footprints allowed)
			)
			(placement
				(enabled no)
				(sheetname "")
			)
			(fill
				(thermal_gap 0.5)
				(thermal_bridge_width 0.5)
				(island_removal_mode 0)
			)
			(polygon
				(pts
					(xy 36.0426 34.9504) (xy 36.0934 34.9504) (xy 36.0934 35.0012) (xy 36.0426 35.0012)
				)
			)
		)
	)
	(footprint ""
		(layer "F.Cu")
		(at 33.6042 43.434 90)
		(property "Reference" "C34"
			(at 0 0 90)
			(layer "F.SilkS")
			(hide yes)
			(effects
				(font
					(size 1.27 1.27)
				)
			)
		)
		(property "Value" "6800PF"
			(at -0.091846 0.2921 180)
			(unlocked yes)
			(layer "F.Fab")
			(hide yes)
			(effects
				(font
					(size 0.7874 0.5842)
					(thickness 0.2032)
				)
				(justify left)
			)
		)
		(property "Device Type" "CAPC0079"
			(at -0.091846 0.2921 180)
			(unlocked yes)
			(layer "F.Fab")
			(hide yes)
			(effects
				(font
					(size 0.7874 0.5842)
					(thickness 0.2032)
				)
				(justify left)
			)
		)
		(duplicate_pad_numbers_are_jumpers no)
		(fp_poly
			(pts
				(xy 0.635 1.0668) (xy 0.635 -1.0668) (xy -0.635 -1.0668) (xy -0.635 1.0668)
			)
			(stroke
				(width 0)
				(type default)
			)
			(fill no)
			(layer "F.CrtYd")
		)
		(fp_line
			(start 0.254 -0.508)
			(end 0.254 0.508)
			(stroke
				(width 0.0254)
				(type default)
			)
			(layer "F.Fab")
		)
		(fp_line
			(start -0.254 -0.508)
			(end 0.254 -0.508)
			(stroke
				(width 0.0254)
				(type default)
			)
			(layer "F.Fab")
		)
		(fp_line
			(start 0.254 0.508)
			(end -0.254 0.508)
			(stroke
				(width 0.0254)
				(type default)
			)
			(layer "F.Fab")
		)
		(fp_line
			(start -0.254 0.508)
			(end -0.254 -0.508)
			(stroke
				(width 0.0254)
				(type default)
			)
			(layer "F.Fab")
		)
		(pad "1" smd rect
			(at 0 -0.4191 90)
			(size 0.508 0.5334)
			(layers "F.Cu" "F.Mask" "F.Paste")
			(net "10N2528")
		)
		(pad "2" smd rect
			(at 0 0.4191 90)
			(size 0.508 0.5334)
			(layers "F.Cu" "F.Mask" "F.Paste")
			(net "NFP_VDD_CORE_TCOMPA")
		)
		(zone
			(layer "F.Cu")
			(hatch none 0.5)
			(connect_pads
				(clearance 0)
			)
			(min_thickness 0.25)
			(keepout
				(tracks not_allowed)
				(vias allowed)
				(pads allowed)
				(copperpour not_allowed)
				(footprints allowed)
			)
			(placement
				(enabled no)
				(sheetname "")
			)
			(fill
				(thermal_gap 0.5)
				(thermal_bridge_width 0.5)
				(island_removal_mode 0)
			)
			(polygon
				(pts
					(xy 33.5788 43.4086) (xy 33.6296 43.4086) (xy 33.6296 43.4594) (xy 33.5788 43.4594)
				)
			)
		)
	)
	(footprint ""
		(layer "F.Cu")
		(at 18.3515 34.3281 180)
		(property "Reference" "C23"
			(at -0.02667 -3.556 90)
			(unlocked yes)
			(layer "F.SilkS")
			(effects
				(font
					(size 0.7874 0.5842)
					(thickness 0.127)
				)
				(justify left)
			)
		)
		(property "Value" "22UF"
			(at -0.148158 1.7526 270)
			(unlocked yes)
			(layer "F.Fab")
			(hide yes)
			(effects
				(font
					(size 1.27 0.9652)
					(thickness 0.000001)
				)
				(justify left)
			)
		)
		(property "Device Type" "CAPC0063"
			(at -0.148158 1.7526 270)
			(unlocked yes)
			(layer "F.Fab")
			(hide yes)
			(effects
				(font
					(size 1.27 0.9652)
					(thickness 0.000001)
				)
				(justify left)
			)
		)
		(duplicate_pad_numbers_are_jumpers no)
		(fp_circle
			(center 0 0)
			(end -0.127 0)
			(stroke
				(width 0.2032)
				(type default)
			)
			(fill no)
			(layer "F.SilkS")
		)
		(fp_poly
			(pts
				(xy 0.7874 -1.6637) (xy -0.7874 -1.6637) (xy -0.7874 1.6637) (xy 0.7874 1.6637)
			)
			(stroke
				(width 0)
				(type default)
			)
			(fill no)
			(layer "F.CrtYd")
		)
		(fp_line
			(start 0.4064 0.8128)
			(end -0.4064 0.8128)
			(stroke
				(width 0.0254)
				(type default)
			)
			(layer "F.Fab")
		)
		(fp_line
			(start 0.4064 -0.7874)
			(end 0.4064 0.8128)
			(stroke
				(width 0.0254)
				(type default)
			)
			(layer "F.Fab")
		)
		(fp_line
			(start -0.4064 0.8128)
			(end -0.4064 -0.7874)
			(stroke
				(width 0.0254)
				(type default)
			)
			(layer "F.Fab")
		)
		(fp_line
			(start -0.4064 -0.7874)
			(end 0.4064 -0.7874)
			(stroke
				(width 0.0254)
				(type default)
			)
			(layer "F.Fab")
		)
		(pad "1" smd rect
			(at 0 -0.8001 180)
			(size 0.8636 0.9652)
			(layers "F.Cu" "F.Mask" "F.Paste")
			(net "VDD_3.3V")
		)
		(pad "2" smd rect
			(at 0 0.8001 180)
			(size 0.8636 0.9652)
			(layers "F.Cu" "F.Mask" "F.Paste")
			(net "GND")
		)
		(zone
			(layer "F.Cu")
			(hatch none 0.5)
			(connect_pads
				(clearance 0)
			)
			(min_thickness 0.25)
			(keepout
				(tracks not_allowed)
				(vias allowed)
				(pads allowed)
				(copperpour not_allowed)
				(footprints allowed)
			)
			(placement
				(enabled no)
				(sheetname "")
			)
			(fill
				(thermal_gap 0.5)
				(thermal_bridge_width 0.5)
				(island_removal_mode 0)
			)
			(polygon
				(pts
					(xy 18.415 34.5821) (xy 18.288 34.5821) (xy 18.288 34.0741) (xy 18.415 34.0741)
				)
			)
		)
	)
	(footprint ""
		(layer "F.Cu")
		(at 17.907 26.67)
		(property "Reference" "R34"
			(at 0.66167 -0.635 90)
			(unlocked yes)
			(layer "F.SilkS")
			(effects
				(font
					(size 0.7874 0.5842)
					(thickness 0.127)
				)
				(justify left)
			)
		)
		(property "Value" "4.75K"
			(at -0.148158 1.3462 90)
			(unlocked yes)
			(layer "F.Fab")
			(hide yes)
			(effects
				(font
					(size 1.27 0.9652)
					(thickness 0.000001)
				)
				(justify left)
			)
		)
		(property "Device Type" "REST4024"
			(at -0.148158 1.3462 90)
			(unlocked yes)
			(layer "F.Fab")
			(hide yes)
			(effects
				(font
					(size 1.27 0.9652)
					(thickness 0.000001)
				)
				(justify left)
			)
		)
		(duplicate_pad_numbers_are_jumpers no)
		(fp_poly
			(pts
				(xy 0.635 1.0668) (xy 0.635 -1.0668) (xy -0.635 -1.0668) (xy -0.635 1.0668)
			)
			(stroke
				(width 0)
				(type default)
			)
			(fill no)
			(layer "F.CrtYd")
		)
		(fp_line
			(start -0.254 -0.508)
			(end 0.254 -0.508)
			(stroke
				(width 0.0254)
				(type default)
			)
			(layer "F.Fab")
		)
		(fp_line
			(start -0.254 0.508)
			(end -0.254 -0.508)
			(stroke
				(width 0.0254)
				(type default)
			)
			(layer "F.Fab")
		)
		(fp_line
			(start 0.254 -0.508)
			(end 0.254 0.508)
			(stroke
				(width 0.0254)
				(type default)
			)
			(layer "F.Fab")
		)
		(fp_line
			(start 0.254 0.508)
			(end -0.254 0.508)
			(stroke
				(width 0.0254)
				(type default)
			)
			(layer "F.Fab")
		)
		(pad "1" smd rect
			(at 0 -0.4191)
			(size 0.508 0.5334)
			(layers "F.Cu" "F.Mask" "F.Paste")
			(net "NFP_FAIL_SAFE_BOOT_L")
		)
		(pad "2" smd rect
			(at 0 0.4191)
			(size 0.508 0.5334)
			(layers "F.Cu" "F.Mask" "F.Paste")
			(net "VDD_3.3V")
		)
		(zone
			(layer "F.Cu")
			(hatch none 0.5)
			(connect_pads
				(clearance 0)
			)
			(min_thickness 0.25)
			(keepout
				(tracks not_allowed)
				(vias allowed)
				(pads allowed)
				(copperpour not_allowed)
				(footprints allowed)
			)
			(placement
				(enabled no)
				(sheetname "")
			)
			(fill
				(thermal_gap 0.5)
				(thermal_bridge_width 0.5)
				(island_removal_mode 0)
			)
			(polygon
				(pts
					(xy 17.9324 26.6446) (xy 17.9324 26.6954) (xy 17.8816 26.6954) (xy 17.8816 26.6446)
				)
			)
		)
	)
	(footprint ""
		(layer "F.Cu")
		(at 29.21 32.639 180)
		(property "Reference" "R93"
			(at 0 0 180)
			(layer "F.SilkS")
			(hide yes)
			(effects
				(font
					(size 1.27 1.27)
				)
			)
		)
		(property "Value" "4.75K"
			(at -0.148158 1.3462 270)
			(unlocked yes)
			(layer "F.Fab")
			(hide yes)
			(effects
				(font
					(size 1.27 0.9652)
					(thickness 0.000001)
				)
				(justify left)
			)
		)
		(property "Device Type" "REST4024"
			(at -0.148158 1.3462 270)
			(unlocked yes)
			(layer "F.Fab")
			(hide yes)
			(effects
				(font
					(size 1.27 0.9652)
					(thickness 0.000001)
				)
				(justify left)
			)
		)
		(duplicate_pad_numbers_are_jumpers no)
		(fp_poly
			(pts
				(xy 0.635 1.0668) (xy 0.635 -1.0668) (xy -0.635 -1.0668) (xy -0.635 1.0668)
			)
			(stroke
				(width 0)
				(type default)
			)
			(fill no)
			(layer "F.CrtYd")
		)
		(fp_line
			(start 0.254 0.508)
			(end -0.254 0.508)
			(stroke
				(width 0.0254)
				(type default)
			)
			(layer "F.Fab")
		)
		(fp_line
			(start 0.254 -0.508)
			(end 0.254 0.508)
			(stroke
				(width 0.0254)
				(type default)
			)
			(layer "F.Fab")
		)
		(fp_line
			(start -0.254 0.508)
			(end -0.254 -0.508)
			(stroke
				(width 0.0254)
				(type default)
			)
			(layer "F.Fab")
		)
		(fp_line
			(start -0.254 -0.508)
			(end 0.254 -0.508)
			(stroke
				(width 0.0254)
				(type default)
			)
			(layer "F.Fab")
		)
		(pad "1" smd rect
			(at 0 -0.4191 180)
			(size 0.508 0.5334)
			(layers "F.Cu" "F.Mask" "F.Paste")
			(net "_NFP_CORE_VID2")
		)
		(pad "2" smd rect
			(at 0 0.4191 180)
			(size 0.508 0.5334)
			(layers "F.Cu" "F.Mask" "F.Paste")
			(net "VDD_1.2V")
		)
		(zone
			(layer "F.Cu")
			(hatch none 0.5)
			(connect_pads
				(clearance 0)
			)
			(min_thickness 0.25)
			(keepout
				(tracks not_allowed)
				(vias allowed)
				(pads allowed)
				(copperpour not_allowed)
				(footprints allowed)
			)
			(placement
				(enabled no)
				(sheetname "")
			)
			(fill
				(thermal_gap 0.5)
				(thermal_bridge_width 0.5)
				(island_removal_mode 0)
			)
			(polygon
				(pts
					(xy 29.1846 32.6644) (xy 29.1846 32.6136) (xy 29.2354 32.6136) (xy 29.2354 32.6644)
				)
			)
		)
	)
	(footprint ""
		(layer "F.Cu")
		(at 73.152 28.194 180)
		(property "Reference" "R339"
			(at 0.86233 -1.27 90)
			(unlocked yes)
			(layer "F.SilkS")
			(effects
				(font
					(size 0.7874 0.5842)
					(thickness 0.127)
				)
				(justify left)
			)
		)
		(property "Value" "4.75K"
			(at -0.148158 1.3462 270)
			(unlocked yes)
			(layer "F.Fab")
			(hide yes)
			(effects
				(font
					(size 1.27 0.9652)
					(thickness 0.000001)
				)
				(justify left)
			)
		)
		(property "Device Type" "REST4024"
			(at -0.148158 1.3462 270)
			(unlocked yes)
			(layer "F.Fab")
			(hide yes)
			(effects
				(font
					(size 1.27 0.9652)
					(thickness 0.000001)
				)
				(justify left)
			)
		)
		(duplicate_pad_numbers_are_jumpers no)
		(fp_poly
			(pts
				(xy 0.635 1.0668) (xy 0.635 -1.0668) (xy -0.635 -1.0668) (xy -0.635 1.0668)
			)
			(stroke
				(width 0)
				(type default)
			)
			(fill no)
			(layer "F.CrtYd")
		)
		(fp_line
			(start 0.254 0.508)
			(end -0.254 0.508)
			(stroke
				(width 0.0254)
				(type default)
			)
			(layer "F.Fab")
		)
		(fp_line
			(start 0.254 -0.508)
			(end 0.254 0.508)
			(stroke
				(width 0.0254)
				(type default)
			)
			(layer "F.Fab")
		)
		(fp_line
			(start -0.254 0.508)
			(end -0.254 -0.508)
			(stroke
				(width 0.0254)
				(type default)
			)
			(layer "F.Fab")
		)
		(fp_line
			(start -0.254 -0.508)
			(end 0.254 -0.508)
			(stroke
				(width 0.0254)
				(type default)
			)
			(layer "F.Fab")
		)
		(pad "1" smd rect
			(at 0 -0.4191 180)
			(size 0.508 0.5334)
			(layers "F.Cu" "F.Mask" "F.Paste")
			(net "GND")
		)
		(pad "2" smd rect
			(at 0 0.4191 180)
			(size 0.508 0.5334)
			(layers "F.Cu" "F.Mask" "F.Paste")
			(net "12N3294")
		)
		(zone
			(layer "F.Cu")
			(hatch none 0.5)
			(connect_pads
				(clearance 0)
			)
			(min_thickness 0.25)
			(keepout
				(tracks not_allowed)
				(vias allowed)
				(pads allowed)
				(copperpour not_allowed)
				(footprints allowed)
			)
			(placement
				(enabled no)
				(sheetname "")
			)
			(fill
				(thermal_gap 0.5)
				(thermal_bridge_width 0.5)
				(island_removal_mode 0)
			)
			(polygon
				(pts
					(xy 73.1266 28.2194) (xy 73.1266 28.1686) (xy 73.1774 28.1686) (xy 73.1774 28.2194)
				)
			)
		)
	)
	(footprint ""
		(layer "F.Cu")
		(at 19.431 47.498)
		(property "Reference" "TP43"
			(at -1.397 2.05867 0)
			(unlocked yes)
			(layer "F.SilkS")
			(effects
				(font
					(size 0.7874 0.5842)
					(thickness 0.127)
				)
				(justify left)
			)
		)
		(property "Value" "*"
			(at -0.4826 -0.14732 0)
			(unlocked yes)
			(layer "F.Fab")
			(hide yes)
			(effects
				(font
					(size 1.27 0.9652)
					(thickness 0.000001)
				)
				(justify left)
			)
		)
		(property "Device Type" "TP_SMALL"
			(at -0.4826 -0.14732 0)
			(unlocked yes)
			(layer "F.Fab")
			(hide yes)
			(effects
				(font
					(size 1.27 0.9652)
					(thickness 0.000001)
				)
				(justify left)
			)
		)
		(duplicate_pad_numbers_are_jumpers no)
		(fp_line
			(start -0.8636 -0.8636)
			(end -0.8636 0.8636)
			(stroke
				(width 0.1524)
				(type default)
			)
			(layer "F.SilkS")
		)
		(fp_line
			(start -0.8636 0.8636)
			(end 0.8636 0.8636)
			(stroke
				(width 0.1524)
				(type default)
			)
			(layer "F.SilkS")
		)
		(fp_line
			(start 0.8636 -0.8636)
			(end -0.8636 -0.8636)
			(stroke
				(width 0.1524)
				(type default)
			)
			(layer "F.SilkS")
		)
		(fp_line
			(start 0.8636 0.8636)
			(end 0.8636 -0.8636)
			(stroke
				(width 0.1524)
				(type default)
			)
			(layer "F.SilkS")
		)
		(fp_poly
			(pts
				(xy -0.635 -0.635) (xy -0.635 0.635) (xy 0.635 0.635) (xy 0.635 -0.635)
			)
			(stroke
				(width 0)
				(type default)
			)
			(fill no)
			(layer "F.CrtYd")
		)
		(pad "1" smd rect
			(at 0 0)
			(size 1.27 1.27)
			(layers "F.Cu" "F.Mask" "F.Paste")
			(net "GND")
		)
	)
	(footprint ""
		(layer "F.Cu")
		(at 80.645 9.398 -90)
		(property "Reference" "C211"
			(at 0.78867 1.905 0)
			(unlocked yes)
			(layer "F.SilkS")
			(effects
				(font
					(size 0.7874 0.5842)
					(thickness 0.127)
				)
				(justify left)
			)
		)
		(property "Value" "1UF"
			(at -0.091846 0.2921 0)
			(unlocked yes)
			(layer "F.Fab")
			(hide yes)
			(effects
				(font
					(size 0.7874 0.5842)
					(thickness 0.2032)
				)
				(justify left)
			)
		)
		(property "Device Type" "CAPC0028"
			(at -0.091846 0.2921 0)
			(unlocked yes)
			(layer "F.Fab")
			(hide yes)
			(effects
				(font
					(size 0.7874 0.5842)
					(thickness 0.2032)
				)
				(justify left)
			)
		)
		(duplicate_pad_numbers_are_jumpers no)
		(fp_poly
			(pts
				(xy 0.635 1.0668) (xy 0.635 -1.0668) (xy -0.635 -1.0668) (xy -0.635 1.0668)
			)
			(stroke
				(width 0)
				(type default)
			)
			(fill no)
			(layer "F.CrtYd")
		)
		(fp_line
			(start -0.254 0.508)
			(end -0.254 -0.508)
			(stroke
				(width 0.0254)
				(type default)
			)
			(layer "F.Fab")
		)
		(fp_line
			(start 0.254 0.508)
			(end -0.254 0.508)
			(stroke
				(width 0.0254)
				(type default)
			)
			(layer "F.Fab")
		)
		(fp_line
			(start -0.254 -0.508)
			(end 0.254 -0.508)
			(stroke
				(width 0.0254)
				(type default)
			)
			(layer "F.Fab")
		)
		(fp_line
			(start 0.254 -0.508)
			(end 0.254 0.508)
			(stroke
				(width 0.0254)
				(type default)
			)
			(layer "F.Fab")
		)
		(pad "1" smd rect
			(at 0 -0.4191 270)
			(size 0.508 0.5334)
			(layers "F.Cu" "F.Mask" "F.Paste")
			(net "DDR_VDDQ")
		)
		(pad "2" smd rect
			(at 0 0.4191 270)
			(size 0.508 0.5334)
			(layers "F.Cu" "F.Mask" "F.Paste")
			(net "GND")
		)
		(zone
			(layer "F.Cu")
			(hatch none 0.5)
			(connect_pads
				(clearance 0)
			)
			(min_thickness 0.25)
			(keepout
				(tracks not_allowed)
				(vias allowed)
				(pads allowed)
				(copperpour not_allowed)
				(footprints allowed)
			)
			(placement
				(enabled no)
				(sheetname "")
			)
			(fill
				(thermal_gap 0.5)
				(thermal_bridge_width 0.5)
				(island_removal_mode 0)
			)
			(polygon
				(pts
					(xy 80.6704 9.4234) (xy 80.6196 9.4234) (xy 80.6196 9.3726) (xy 80.6704 9.3726)
				)
			)
		)
	)
	(footprint ""
		(layer "F.Cu")
		(at 13.208 28.702)
		(property "Reference" "TP41"
			(at -2.032 -2.00533 0)
			(unlocked yes)
			(layer "F.SilkS")
			(effects
				(font
					(size 0.7874 0.5842)
					(thickness 0.127)
				)
				(justify left)
			)
		)
		(property "Value" "*"
			(at -0.4826 -0.14732 0)
			(unlocked yes)
			(layer "F.Fab")
			(hide yes)
			(effects
				(font
					(size 1.27 0.9652)
					(thickness 0.000001)
				)
				(justify left)
			)
		)
		(property "Device Type" "TP_SMALL"
			(at -0.4826 -0.14732 0)
			(unlocked yes)
			(layer "F.Fab")
			(hide yes)
			(effects
				(font
					(size 1.27 0.9652)
					(thickness 0.000001)
				)
				(justify left)
			)
		)
		(duplicate_pad_numbers_are_jumpers no)
		(fp_line
			(start -0.8636 -0.8636)
			(end -0.8636 0.8636)
			(stroke
				(width 0.1524)
				(type default)
			)
			(layer "F.SilkS")
		)
		(fp_line
			(start -0.8636 0.8636)
			(end 0.8636 0.8636)
			(stroke
				(width 0.1524)
				(type default)
			)
			(layer "F.SilkS")
		)
		(fp_line
			(start 0.8636 -0.8636)
			(end -0.8636 -0.8636)
			(stroke
				(width 0.1524)
				(type default)
			)
			(layer "F.SilkS")
		)
		(fp_line
			(start 0.8636 0.8636)
			(end 0.8636 -0.8636)
			(stroke
				(width 0.1524)
				(type default)
			)
			(layer "F.SilkS")
		)
		(fp_poly
			(pts
				(xy -0.635 -0.635) (xy -0.635 0.635) (xy 0.635 0.635) (xy 0.635 -0.635)
			)
			(stroke
				(width 0)
				(type default)
			)
			(fill no)
			(layer "F.CrtYd")
		)
		(pad "1" smd rect
			(at 0 0)
			(size 1.27 1.27)
			(layers "F.Cu" "F.Mask" "F.Paste")
			(net "GND")
		)
	)
	(footprint ""
		(layer "F.Cu")
		(at 8.5852 38.735)
		(property "Reference" "TP21"
			(at 0.15367 -0.889 90)
			(unlocked yes)
			(layer "F.SilkS")
			(effects
				(font
					(size 0.7874 0.5842)
					(thickness 0.127)
				)
				(justify left)
			)
		)
		(property "Value" "*"
			(at -0.4826 -0.14732 0)
			(unlocked yes)
			(layer "F.Fab")
			(hide yes)
			(effects
				(font
					(size 1.27 0.9652)
					(thickness 0.000001)
				)
				(justify left)
			)
		)
		(property "Device Type" "TP_SMALL"
			(at -0.4826 -0.14732 0)
			(unlocked yes)
			(layer "F.Fab")
			(hide yes)
			(effects
				(font
					(size 1.27 0.9652)
					(thickness 0.000001)
				)
				(justify left)
			)
		)
		(duplicate_pad_numbers_are_jumpers no)
		(fp_line
			(start -0.8636 -0.8636)
			(end -0.8636 0.8636)
			(stroke
				(width 0.1524)
				(type default)
			)
			(layer "F.SilkS")
		)
		(fp_line
			(start -0.8636 0.8636)
			(end 0.8636 0.8636)
			(stroke
				(width 0.1524)
				(type default)
			)
			(layer "F.SilkS")
		)
		(fp_line
			(start 0.8636 -0.8636)
			(end -0.8636 -0.8636)
			(stroke
				(width 0.1524)
				(type default)
			)
			(layer "F.SilkS")
		)
		(fp_line
			(start 0.8636 0.8636)
			(end 0.8636 -0.8636)
			(stroke
				(width 0.1524)
				(type default)
			)
			(layer "F.SilkS")
		)
		(fp_poly
			(pts
				(xy -0.635 -0.635) (xy -0.635 0.635) (xy 0.635 0.635) (xy 0.635 -0.635)
			)
			(stroke
				(width 0)
				(type default)
			)
			(fill no)
			(layer "F.CrtYd")
		)
		(pad "1" smd rect
			(at 0 0)
			(size 1.27 1.27)
			(layers "F.Cu" "F.Mask" "F.Paste")
			(net "CPLD_GPIO_1")
		)
	)
	(footprint ""
		(layer "F.Cu")
		(at 66.802 36.957 90)
		(property "Reference" "R171"
			(at 0.86233 -0.127 0)
			(unlocked yes)
			(layer "F.SilkS")
			(effects
				(font
					(size 0.7874 0.5842)
					(thickness 0.127)
				)
				(justify left)
			)
		)
		(property "Value" "0"
			(at -0.148158 1.3462 180)
			(unlocked yes)
			(layer "F.Fab")
			(hide yes)
			(effects
				(font
					(size 1.27 0.9652)
					(thickness 0.000001)
				)
				(justify left)
			)
		)
		(property "Device Type" "REST1111"
			(at -0.148158 1.3462 180)
			(unlocked yes)
			(layer "F.Fab")
			(hide yes)
			(effects
				(font
					(size 1.27 0.9652)
					(thickness 0.000001)
				)
				(justify left)
			)
		)
		(duplicate_pad_numbers_are_jumpers no)
		(fp_poly
			(pts
				(xy 0.635 1.0668) (xy 0.635 -1.0668) (xy -0.635 -1.0668) (xy -0.635 1.0668)
			)
			(stroke
				(width 0)
				(type default)
			)
			(fill no)
			(layer "F.CrtYd")
		)
		(fp_line
			(start 0.254 -0.508)
			(end 0.254 0.508)
			(stroke
				(width 0.0254)
				(type default)
			)
			(layer "F.Fab")
		)
		(fp_line
			(start -0.254 -0.508)
			(end 0.254 -0.508)
			(stroke
				(width 0.0254)
				(type default)
			)
			(layer "F.Fab")
		)
		(fp_line
			(start 0.254 0.508)
			(end -0.254 0.508)
			(stroke
				(width 0.0254)
				(type default)
			)
			(layer "F.Fab")
		)
		(fp_line
			(start -0.254 0.508)
			(end -0.254 -0.508)
			(stroke
				(width 0.0254)
				(type default)
			)
			(layer "F.Fab")
		)
		(pad "1" smd rect
			(at 0 -0.4191 90)
			(size 0.508 0.5334)
			(layers "F.Cu" "F.Mask" "F.Paste")
			(net "L_1_CORE_PHASE")
		)
		(pad "2" smd rect
			(at 0 0.4191 90)
			(size 0.508 0.5334)
			(layers "F.Cu" "F.Mask" "F.Paste")
			(net "NFP_VDD_CORE_ISEN1_P")
		)
		(zone
			(layer "F.Cu")
			(hatch none 0.5)
			(connect_pads
				(clearance 0)
			)
			(min_thickness 0.25)
			(keepout
				(tracks not_allowed)
				(vias allowed)
				(pads allowed)
				(copperpour not_allowed)
				(footprints allowed)
			)
			(placement
				(enabled no)
				(sheetname "")
			)
			(fill
				(thermal_gap 0.5)
				(thermal_bridge_width 0.5)
				(island_removal_mode 0)
			)
			(polygon
				(pts
					(xy 66.7766 36.9316) (xy 66.8274 36.9316) (xy 66.8274 36.9824) (xy 66.7766 36.9824)
				)
			)
		)
	)
	(footprint ""
		(layer "F.Cu")
		(at 35.941 9.779 90)
		(property "Reference" "R135"
			(at 0 0 90)
			(layer "F.SilkS")
			(hide yes)
			(effects
				(font
					(size 1.27 1.27)
				)
			)
		)
		(property "Value" "0"
			(at -0.148158 1.3462 180)
			(unlocked yes)
			(layer "F.Fab")
			(hide yes)
			(effects
				(font
					(size 1.27 0.9652)
					(thickness 0.000001)
				)
				(justify left)
			)
		)
		(property "Device Type" "REST1111"
			(at -0.148158 1.3462 180)
			(unlocked yes)
			(layer "F.Fab")
			(hide yes)
			(effects
				(font
					(size 1.27 0.9652)
					(thickness 0.000001)
				)
				(justify left)
			)
		)
		(duplicate_pad_numbers_are_jumpers no)
		(fp_poly
			(pts
				(xy 0.635 1.0668) (xy 0.635 -1.0668) (xy -0.635 -1.0668) (xy -0.635 1.0668)
			)
			(stroke
				(width 0)
				(type default)
			)
			(fill no)
			(layer "F.CrtYd")
		)
		(fp_line
			(start 0.254 -0.508)
			(end 0.254 0.508)
			(stroke
				(width 0.0254)
				(type default)
			)
			(layer "F.Fab")
		)
		(fp_line
			(start -0.254 -0.508)
			(end 0.254 -0.508)
			(stroke
				(width 0.0254)
				(type default)
			)
			(layer "F.Fab")
		)
		(fp_line
			(start 0.254 0.508)
			(end -0.254 0.508)
			(stroke
				(width 0.0254)
				(type default)
			)
			(layer "F.Fab")
		)
		(fp_line
			(start -0.254 0.508)
			(end -0.254 -0.508)
			(stroke
				(width 0.0254)
				(type default)
			)
			(layer "F.Fab")
		)
		(pad "1" smd rect
			(at 0 -0.4191 90)
			(size 0.508 0.5334)
			(layers "F.Cu" "F.Mask" "F.Paste")
			(net "3N2301")
		)
		(pad "2" smd rect
			(at 0 0.4191 90)
			(size 0.508 0.5334)
			(layers "F.Cu" "F.Mask" "F.Paste")
			(net "NFP_CLK_REF_N")
		)
		(zone
			(layer "F.Cu")
			(hatch none 0.5)
			(connect_pads
				(clearance 0)
			)
			(min_thickness 0.25)
			(keepout
				(tracks not_allowed)
				(vias allowed)
				(pads allowed)
				(copperpour not_allowed)
				(footprints allowed)
			)
			(placement
				(enabled no)
				(sheetname "")
			)
			(fill
				(thermal_gap 0.5)
				(thermal_bridge_width 0.5)
				(island_removal_mode 0)
			)
			(polygon
				(pts
					(xy 35.9156 9.7536) (xy 35.9664 9.7536) (xy 35.9664 9.8044) (xy 35.9156 9.8044)
				)
			)
		)
	)
	(footprint ""
		(layer "F.Cu")
		(at 6.985 33.02 90)
		(property "Reference" "L10"
			(at 2.51333 -0.508 0)
			(unlocked yes)
			(layer "F.SilkS")
			(effects
				(font
					(size 0.7874 0.5842)
					(thickness 0.127)
				)
				(justify left)
			)
		)
		(property "Value" "2.2UH"
			(at -0.483362 -0.148082 90)
			(unlocked yes)
			(layer "F.Fab")
			(hide yes)
			(effects
				(font
					(size 1.27 0.9652)
					(thickness 0.000001)
				)
				(justify left)
			)
		)
		(property "Device Type" "INDS0060"
			(at -0.483362 -0.148082 90)
			(unlocked yes)
			(layer "F.Fab")
			(hide yes)
			(effects
				(font
					(size 1.27 0.9652)
					(thickness 0.000001)
				)
				(justify left)
			)
		)
		(duplicate_pad_numbers_are_jumpers no)
		(fp_line
			(start -1.27 -1.397)
			(end 1.27 -1.397)
			(stroke
				(width 0.1524)
				(type default)
			)
			(layer "F.SilkS")
		)
		(fp_line
			(start 1.27 1.397)
			(end -1.27 1.397)
			(stroke
				(width 0.1524)
				(type default)
			)
			(layer "F.SilkS")
		)
		(fp_poly
			(pts
				(xy 2.159 -1.651) (xy 2.159 1.651) (xy -2.159 1.651) (xy -2.159 -1.651)
			)
			(stroke
				(width 0)
				(type default)
			)
			(fill no)
			(layer "F.CrtYd")
		)
		(fp_line
			(start 1.3462 -1.1049)
			(end -1.3462 -1.1049)
			(stroke
				(width 0.1524)
				(type default)
			)
			(layer "F.Fab")
		)
		(fp_line
			(start -1.3462 -1.1049)
			(end -1.3462 1.1049)
			(stroke
				(width 0.1524)
				(type default)
			)
			(layer "F.Fab")
		)
		(fp_line
			(start 1.3462 1.1049)
			(end 1.3462 -1.1049)
			(stroke
				(width 0.1524)
				(type default)
			)
			(layer "F.Fab")
		)
		(fp_line
			(start -1.3462 1.1049)
			(end 1.3462 1.1049)
			(stroke
				(width 0.1524)
				(type default)
			)
			(layer "F.Fab")
		)
		(pad "1" smd rect
			(at -1.1303 0 90)
			(size 1.1938 2.3368)
			(layers "F.Cu" "F.Mask" "F.Paste")
			(net "VDD_1.2V")
		)
		(pad "2" smd rect
			(at 1.1303 0 90)
			(size 1.1938 2.3368)
			(layers "F.Cu" "F.Mask" "F.Paste")
			(net "11N1970")
		)
		(zone
			(layer "F.Cu")
			(hatch none 0.5)
			(connect_pads
				(clearance 0)
			)
			(min_thickness 0.25)
			(keepout
				(tracks allowed)
				(vias not_allowed)
				(pads allowed)
				(copperpour not_allowed)
				(footprints allowed)
			)
			(placement
				(enabled no)
				(sheetname "")
			)
			(fill
				(thermal_gap 0.5)
				(thermal_bridge_width 0.5)
				(island_removal_mode 0)
			)
			(polygon
				(pts
					(xy 8.0899 34.3662) (xy 8.0899 31.6738) (xy 5.8801 31.6738) (xy 5.8801 34.3662)
				)
			)
		)
	)
	(footprint ""
		(layer "F.Cu")
		(at 22.987 44.069 90)
		(property "Reference" "R312"
			(at -1.80467 -2.413 0)
			(unlocked yes)
			(layer "F.SilkS")
			(effects
				(font
					(size 0.7874 0.5842)
					(thickness 0.127)
				)
				(justify left)
			)
		)
		(property "Value" "1.0K"
			(at -0.148158 1.3462 180)
			(unlocked yes)
			(layer "F.Fab")
			(hide yes)
			(effects
				(font
					(size 1.27 0.9652)
					(thickness 0.000001)
				)
				(justify left)
			)
		)
		(property "Device Type" "REST0025"
			(at -0.148158 1.3462 180)
			(unlocked yes)
			(layer "F.Fab")
			(hide yes)
			(effects
				(font
					(size 1.27 0.9652)
					(thickness 0.000001)
				)
				(justify left)
			)
		)
		(duplicate_pad_numbers_are_jumpers no)
		(fp_poly
			(pts
				(xy 0.635 1.0668) (xy 0.635 -1.0668) (xy -0.635 -1.0668) (xy -0.635 1.0668)
			)
			(stroke
				(width 0)
				(type default)
			)
			(fill no)
			(layer "F.CrtYd")
		)
		(fp_line
			(start 0.254 -0.508)
			(end 0.254 0.508)
			(stroke
				(width 0.0254)
				(type default)
			)
			(layer "F.Fab")
		)
		(fp_line
			(start -0.254 -0.508)
			(end 0.254 -0.508)
			(stroke
				(width 0.0254)
				(type default)
			)
			(layer "F.Fab")
		)
		(fp_line
			(start 0.254 0.508)
			(end -0.254 0.508)
			(stroke
				(width 0.0254)
				(type default)
			)
			(layer "F.Fab")
		)
		(fp_line
			(start -0.254 0.508)
			(end -0.254 -0.508)
			(stroke
				(width 0.0254)
				(type default)
			)
			(layer "F.Fab")
		)
		(pad "1" smd rect
			(at 0 -0.4191 90)
			(size 0.508 0.5334)
			(layers "F.Cu" "F.Mask" "F.Paste")
			(net "EXT_12.0V")
		)
		(pad "2" smd rect
			(at 0 0.4191 90)
			(size 0.508 0.5334)
			(layers "F.Cu" "F.Mask" "F.Paste")
			(net "10N2407")
		)
		(zone
			(layer "F.Cu")
			(hatch none 0.5)
			(connect_pads
				(clearance 0)
			)
			(min_thickness 0.25)
			(keepout
				(tracks not_allowed)
				(vias allowed)
				(pads allowed)
				(copperpour not_allowed)
				(footprints allowed)
			)
			(placement
				(enabled no)
				(sheetname "")
			)
			(fill
				(thermal_gap 0.5)
				(thermal_bridge_width 0.5)
				(island_removal_mode 0)
			)
			(polygon
				(pts
					(xy 22.9616 44.0436) (xy 23.0124 44.0436) (xy 23.0124 44.0944) (xy 22.9616 44.0944)
				)
			)
		)
	)
	(footprint ""
		(layer "F.Cu")
		(at 36.322 32.639 180)
		(property "Reference" "R79"
			(at 0 0 180)
			(layer "F.SilkS")
			(hide yes)
			(effects
				(font
					(size 1.27 1.27)
				)
			)
		)
		(property "Value" "4.75K"
			(at -0.148158 1.3462 270)
			(unlocked yes)
			(layer "F.Fab")
			(hide yes)
			(effects
				(font
					(size 1.27 0.9652)
					(thickness 0.000001)
				)
				(justify left)
			)
		)
		(property "Device Type" "REST4024"
			(at -0.148158 1.3462 270)
			(unlocked yes)
			(layer "F.Fab")
			(hide yes)
			(effects
				(font
					(size 1.27 0.9652)
					(thickness 0.000001)
				)
				(justify left)
			)
		)
		(duplicate_pad_numbers_are_jumpers no)
		(fp_poly
			(pts
				(xy 0.635 1.0668) (xy 0.635 -1.0668) (xy -0.635 -1.0668) (xy -0.635 1.0668)
			)
			(stroke
				(width 0)
				(type default)
			)
			(fill no)
			(layer "F.CrtYd")
		)
		(fp_line
			(start 0.254 0.508)
			(end -0.254 0.508)
			(stroke
				(width 0.0254)
				(type default)
			)
			(layer "F.Fab")
		)
		(fp_line
			(start 0.254 -0.508)
			(end 0.254 0.508)
			(stroke
				(width 0.0254)
				(type default)
			)
			(layer "F.Fab")
		)
		(fp_line
			(start -0.254 0.508)
			(end -0.254 -0.508)
			(stroke
				(width 0.0254)
				(type default)
			)
			(layer "F.Fab")
		)
		(fp_line
			(start -0.254 -0.508)
			(end 0.254 -0.508)
			(stroke
				(width 0.0254)
				(type default)
			)
			(layer "F.Fab")
		)
		(pad "1" smd rect
			(at 0 -0.4191 180)
			(size 0.508 0.5334)
			(layers "F.Cu" "F.Mask" "F.Paste")
			(net "_NFP_CORE_VID7")
		)
		(pad "2" smd rect
			(at 0 0.4191 180)
			(size 0.508 0.5334)
			(layers "F.Cu" "F.Mask" "F.Paste")
			(net "VDD_1.2V")
		)
		(zone
			(layer "F.Cu")
			(hatch none 0.5)
			(connect_pads
				(clearance 0)
			)
			(min_thickness 0.25)
			(keepout
				(tracks not_allowed)
				(vias allowed)
				(pads allowed)
				(copperpour not_allowed)
				(footprints allowed)
			)
			(placement
				(enabled no)
				(sheetname "")
			)
			(fill
				(thermal_gap 0.5)
				(thermal_bridge_width 0.5)
				(island_removal_mode 0)
			)
			(polygon
				(pts
					(xy 36.2966 32.6644) (xy 36.2966 32.6136) (xy 36.3474 32.6136) (xy 36.3474 32.6644)
				)
			)
		)
	)
	(footprint ""
		(layer "F.Cu")
		(at 9.7155 34.417 180)
		(property "Reference" "C20"
			(at 0.86233 0.762 90)
			(unlocked yes)
			(layer "F.SilkS")
			(effects
				(font
					(size 0.7874 0.5842)
					(thickness 0.127)
				)
				(justify left)
			)
		)
		(property "Value" "22UF"
			(at -0.148158 1.7526 270)
			(unlocked yes)
			(layer "F.Fab")
			(hide yes)
			(effects
				(font
					(size 1.27 0.9652)
					(thickness 0.000001)
				)
				(justify left)
			)
		)
		(property "Device Type" "CAPC0063"
			(at -0.148158 1.7526 270)
			(unlocked yes)
			(layer "F.Fab")
			(hide yes)
			(effects
				(font
					(size 1.27 0.9652)
					(thickness 0.000001)
				)
				(justify left)
			)
		)
		(duplicate_pad_numbers_are_jumpers no)
		(fp_circle
			(center 0 0)
			(end -0.127 0)
			(stroke
				(width 0.2032)
				(type default)
			)
			(fill no)
			(layer "F.SilkS")
		)
		(fp_poly
			(pts
				(xy 0.7874 -1.6637) (xy -0.7874 -1.6637) (xy -0.7874 1.6637) (xy 0.7874 1.6637)
			)
			(stroke
				(width 0)
				(type default)
			)
			(fill no)
			(layer "F.CrtYd")
		)
		(fp_line
			(start 0.4064 0.8128)
			(end -0.4064 0.8128)
			(stroke
				(width 0.0254)
				(type default)
			)
			(layer "F.Fab")
		)
		(fp_line
			(start 0.4064 -0.7874)
			(end 0.4064 0.8128)
			(stroke
				(width 0.0254)
				(type default)
			)
			(layer "F.Fab")
		)
		(fp_line
			(start -0.4064 0.8128)
			(end -0.4064 -0.7874)
			(stroke
				(width 0.0254)
				(type default)
			)
			(layer "F.Fab")
		)
		(fp_line
			(start -0.4064 -0.7874)
			(end 0.4064 -0.7874)
			(stroke
				(width 0.0254)
				(type default)
			)
			(layer "F.Fab")
		)
		(pad "1" smd rect
			(at 0 -0.8001 180)
			(size 0.8636 0.9652)
			(layers "F.Cu" "F.Mask" "F.Paste")
			(net "VDD_1.2V")
		)
		(pad "2" smd rect
			(at 0 0.8001 180)
			(size 0.8636 0.9652)
			(layers "F.Cu" "F.Mask" "F.Paste")
			(net "GND")
		)
		(zone
			(layer "F.Cu")
			(hatch none 0.5)
			(connect_pads
				(clearance 0)
			)
			(min_thickness 0.25)
			(keepout
				(tracks not_allowed)
				(vias allowed)
				(pads allowed)
				(copperpour not_allowed)
				(footprints allowed)
			)
			(placement
				(enabled no)
				(sheetname "")
			)
			(fill
				(thermal_gap 0.5)
				(thermal_bridge_width 0.5)
				(island_removal_mode 0)
			)
			(polygon
				(pts
					(xy 9.779 34.671) (xy 9.652 34.671) (xy 9.652 34.163) (xy 9.779 34.163)
				)
			)
		)
	)
	(footprint ""
		(layer "F.Cu")
		(at 17.272 28.8925 -90)
		(property "Reference" "TP56"
			(at -0.8255 1.11633 90)
			(unlocked yes)
			(layer "F.SilkS")
			(effects
				(font
					(size 0.7874 0.5842)
					(thickness 0.127)
				)
				(justify left)
			)
		)
		(property "Value" "*"
			(at -0.4826 -0.14732 270)
			(unlocked yes)
			(layer "F.Fab")
			(hide yes)
			(effects
				(font
					(size 1.27 0.9652)
					(thickness 0.000001)
				)
				(justify left)
			)
		)
		(property "Device Type" "TP_SMALL"
			(at -0.4826 -0.14732 270)
			(unlocked yes)
			(layer "F.Fab")
			(hide yes)
			(effects
				(font
					(size 1.27 0.9652)
					(thickness 0.000001)
				)
				(justify left)
			)
		)
		(duplicate_pad_numbers_are_jumpers no)
		(fp_line
			(start -0.8636 0.8636)
			(end 0.8636 0.8636)
			(stroke
				(width 0.1524)
				(type default)
			)
			(layer "F.SilkS")
		)
		(fp_line
			(start 0.8636 0.8636)
			(end 0.8636 -0.8636)
			(stroke
				(width 0.1524)
				(type default)
			)
			(layer "F.SilkS")
		)
		(fp_line
			(start -0.8636 -0.8636)
			(end -0.8636 0.8636)
			(stroke
				(width 0.1524)
				(type default)
			)
			(layer "F.SilkS")
		)
		(fp_line
			(start 0.8636 -0.8636)
			(end -0.8636 -0.8636)
			(stroke
				(width 0.1524)
				(type default)
			)
			(layer "F.SilkS")
		)
		(fp_poly
			(pts
				(xy -0.635 -0.635) (xy -0.635 0.635) (xy 0.635 0.635) (xy 0.635 -0.635)
			)
			(stroke
				(width 0)
				(type default)
			)
			(fill no)
			(layer "F.CrtYd")
		)
		(pad "1" smd rect
			(at 0 0 270)
			(size 1.27 1.27)
			(layers "F.Cu" "F.Mask" "F.Paste")
			(net "VDD_3.3V")
		)
	)
	(footprint ""
		(layer "F.Cu")
		(at 21.5265 6.35 -90)
		(property "Reference" "R381"
			(at 0 0 270)
			(layer "F.SilkS")
			(hide yes)
			(effects
				(font
					(size 1.27 1.27)
				)
			)
		)
		(property "Value" "0"
			(at -0.148158 1.3462 0)
			(unlocked yes)
			(layer "F.Fab")
			(hide yes)
			(effects
				(font
					(size 1.27 0.9652)
					(thickness 0.000001)
				)
				(justify left)
			)
		)
		(property "Device Type" "REST1111"
			(at -0.148158 1.3462 0)
			(unlocked yes)
			(layer "F.Fab")
			(hide yes)
			(effects
				(font
					(size 1.27 0.9652)
					(thickness 0.000001)
				)
				(justify left)
			)
		)
		(duplicate_pad_numbers_are_jumpers no)
		(fp_poly
			(pts
				(xy 0.635 1.0668) (xy 0.635 -1.0668) (xy -0.635 -1.0668) (xy -0.635 1.0668)
			)
			(stroke
				(width 0)
				(type default)
			)
			(fill no)
			(layer "F.CrtYd")
		)
		(fp_line
			(start -0.254 0.508)
			(end -0.254 -0.508)
			(stroke
				(width 0.0254)
				(type default)
			)
			(layer "F.Fab")
		)
		(fp_line
			(start 0.254 0.508)
			(end -0.254 0.508)
			(stroke
				(width 0.0254)
				(type default)
			)
			(layer "F.Fab")
		)
		(fp_line
			(start -0.254 -0.508)
			(end 0.254 -0.508)
			(stroke
				(width 0.0254)
				(type default)
			)
			(layer "F.Fab")
		)
		(fp_line
			(start 0.254 -0.508)
			(end 0.254 0.508)
			(stroke
				(width 0.0254)
				(type default)
			)
			(layer "F.Fab")
		)
		(pad "1" smd rect
			(at 0 -0.4191 270)
			(size 0.508 0.5334)
			(layers "F.Cu" "F.Mask" "F.Paste")
			(net "NFP_SMBUS_ALERT_L")
		)
		(pad "2" smd rect
			(at 0 0.4191 270)
			(size 0.508 0.5334)
			(layers "F.Cu" "F.Mask" "F.Paste")
			(net "MUX_NFP_SMBUS_ALERT_L")
		)
		(zone
			(layer "F.Cu")
			(hatch none 0.5)
			(connect_pads
				(clearance 0)
			)
			(min_thickness 0.25)
			(keepout
				(tracks not_allowed)
				(vias allowed)
				(pads allowed)
				(copperpour not_allowed)
				(footprints allowed)
			)
			(placement
				(enabled no)
				(sheetname "")
			)
			(fill
				(thermal_gap 0.5)
				(thermal_bridge_width 0.5)
				(island_removal_mode 0)
			)
			(polygon
				(pts
					(xy 21.5519 6.3754) (xy 21.5011 6.3754) (xy 21.5011 6.3246) (xy 21.5519 6.3246)
				)
			)
		)
	)
	(footprint ""
		(layer "F.Cu")
		(at 36.322 37.211 90)
		(property "Reference" "R181"
			(at 0 0 90)
			(layer "F.SilkS")
			(hide yes)
			(effects
				(font
					(size 1.27 1.27)
				)
			)
		)
		(property "Value" "0"
			(at -0.148158 1.3462 180)
			(unlocked yes)
			(layer "F.Fab")
			(hide yes)
			(effects
				(font
					(size 1.27 0.9652)
					(thickness 0.000001)
				)
				(justify left)
			)
		)
		(property "Device Type" "REST1111"
			(at -0.148158 1.3462 180)
			(unlocked yes)
			(layer "F.Fab")
			(hide yes)
			(effects
				(font
					(size 1.27 0.9652)
					(thickness 0.000001)
				)
				(justify left)
			)
		)
		(duplicate_pad_numbers_are_jumpers no)
		(fp_poly
			(pts
				(xy 0.635 1.0668) (xy 0.635 -1.0668) (xy -0.635 -1.0668) (xy -0.635 1.0668)
			)
			(stroke
				(width 0)
				(type default)
			)
			(fill no)
			(layer "F.CrtYd")
		)
		(fp_line
			(start 0.254 -0.508)
			(end 0.254 0.508)
			(stroke
				(width 0.0254)
				(type default)
			)
			(layer "F.Fab")
		)
		(fp_line
			(start -0.254 -0.508)
			(end 0.254 -0.508)
			(stroke
				(width 0.0254)
				(type default)
			)
			(layer "F.Fab")
		)
		(fp_line
			(start 0.254 0.508)
			(end -0.254 0.508)
			(stroke
				(width 0.0254)
				(type default)
			)
			(layer "F.Fab")
		)
		(fp_line
			(start -0.254 0.508)
			(end -0.254 -0.508)
			(stroke
				(width 0.0254)
				(type default)
			)
			(layer "F.Fab")
		)
		(pad "1" smd rect
			(at 0 -0.4191 90)
			(size 0.508 0.5334)
			(layers "F.Cu" "F.Mask" "F.Paste")
			(net "10N2403")
		)
		(pad "2" smd rect
			(at 0 0.4191 90)
			(size 0.508 0.5334)
			(layers "F.Cu" "F.Mask" "F.Paste")
			(net "VDD_5.0V")
		)
		(zone
			(layer "F.Cu")
			(hatch none 0.5)
			(connect_pads
				(clearance 0)
			)
			(min_thickness 0.25)
			(keepout
				(tracks not_allowed)
				(vias allowed)
				(pads allowed)
				(copperpour not_allowed)
				(footprints allowed)
			)
			(placement
				(enabled no)
				(sheetname "")
			)
			(fill
				(thermal_gap 0.5)
				(thermal_bridge_width 0.5)
				(island_removal_mode 0)
			)
			(polygon
				(pts
					(xy 36.2966 37.1856) (xy 36.3474 37.1856) (xy 36.3474 37.2364) (xy 36.2966 37.2364)
				)
			)
		)
	)
	(footprint ""
		(layer "F.Cu")
		(at 22.86 11.176 90)
		(property "Reference" "U8"
			(at 1.75133 -4.318 0)
			(unlocked yes)
			(layer "F.SilkS")
			(effects
				(font
					(size 0.7874 0.5842)
					(thickness 0.127)
				)
				(justify left)
			)
		)
		(property "Value" "*"
			(at -2.0066 1.756842 90)
			(unlocked yes)
			(layer "F.Fab")
			(hide yes)
			(effects
				(font
					(size 1.27 0.9652)
					(thickness 0.000001)
				)
				(justify left)
			)
		)
		(property "Device Type" "PROG0053"
			(at -2.0066 1.756842 90)
			(unlocked yes)
			(layer "F.Fab")
			(hide yes)
			(effects
				(font
					(size 1.27 0.9652)
					(thickness 0.000001)
				)
				(justify left)
			)
		)
		(duplicate_pad_numbers_are_jumpers no)
		(fp_line
			(start 2.286 -2.794)
			(end 2.286 -2.54)
			(stroke
				(width 0.2032)
				(type default)
			)
			(layer "F.SilkS")
		)
		(fp_line
			(start 0.252324 -2.794)
			(end 2.286 -2.794)
			(stroke
				(width 0.2032)
				(type default)
			)
			(layer "F.SilkS")
		)
		(fp_line
			(start -0.762 -2.794)
			(end -0.762 -1.905)
			(stroke
				(width 0.2032)
				(type default)
			)
			(layer "F.SilkS")
		)
		(fp_line
			(start -2.286 -2.794)
			(end 2.286 -2.794)
			(stroke
				(width 0.2032)
				(type default)
			)
			(layer "F.SilkS")
		)
		(fp_line
			(start -2.286 -2.794)
			(end -1.6256 -2.794)
			(stroke
				(width 0.2032)
				(type default)
			)
			(layer "F.SilkS")
		)
		(fp_line
			(start -2.286 -2.54)
			(end -2.286 -2.794)
			(stroke
				(width 0.2032)
				(type default)
			)
			(layer "F.SilkS")
		)
		(fp_line
			(start 0.762 -1.905)
			(end 0.762 -2.794)
			(stroke
				(width 0.2032)
				(type default)
			)
			(layer "F.SilkS")
		)
		(fp_line
			(start 0.762 -1.905)
			(end 0.762 -2.794)
			(stroke
				(width 0.2032)
				(type default)
			)
			(layer "F.SilkS")
		)
		(fp_line
			(start -0.762 -1.905)
			(end 0.762 -1.905)
			(stroke
				(width 0.2032)
				(type default)
			)
			(layer "F.SilkS")
		)
		(fp_line
			(start -2.286 2.54)
			(end -2.286 2.794)
			(stroke
				(width 0.2032)
				(type default)
			)
			(layer "F.SilkS")
		)
		(fp_line
			(start 2.286 2.794)
			(end 2.286 2.54)
			(stroke
				(width 0.2032)
				(type default)
			)
			(layer "F.SilkS")
		)
		(fp_line
			(start -1.054786 2.794)
			(end 1.6256 2.794)
			(stroke
				(width 0.2032)
				(type default)
			)
			(layer "F.SilkS")
		)
		(fp_line
			(start -2.286 2.794)
			(end 2.286 2.794)
			(stroke
				(width 0.2032)
				(type default)
			)
			(layer "F.SilkS")
		)
		(fp_arc
			(start -2.794 -3.048)
			(mid -2.614395 -2.973605)
			(end -2.54 -2.794)
			(stroke
				(width 0.2032)
				(type default)
			)
			(layer "F.SilkS")
		)
		(fp_arc
			(start -2.54 -2.794)
			(mid -2.572074 -2.67045)
			(end -2.660193 -2.5781)
			(stroke
				(width 0.2032)
				(type default)
			)
			(layer "F.SilkS")
		)
		(fp_arc
			(start -3.048 -2.794)
			(mid -2.973605 -2.973605)
			(end -2.794 -3.048)
			(stroke
				(width 0.2032)
				(type default)
			)
			(layer "F.SilkS")
		)
		(fp_arc
			(start -2.927807 -2.5781)
			(mid -3.015928 -2.670449)
			(end -3.048 -2.794)
			(stroke
				(width 0.2032)
				(type default)
			)
			(layer "F.SilkS")
		)
		(fp_circle
			(center -2.794 -2.794)
			(end -2.794 -2.54)
			(stroke
				(width 0.2032)
				(type default)
			)
			(fill no)
			(layer "F.SilkS")
		)
		(fp_poly
			(pts
				(xy 2.54 3.048) (xy 2.54 2.921) (xy 4.191 2.921) (xy 4.191 -2.921) (xy 2.54 -2.921) (xy 2.54 -3.048)
				(xy -2.54 -3.048) (xy -2.54 -2.921) (xy -4.191 -2.921) (xy -4.191 2.921) (xy -2.54 2.921) (xy -2.54 3.048)
			)
			(stroke
				(width 0)
				(type default)
			)
			(fill no)
			(layer "F.CrtYd")
		)
		(fp_line
			(start 2.0066 -2.5019)
			(end -2.0066 -2.5019)
			(stroke
				(width 0.2032)
				(type default)
			)
			(layer "F.Fab")
		)
		(fp_line
			(start -2.0066 -2.5019)
			(end -2.0066 2.5019)
			(stroke
				(width 0.2032)
				(type default)
			)
			(layer "F.Fab")
		)
		(fp_line
			(start -0.635 -2.4892)
			(end -0.635 -1.7272)
			(stroke
				(width 0.2032)
				(type default)
			)
			(layer "F.Fab")
		)
		(fp_line
			(start 0.635 -1.7272)
			(end 0.635 -2.4892)
			(stroke
				(width 0.2032)
				(type default)
			)
			(layer "F.Fab")
		)
		(fp_line
			(start -0.635 -1.7272)
			(end 0.635 -1.7272)
			(stroke
				(width 0.2032)
				(type default)
			)
			(layer "F.Fab")
		)
		(fp_line
			(start 2.0066 2.5019)
			(end 2.0066 -2.5019)
			(stroke
				(width 0.2032)
				(type default)
			)
			(layer "F.Fab")
		)
		(fp_line
			(start -2.0066 2.5019)
			(end 2.0066 2.5019)
			(stroke
				(width 0.2032)
				(type default)
			)
			(layer "F.Fab")
		)
		(fp_circle
			(center -1.524 -1.905)
			(end -1.524 -1.621028)
			(stroke
				(width 0.2032)
				(type default)
			)
			(fill no)
			(layer "F.Fab")
		)
		(pad "1" smd rect
			(at -2.667 -1.905 90)
			(size 2.032 0.635)
			(layers "F.Cu" "F.Mask" "F.Paste")
			(net "NFP_CFG_SPI_FLASH_SEL")
		)
		(pad "2" smd rect
			(at -2.667 -0.635 90)
			(size 2.032 0.635)
			(layers "F.Cu" "F.Mask" "F.Paste")
			(net "NFP_CFG_SPI_FLASH_MISO")
		)
		(pad "3" smd rect
			(at -2.667 0.635 90)
			(size 2.032 0.635)
			(layers "F.Cu" "F.Mask" "F.Paste")
			(net "NFP_CFG_SPI_FLASH_WP_L")
		)
		(pad "4" smd rect
			(at -2.667 1.905 90)
			(size 2.032 0.635)
			(layers "F.Cu" "F.Mask" "F.Paste")
			(net "GND")
		)
		(pad "5" smd rect
			(at 2.667 1.905 90)
			(size 2.032 0.635)
			(layers "F.Cu" "F.Mask" "F.Paste")
			(net "NFP_CFG_SPI_FLASH_MOSI")
		)
		(pad "6" smd rect
			(at 2.667 0.635 90)
			(size 2.032 0.635)
			(layers "F.Cu" "F.Mask" "F.Paste")
			(net "NFP_CFG_SPI_FLASH_SCK")
		)
		(pad "7" smd rect
			(at 2.667 -0.635 90)
			(size 2.032 0.635)
			(layers "F.Cu" "F.Mask" "F.Paste")
			(net "NFP_CFG_SPI_FLASH_HOLD_L")
		)
		(pad "8" smd rect
			(at 2.667 -1.905 90)
			(size 2.032 0.635)
			(layers "F.Cu" "F.Mask" "F.Paste")
			(net "VDD_3.3V")
		)
	)
	(footprint ""
		(layer "F.Cu")
		(at 77.051002 6.698996)
		(property "Reference" "V_A-DQ03"
			(at 0 0 0)
			(layer "F.SilkS")
			(hide yes)
			(effects
				(font
					(size 1.27 1.27)
				)
			)
		)
		(property "Value" ""
			(at 0 0 0)
			(layer "F.Fab")
			(effects
				(font
					(size 1.27 1.27)
				)
			)
		)
		(duplicate_pad_numbers_are_jumpers no)
		(pad "1" thru_hole circle
			(at 0 0)
			(size 0.762 0.762)
			(drill 0.20574)
			(layers "*.Cu" "*.Mask")
			(remove_unused_layers no)
			(net "DDR0_32A_DQ3")
			(clearance 0.127)
			(thermal_gap 0.127)
			(padstack
				(mode front_inner_back)
				(layer "Inner"
					(shape circle)
					(size 0.4572 0.4572)
					(clearance 0.1143)
				)
				(layer "B.Cu"
					(shape circle)
					(size 0.4572 0.4572)
					(clearance 0.1143)
				)
			)
		)
	)
	(footprint ""
		(layer "F.Cu")
		(at 38.6715 39.0144 -90)
		(property "Reference" "R402"
			(at 0.25527 -1.397 0)
			(unlocked yes)
			(layer "F.SilkS")
			(effects
				(font
					(size 0.7874 0.5842)
					(thickness 0.127)
				)
				(justify left)
			)
		)
		(property "Value" "680"
			(at -0.148158 1.7526 0)
			(unlocked yes)
			(layer "F.Fab")
			(hide yes)
			(effects
				(font
					(size 1.27 0.9652)
					(thickness 0.000001)
				)
				(justify left)
			)
		)
		(property "Device Type" "REST0283"
			(at -0.148158 1.7526 0)
			(unlocked yes)
			(layer "F.Fab")
			(hide yes)
			(effects
				(font
					(size 1.27 0.9652)
					(thickness 0.000001)
				)
				(justify left)
			)
		)
		(duplicate_pad_numbers_are_jumpers no)
		(fp_circle
			(center 0 0)
			(end 0 -0.127)
			(stroke
				(width 0.2032)
				(type default)
			)
			(fill no)
			(layer "F.SilkS")
		)
		(fp_poly
			(pts
				(xy 0.7874 -1.6637) (xy -0.7874 -1.6637) (xy -0.7874 1.6637) (xy 0.7874 1.6637)
			)
			(stroke
				(width 0)
				(type default)
			)
			(fill no)
			(layer "F.CrtYd")
		)
		(fp_line
			(start -0.4064 0.8128)
			(end -0.4064 -0.8128)
			(stroke
				(width 0.0254)
				(type default)
			)
			(layer "F.Fab")
		)
		(fp_line
			(start 0.4064 0.8128)
			(end -0.4064 0.8128)
			(stroke
				(width 0.0254)
				(type default)
			)
			(layer "F.Fab")
		)
		(fp_line
			(start -0.4064 -0.8128)
			(end 0.4064 -0.8128)
			(stroke
				(width 0.0254)
				(type default)
			)
			(layer "F.Fab")
		)
		(fp_line
			(start 0.4064 -0.8128)
			(end 0.4064 0.8128)
			(stroke
				(width 0.0254)
				(type default)
			)
			(layer "F.Fab")
		)
		(pad "1" smd rect
			(at 0 -0.8001 270)
			(size 0.762 0.9652)
			(layers "F.Cu" "F.Mask" "F.Paste")
			(net "EXT_12.0V")
		)
		(pad "2" smd rect
			(at 0 0.8001 270)
			(size 0.762 0.9652)
			(layers "F.Cu" "F.Mask" "F.Paste")
			(net "10N2370")
		)
		(zone
			(layer "F.Cu")
			(hatch none 0.5)
			(connect_pads
				(clearance 0)
			)
			(min_thickness 0.25)
			(keepout
				(tracks not_allowed)
				(vias allowed)
				(pads allowed)
				(copperpour not_allowed)
				(footprints allowed)
			)
			(placement
				(enabled no)
				(sheetname "")
			)
			(fill
				(thermal_gap 0.5)
				(thermal_bridge_width 0.5)
				(island_removal_mode 0)
			)
			(polygon
				(pts
					(xy 38.9255 38.9509) (xy 38.9255 39.0779) (xy 38.4175 39.0779) (xy 38.4175 38.9509)
				)
			)
		)
	)
	(footprint ""
		(layer "F.Cu")
		(at 73.533 11.938 90)
		(property "Reference" "C265"
			(at -0.254 -1.24333 90)
			(unlocked yes)
			(layer "F.SilkS")
			(effects
				(font
					(size 0.7874 0.5842)
					(thickness 0.127)
				)
				(justify left)
			)
		)
		(property "Value" "1UF"
			(at -0.091846 0.2921 180)
			(unlocked yes)
			(layer "F.Fab")
			(hide yes)
			(effects
				(font
					(size 0.7874 0.5842)
					(thickness 0.2032)
				)
				(justify left)
			)
		)
		(property "Device Type" "CAPC0028"
			(at -0.091846 0.2921 180)
			(unlocked yes)
			(layer "F.Fab")
			(hide yes)
			(effects
				(font
					(size 0.7874 0.5842)
					(thickness 0.2032)
				)
				(justify left)
			)
		)
		(duplicate_pad_numbers_are_jumpers no)
		(fp_poly
			(pts
				(xy 0.635 1.0668) (xy 0.635 -1.0668) (xy -0.635 -1.0668) (xy -0.635 1.0668)
			)
			(stroke
				(width 0)
				(type default)
			)
			(fill no)
			(layer "F.CrtYd")
		)
		(fp_line
			(start 0.254 -0.508)
			(end 0.254 0.508)
			(stroke
				(width 0.0254)
				(type default)
			)
			(layer "F.Fab")
		)
		(fp_line
			(start -0.254 -0.508)
			(end 0.254 -0.508)
			(stroke
				(width 0.0254)
				(type default)
			)
			(layer "F.Fab")
		)
		(fp_line
			(start 0.254 0.508)
			(end -0.254 0.508)
			(stroke
				(width 0.0254)
				(type default)
			)
			(layer "F.Fab")
		)
		(fp_line
			(start -0.254 0.508)
			(end -0.254 -0.508)
			(stroke
				(width 0.0254)
				(type default)
			)
			(layer "F.Fab")
		)
		(pad "1" smd rect
			(at 0 -0.4191 90)
			(size 0.508 0.5334)
			(layers "F.Cu" "F.Mask" "F.Paste")
			(net "DDR_VDDQ")
		)
		(pad "2" smd rect
			(at 0 0.4191 90)
			(size 0.508 0.5334)
			(layers "F.Cu" "F.Mask" "F.Paste")
			(net "GND")
		)
		(zone
			(layer "F.Cu")
			(hatch none 0.5)
			(connect_pads
				(clearance 0)
			)
			(min_thickness 0.25)
			(keepout
				(tracks not_allowed)
				(vias allowed)
				(pads allowed)
				(copperpour not_allowed)
				(footprints allowed)
			)
			(placement
				(enabled no)
				(sheetname "")
			)
			(fill
				(thermal_gap 0.5)
				(thermal_bridge_width 0.5)
				(island_removal_mode 0)
			)
			(polygon
				(pts
					(xy 73.5076 11.9126) (xy 73.5584 11.9126) (xy 73.5584 11.9634) (xy 73.5076 11.9634)
				)
			)
		)
	)
	(footprint ""
		(layer "F.Cu")
		(at 26.543 32.639 180)
		(property "Reference" "R84"
			(at -0.02667 1.524 90)
			(unlocked yes)
			(layer "F.SilkS")
			(effects
				(font
					(size 0.7874 0.5842)
					(thickness 0.127)
				)
				(justify left)
			)
		)
		(property "Value" "4.75K"
			(at -0.148158 1.3462 270)
			(unlocked yes)
			(layer "F.Fab")
			(hide yes)
			(effects
				(font
					(size 1.27 0.9652)
					(thickness 0.000001)
				)
				(justify left)
			)
		)
		(property "Device Type" "REST4024"
			(at -0.148158 1.3462 270)
			(unlocked yes)
			(layer "F.Fab")
			(hide yes)
			(effects
				(font
					(size 1.27 0.9652)
					(thickness 0.000001)
				)
				(justify left)
			)
		)
		(duplicate_pad_numbers_are_jumpers no)
		(fp_poly
			(pts
				(xy 0.635 1.0668) (xy 0.635 -1.0668) (xy -0.635 -1.0668) (xy -0.635 1.0668)
			)
			(stroke
				(width 0)
				(type default)
			)
			(fill no)
			(layer "F.CrtYd")
		)
		(fp_line
			(start 0.254 0.508)
			(end -0.254 0.508)
			(stroke
				(width 0.0254)
				(type default)
			)
			(layer "F.Fab")
		)
		(fp_line
			(start 0.254 -0.508)
			(end 0.254 0.508)
			(stroke
				(width 0.0254)
				(type default)
			)
			(layer "F.Fab")
		)
		(fp_line
			(start -0.254 0.508)
			(end -0.254 -0.508)
			(stroke
				(width 0.0254)
				(type default)
			)
			(layer "F.Fab")
		)
		(fp_line
			(start -0.254 -0.508)
			(end 0.254 -0.508)
			(stroke
				(width 0.0254)
				(type default)
			)
			(layer "F.Fab")
		)
		(pad "1" smd rect
			(at 0 -0.4191 180)
			(size 0.508 0.5334)
			(layers "F.Cu" "F.Mask" "F.Paste")
			(net "_NFP_CORE_VID0")
		)
		(pad "2" smd rect
			(at 0 0.4191 180)
			(size 0.508 0.5334)
			(layers "F.Cu" "F.Mask" "F.Paste")
			(net "VDD_1.2V")
		)
		(zone
			(layer "F.Cu")
			(hatch none 0.5)
			(connect_pads
				(clearance 0)
			)
			(min_thickness 0.25)
			(keepout
				(tracks not_allowed)
				(vias allowed)
				(pads allowed)
				(copperpour not_allowed)
				(footprints allowed)
			)
			(placement
				(enabled no)
				(sheetname "")
			)
			(fill
				(thermal_gap 0.5)
				(thermal_bridge_width 0.5)
				(island_removal_mode 0)
			)
			(polygon
				(pts
					(xy 26.5176 32.6644) (xy 26.5176 32.6136) (xy 26.5684 32.6136) (xy 26.5684 32.6644)
				)
			)
		)
	)
	(footprint ""
		(layer "F.Cu")
		(at 36.322 38.989 90)
		(property "Reference" "R314"
			(at 0 0 90)
			(layer "F.SilkS")
			(hide yes)
			(effects
				(font
					(size 1.27 1.27)
				)
			)
		)
		(property "Value" "1.0K"
			(at -0.148158 1.3462 180)
			(unlocked yes)
			(layer "F.Fab")
			(hide yes)
			(effects
				(font
					(size 1.27 0.9652)
					(thickness 0.000001)
				)
				(justify left)
			)
		)
		(property "Device Type" "REST0025"
			(at -0.148158 1.3462 180)
			(unlocked yes)
			(layer "F.Fab")
			(hide yes)
			(effects
				(font
					(size 1.27 0.9652)
					(thickness 0.000001)
				)
				(justify left)
			)
		)
		(duplicate_pad_numbers_are_jumpers no)
		(fp_poly
			(pts
				(xy 0.635 1.0668) (xy 0.635 -1.0668) (xy -0.635 -1.0668) (xy -0.635 1.0668)
			)
			(stroke
				(width 0)
				(type default)
			)
			(fill no)
			(layer "F.CrtYd")
		)
		(fp_line
			(start 0.254 -0.508)
			(end 0.254 0.508)
			(stroke
				(width 0.0254)
				(type default)
			)
			(layer "F.Fab")
		)
		(fp_line
			(start -0.254 -0.508)
			(end 0.254 -0.508)
			(stroke
				(width 0.0254)
				(type default)
			)
			(layer "F.Fab")
		)
		(fp_line
			(start 0.254 0.508)
			(end -0.254 0.508)
			(stroke
				(width 0.0254)
				(type default)
			)
			(layer "F.Fab")
		)
		(fp_line
			(start -0.254 0.508)
			(end -0.254 -0.508)
			(stroke
				(width 0.0254)
				(type default)
			)
			(layer "F.Fab")
		)
		(pad "1" smd rect
			(at 0 -0.4191 90)
			(size 0.508 0.5334)
			(layers "F.Cu" "F.Mask" "F.Paste")
			(net "_SW1")
		)
		(pad "2" smd rect
			(at 0 0.4191 90)
			(size 0.508 0.5334)
			(layers "F.Cu" "F.Mask" "F.Paste")
			(net "NFP_VDD_CORE_ISEN1_P")
		)
		(zone
			(layer "F.Cu")
			(hatch none 0.5)
			(connect_pads
				(clearance 0)
			)
			(min_thickness 0.25)
			(keepout
				(tracks not_allowed)
				(vias allowed)
				(pads allowed)
				(copperpour not_allowed)
				(footprints allowed)
			)
			(placement
				(enabled no)
				(sheetname "")
			)
			(fill
				(thermal_gap 0.5)
				(thermal_bridge_width 0.5)
				(island_removal_mode 0)
			)
			(polygon
				(pts
					(xy 36.2966 38.9636) (xy 36.3474 38.9636) (xy 36.3474 39.0144) (xy 36.2966 39.0144)
				)
			)
		)
	)
	(footprint ""
		(layer "F.Cu")
		(at 77.343 43.688)
		(property "Reference" "C139"
			(at 0.28067 -1.397 90)
			(unlocked yes)
			(layer "F.SilkS")
			(effects
				(font
					(size 0.7874 0.5842)
					(thickness 0.127)
				)
				(justify left)
			)
		)
		(property "Value" "10UF"
			(at -0.148158 1.7526 90)
			(unlocked yes)
			(layer "F.Fab")
			(hide yes)
			(effects
				(font
					(size 1.27 0.9652)
					(thickness 0.000001)
				)
				(justify left)
			)
		)
		(property "Device Type" "CAPC0058"
			(at -0.148158 1.7526 90)
			(unlocked yes)
			(layer "F.Fab")
			(hide yes)
			(effects
				(font
					(size 1.27 0.9652)
					(thickness 0.000001)
				)
				(justify left)
			)
		)
		(duplicate_pad_numbers_are_jumpers no)
		(fp_circle
			(center 0 0)
			(end 0.127 0)
			(stroke
				(width 0.2032)
				(type default)
			)
			(fill no)
			(layer "F.SilkS")
		)
		(fp_poly
			(pts
				(xy 0.7874 -1.6637) (xy -0.7874 -1.6637) (xy -0.7874 1.6637) (xy 0.7874 1.6637)
			)
			(stroke
				(width 0)
				(type default)
			)
			(fill no)
			(layer "F.CrtYd")
		)
		(fp_line
			(start -0.4064 -0.7874)
			(end 0.4064 -0.7874)
			(stroke
				(width 0.0254)
				(type default)
			)
			(layer "F.Fab")
		)
		(fp_line
			(start -0.4064 0.8128)
			(end -0.4064 -0.7874)
			(stroke
				(width 0.0254)
				(type default)
			)
			(layer "F.Fab")
		)
		(fp_line
			(start 0.4064 -0.7874)
			(end 0.4064 0.8128)
			(stroke
				(width 0.0254)
				(type default)
			)
			(layer "F.Fab")
		)
		(fp_line
			(start 0.4064 0.8128)
			(end -0.4064 0.8128)
			(stroke
				(width 0.0254)
				(type default)
			)
			(layer "F.Fab")
		)
		(pad "1" smd rect
			(at 0 -0.8001)
			(size 0.8636 0.9652)
			(layers "F.Cu" "F.Mask" "F.Paste")
			(net "DDR_VTT")
		)
		(pad "2" smd rect
			(at 0 0.8001)
			(size 0.8636 0.9652)
			(layers "F.Cu" "F.Mask" "F.Paste")
			(net "GND")
		)
	)
	(footprint ""
		(layer "F.Cu")
		(at 2.413 34.163 180)
		(property "Reference" "R131"
			(at 0 0 180)
			(layer "F.SilkS")
			(hide yes)
			(effects
				(font
					(size 1.27 1.27)
				)
			)
		)
		(property "Value" "2K"
			(at -0.148158 1.3462 270)
			(unlocked yes)
			(layer "F.Fab")
			(hide yes)
			(effects
				(font
					(size 1.27 0.9652)
					(thickness 0.000001)
				)
				(justify left)
			)
		)
		(property "Device Type" "REST0138"
			(at -0.148158 1.3462 270)
			(unlocked yes)
			(layer "F.Fab")
			(hide yes)
			(effects
				(font
					(size 1.27 0.9652)
					(thickness 0.000001)
				)
				(justify left)
			)
		)
		(duplicate_pad_numbers_are_jumpers no)
		(fp_poly
			(pts
				(xy 0.635 1.0668) (xy 0.635 -1.0668) (xy -0.635 -1.0668) (xy -0.635 1.0668)
			)
			(stroke
				(width 0)
				(type default)
			)
			(fill no)
			(layer "F.CrtYd")
		)
		(fp_line
			(start 0.254 0.508)
			(end -0.254 0.508)
			(stroke
				(width 0.0254)
				(type default)
			)
			(layer "F.Fab")
		)
		(fp_line
			(start 0.254 -0.508)
			(end 0.254 0.508)
			(stroke
				(width 0.0254)
				(type default)
			)
			(layer "F.Fab")
		)
		(fp_line
			(start -0.254 0.508)
			(end -0.254 -0.508)
			(stroke
				(width 0.0254)
				(type default)
			)
			(layer "F.Fab")
		)
		(fp_line
			(start -0.254 -0.508)
			(end 0.254 -0.508)
			(stroke
				(width 0.0254)
				(type default)
			)
			(layer "F.Fab")
		)
		(pad "1" smd rect
			(at 0 -0.4191 180)
			(size 0.508 0.5334)
			(layers "F.Cu" "F.Mask" "F.Paste")
			(net "PSU_I2C_SCL")
		)
		(pad "2" smd rect
			(at 0 0.4191 180)
			(size 0.508 0.5334)
			(layers "F.Cu" "F.Mask" "F.Paste")
			(net "EXT_3.3V")
		)
		(zone
			(layer "F.Cu")
			(hatch none 0.5)
			(connect_pads
				(clearance 0)
			)
			(min_thickness 0.25)
			(keepout
				(tracks not_allowed)
				(vias allowed)
				(pads allowed)
				(copperpour not_allowed)
				(footprints allowed)
			)
			(placement
				(enabled no)
				(sheetname "")
			)
			(fill
				(thermal_gap 0.5)
				(thermal_bridge_width 0.5)
				(island_removal_mode 0)
			)
			(polygon
				(pts
					(xy 2.3876 34.1884) (xy 2.3876 34.1376) (xy 2.4384 34.1376) (xy 2.4384 34.1884)
				)
			)
		)
	)
	(footprint ""
		(layer "F.Cu")
		(at 80.645 11.811 -90)
		(property "Reference" "C216"
			(at 0.91567 1.778 0)
			(unlocked yes)
			(layer "F.SilkS")
			(effects
				(font
					(size 0.7874 0.5842)
					(thickness 0.127)
				)
				(justify left)
			)
		)
		(property "Value" "1UF"
			(at -0.091846 0.2921 0)
			(unlocked yes)
			(layer "F.Fab")
			(hide yes)
			(effects
				(font
					(size 0.7874 0.5842)
					(thickness 0.2032)
				)
				(justify left)
			)
		)
		(property "Device Type" "CAPC0028"
			(at -0.091846 0.2921 0)
			(unlocked yes)
			(layer "F.Fab")
			(hide yes)
			(effects
				(font
					(size 0.7874 0.5842)
					(thickness 0.2032)
				)
				(justify left)
			)
		)
		(duplicate_pad_numbers_are_jumpers no)
		(fp_poly
			(pts
				(xy 0.635 1.0668) (xy 0.635 -1.0668) (xy -0.635 -1.0668) (xy -0.635 1.0668)
			)
			(stroke
				(width 0)
				(type default)
			)
			(fill no)
			(layer "F.CrtYd")
		)
		(fp_line
			(start -0.254 0.508)
			(end -0.254 -0.508)
			(stroke
				(width 0.0254)
				(type default)
			)
			(layer "F.Fab")
		)
		(fp_line
			(start 0.254 0.508)
			(end -0.254 0.508)
			(stroke
				(width 0.0254)
				(type default)
			)
			(layer "F.Fab")
		)
		(fp_line
			(start -0.254 -0.508)
			(end 0.254 -0.508)
			(stroke
				(width 0.0254)
				(type default)
			)
			(layer "F.Fab")
		)
		(fp_line
			(start 0.254 -0.508)
			(end 0.254 0.508)
			(stroke
				(width 0.0254)
				(type default)
			)
			(layer "F.Fab")
		)
		(pad "1" smd rect
			(at 0 -0.4191 270)
			(size 0.508 0.5334)
			(layers "F.Cu" "F.Mask" "F.Paste")
			(net "DDR_VDDQ")
		)
		(pad "2" smd rect
			(at 0 0.4191 270)
			(size 0.508 0.5334)
			(layers "F.Cu" "F.Mask" "F.Paste")
			(net "GND")
		)
		(zone
			(layer "F.Cu")
			(hatch none 0.5)
			(connect_pads
				(clearance 0)
			)
			(min_thickness 0.25)
			(keepout
				(tracks not_allowed)
				(vias allowed)
				(pads allowed)
				(copperpour not_allowed)
				(footprints allowed)
			)
			(placement
				(enabled no)
				(sheetname "")
			)
			(fill
				(thermal_gap 0.5)
				(thermal_bridge_width 0.5)
				(island_removal_mode 0)
			)
			(polygon
				(pts
					(xy 80.6704 11.8364) (xy 80.6196 11.8364) (xy 80.6196 11.7856) (xy 80.6704 11.7856)
				)
			)
		)
	)
	(footprint ""
		(layer "F.Cu")
		(at 26.162 8.509)
		(property "Reference" "R351"
			(at 0.91567 1.397 90)
			(unlocked yes)
			(layer "F.SilkS")
			(effects
				(font
					(size 0.7874 0.5842)
					(thickness 0.127)
				)
				(justify left)
			)
		)
		(property "Value" "0"
			(at -0.148158 1.3462 90)
			(unlocked yes)
			(layer "F.Fab")
			(hide yes)
			(effects
				(font
					(size 1.27 0.9652)
					(thickness 0.000001)
				)
				(justify left)
			)
		)
		(property "Device Type" "REST1111"
			(at -0.148158 1.3462 90)
			(unlocked yes)
			(layer "F.Fab")
			(hide yes)
			(effects
				(font
					(size 1.27 0.9652)
					(thickness 0.000001)
				)
				(justify left)
			)
		)
		(duplicate_pad_numbers_are_jumpers no)
		(fp_poly
			(pts
				(xy 0.635 1.0668) (xy 0.635 -1.0668) (xy -0.635 -1.0668) (xy -0.635 1.0668)
			)
			(stroke
				(width 0)
				(type default)
			)
			(fill no)
			(layer "F.CrtYd")
		)
		(fp_line
			(start -0.254 -0.508)
			(end 0.254 -0.508)
			(stroke
				(width 0.0254)
				(type default)
			)
			(layer "F.Fab")
		)
		(fp_line
			(start -0.254 0.508)
			(end -0.254 -0.508)
			(stroke
				(width 0.0254)
				(type default)
			)
			(layer "F.Fab")
		)
		(fp_line
			(start 0.254 -0.508)
			(end 0.254 0.508)
			(stroke
				(width 0.0254)
				(type default)
			)
			(layer "F.Fab")
		)
		(fp_line
			(start 0.254 0.508)
			(end -0.254 0.508)
			(stroke
				(width 0.0254)
				(type default)
			)
			(layer "F.Fab")
		)
		(pad "1" smd rect
			(at 0 -0.4191)
			(size 0.508 0.5334)
			(layers "F.Cu" "F.Mask" "F.Paste")
			(net "NFP_SMBUS_SDA")
		)
		(pad "2" smd rect
			(at 0 0.4191)
			(size 0.508 0.5334)
			(layers "F.Cu" "F.Mask" "F.Paste")
			(net "SMBUS_SDA")
		)
		(zone
			(layer "F.Cu")
			(hatch none 0.5)
			(connect_pads
				(clearance 0)
			)
			(min_thickness 0.25)
			(keepout
				(tracks not_allowed)
				(vias allowed)
				(pads allowed)
				(copperpour not_allowed)
				(footprints allowed)
			)
			(placement
				(enabled no)
				(sheetname "")
			)
			(fill
				(thermal_gap 0.5)
				(thermal_bridge_width 0.5)
				(island_removal_mode 0)
			)
			(polygon
				(pts
					(xy 26.1874 8.4836) (xy 26.1874 8.5344) (xy 26.1366 8.5344) (xy 26.1366 8.4836)
				)
			)
		)
	)
	(footprint ""
		(layer "F.Cu")
		(at 36.322 39.878 90)
		(property "Reference" "R325"
			(at 0 0 90)
			(layer "F.SilkS")
			(hide yes)
			(effects
				(font
					(size 1.27 1.27)
				)
			)
		)
		(property "Value" "86.6K"
			(at -0.148158 1.3462 180)
			(unlocked yes)
			(layer "F.Fab")
			(hide yes)
			(effects
				(font
					(size 1.27 0.9652)
					(thickness 0.000001)
				)
				(justify left)
			)
		)
		(property "Device Type" "REST0029"
			(at -0.148158 1.3462 180)
			(unlocked yes)
			(layer "F.Fab")
			(hide yes)
			(effects
				(font
					(size 1.27 0.9652)
					(thickness 0.000001)
				)
				(justify left)
			)
		)
		(duplicate_pad_numbers_are_jumpers no)
		(fp_poly
			(pts
				(xy 0.635 1.0668) (xy 0.635 -1.0668) (xy -0.635 -1.0668) (xy -0.635 1.0668)
			)
			(stroke
				(width 0)
				(type default)
			)
			(fill no)
			(layer "F.CrtYd")
		)
		(fp_line
			(start 0.254 -0.508)
			(end 0.254 0.508)
			(stroke
				(width 0.0254)
				(type default)
			)
			(layer "F.Fab")
		)
		(fp_line
			(start -0.254 -0.508)
			(end 0.254 -0.508)
			(stroke
				(width 0.0254)
				(type default)
			)
			(layer "F.Fab")
		)
		(fp_line
			(start 0.254 0.508)
			(end -0.254 0.508)
			(stroke
				(width 0.0254)
				(type default)
			)
			(layer "F.Fab")
		)
		(fp_line
			(start -0.254 0.508)
			(end -0.254 -0.508)
			(stroke
				(width 0.0254)
				(type default)
			)
			(layer "F.Fab")
		)
		(pad "1" smd rect
			(at 0 -0.4191 90)
			(size 0.508 0.5334)
			(layers "F.Cu" "F.Mask" "F.Paste")
			(net "10N2528")
		)
		(pad "2" smd rect
			(at 0 0.4191 90)
			(size 0.508 0.5334)
			(layers "F.Cu" "F.Mask" "F.Paste")
			(net "NFP_VDD_CORE_ISEN1_P")
		)
		(zone
			(layer "F.Cu")
			(hatch none 0.5)
			(connect_pads
				(clearance 0)
			)
			(min_thickness 0.25)
			(keepout
				(tracks not_allowed)
				(vias allowed)
				(pads allowed)
				(copperpour not_allowed)
				(footprints allowed)
			)
			(placement
				(enabled no)
				(sheetname "")
			)
			(fill
				(thermal_gap 0.5)
				(thermal_bridge_width 0.5)
				(island_removal_mode 0)
			)
			(polygon
				(pts
					(xy 36.2966 39.8526) (xy 36.3474 39.8526) (xy 36.3474 39.9034) (xy 36.2966 39.9034)
				)
			)
		)
	)
	(footprint ""
		(layer "F.Cu")
		(at 36.322 36.195 90)
		(property "Reference" "R180"
			(at 0 0 90)
			(layer "F.SilkS")
			(hide yes)
			(effects
				(font
					(size 1.27 1.27)
				)
			)
		)
		(property "Value" "0"
			(at -0.148158 1.3462 180)
			(unlocked yes)
			(layer "F.Fab")
			(hide yes)
			(effects
				(font
					(size 1.27 0.9652)
					(thickness 0.000001)
				)
				(justify left)
			)
		)
		(property "Device Type" "REST1111"
			(at -0.148158 1.3462 180)
			(unlocked yes)
			(layer "F.Fab")
			(hide yes)
			(effects
				(font
					(size 1.27 0.9652)
					(thickness 0.000001)
				)
				(justify left)
			)
		)
		(duplicate_pad_numbers_are_jumpers no)
		(fp_poly
			(pts
				(xy 0.635 1.0668) (xy 0.635 -1.0668) (xy -0.635 -1.0668) (xy -0.635 1.0668)
			)
			(stroke
				(width 0)
				(type default)
			)
			(fill no)
			(layer "F.CrtYd")
		)
		(fp_line
			(start 0.254 -0.508)
			(end 0.254 0.508)
			(stroke
				(width 0.0254)
				(type default)
			)
			(layer "F.Fab")
		)
		(fp_line
			(start -0.254 -0.508)
			(end 0.254 -0.508)
			(stroke
				(width 0.0254)
				(type default)
			)
			(layer "F.Fab")
		)
		(fp_line
			(start 0.254 0.508)
			(end -0.254 0.508)
			(stroke
				(width 0.0254)
				(type default)
			)
			(layer "F.Fab")
		)
		(fp_line
			(start -0.254 0.508)
			(end -0.254 -0.508)
			(stroke
				(width 0.0254)
				(type default)
			)
			(layer "F.Fab")
		)
		(pad "1" smd rect
			(at 0 -0.4191 90)
			(size 0.508 0.5334)
			(layers "F.Cu" "F.Mask" "F.Paste")
			(net "10N2409")
		)
		(pad "2" smd rect
			(at 0 0.4191 90)
			(size 0.508 0.5334)
			(layers "F.Cu" "F.Mask" "F.Paste")
			(net "VDD_5.0V")
		)
		(zone
			(layer "F.Cu")
			(hatch none 0.5)
			(connect_pads
				(clearance 0)
			)
			(min_thickness 0.25)
			(keepout
				(tracks not_allowed)
				(vias allowed)
				(pads allowed)
				(copperpour not_allowed)
				(footprints allowed)
			)
			(placement
				(enabled no)
				(sheetname "")
			)
			(fill
				(thermal_gap 0.5)
				(thermal_bridge_width 0.5)
				(island_removal_mode 0)
			)
			(polygon
				(pts
					(xy 36.2966 36.1696) (xy 36.3474 36.1696) (xy 36.3474 36.2204) (xy 36.2966 36.2204)
				)
			)
		)
	)
	(footprint ""
		(layer "F.Cu")
		(at 15.748 29.0195 -90)
		(property "Reference" "TP55"
			(at -0.889 0.86233 90)
			(unlocked yes)
			(layer "F.SilkS")
			(effects
				(font
					(size 0.7874 0.5842)
					(thickness 0.127)
				)
				(justify left)
			)
		)
		(property "Value" "*"
			(at -0.4826 -0.14732 270)
			(unlocked yes)
			(layer "F.Fab")
			(hide yes)
			(effects
				(font
					(size 1.27 0.9652)
					(thickness 0.000001)
				)
				(justify left)
			)
		)
		(property "Device Type" "TP_SMALL"
			(at -0.4826 -0.14732 270)
			(unlocked yes)
			(layer "F.Fab")
			(hide yes)
			(effects
				(font
					(size 1.27 0.9652)
					(thickness 0.000001)
				)
				(justify left)
			)
		)
		(duplicate_pad_numbers_are_jumpers no)
		(fp_line
			(start -0.8636 0.8636)
			(end 0.8636 0.8636)
			(stroke
				(width 0.1524)
				(type default)
			)
			(layer "F.SilkS")
		)
		(fp_line
			(start 0.8636 0.8636)
			(end 0.8636 -0.8636)
			(stroke
				(width 0.1524)
				(type default)
			)
			(layer "F.SilkS")
		)
		(fp_line
			(start -0.8636 -0.8636)
			(end -0.8636 0.8636)
			(stroke
				(width 0.1524)
				(type default)
			)
			(layer "F.SilkS")
		)
		(fp_line
			(start 0.8636 -0.8636)
			(end -0.8636 -0.8636)
			(stroke
				(width 0.1524)
				(type default)
			)
			(layer "F.SilkS")
		)
		(fp_poly
			(pts
				(xy -0.635 -0.635) (xy -0.635 0.635) (xy 0.635 0.635) (xy 0.635 -0.635)
			)
			(stroke
				(width 0)
				(type default)
			)
			(fill no)
			(layer "F.CrtYd")
		)
		(pad "1" smd rect
			(at 0 0 270)
			(size 1.27 1.27)
			(layers "F.Cu" "F.Mask" "F.Paste")
			(net "GND")
		)
	)
	(footprint ""
		(layer "F.Cu")
		(at 19.7739 42.9641)
		(property "Reference" "L12"
			(at -1.651 2.05867 0)
			(unlocked yes)
			(layer "F.SilkS")
			(effects
				(font
					(size 0.7874 0.5842)
					(thickness 0.127)
				)
				(justify left)
			)
		)
		(property "Value" "2.2UH"
			(at -0.483362 -0.148082 0)
			(unlocked yes)
			(layer "F.Fab")
			(hide yes)
			(effects
				(font
					(size 1.27 0.9652)
					(thickness 0.000001)
				)
				(justify left)
			)
		)
		(property "Device Type" "INDS0060"
			(at -0.483362 -0.148082 0)
			(unlocked yes)
			(layer "F.Fab")
			(hide yes)
			(effects
				(font
					(size 1.27 0.9652)
					(thickness 0.000001)
				)
				(justify left)
			)
		)
		(duplicate_pad_numbers_are_jumpers no)
		(fp_line
			(start -1.27 -1.397)
			(end 1.27 -1.397)
			(stroke
				(width 0.1524)
				(type default)
			)
			(layer "F.SilkS")
		)
		(fp_line
			(start 1.27 1.397)
			(end -1.27 1.397)
			(stroke
				(width 0.1524)
				(type default)
			)
			(layer "F.SilkS")
		)
		(fp_poly
			(pts
				(xy 2.159 -1.651) (xy 2.159 1.651) (xy -2.159 1.651) (xy -2.159 -1.651)
			)
			(stroke
				(width 0)
				(type default)
			)
			(fill no)
			(layer "F.CrtYd")
		)
		(fp_line
			(start -1.3462 -1.1049)
			(end -1.3462 1.1049)
			(stroke
				(width 0.1524)
				(type default)
			)
			(layer "F.Fab")
		)
		(fp_line
			(start -1.3462 1.1049)
			(end 1.3462 1.1049)
			(stroke
				(width 0.1524)
				(type default)
			)
			(layer "F.Fab")
		)
		(fp_line
			(start 1.3462 -1.1049)
			(end -1.3462 -1.1049)
			(stroke
				(width 0.1524)
				(type default)
			)
			(layer "F.Fab")
		)
		(fp_line
			(start 1.3462 1.1049)
			(end 1.3462 -1.1049)
			(stroke
				(width 0.1524)
				(type default)
			)
			(layer "F.Fab")
		)
		(pad "1" smd rect
			(at -1.1303 0)
			(size 1.1938 2.3368)
			(layers "F.Cu" "F.Mask" "F.Paste")
			(net "11N1971")
		)
		(pad "2" smd rect
			(at 1.1303 0)
			(size 1.1938 2.3368)
			(layers "F.Cu" "F.Mask" "F.Paste")
			(net "DDR_1.8V")
		)
		(zone
			(layer "F.Cu")
			(hatch none 0.5)
			(connect_pads
				(clearance 0)
			)
			(min_thickness 0.25)
			(keepout
				(tracks allowed)
				(vias not_allowed)
				(pads allowed)
				(copperpour not_allowed)
				(footprints allowed)
			)
			(placement
				(enabled no)
				(sheetname "")
			)
			(fill
				(thermal_gap 0.5)
				(thermal_bridge_width 0.5)
				(island_removal_mode 0)
			)
			(polygon
				(pts
					(xy 18.4277 44.069) (xy 21.1201 44.069) (xy 21.1201 41.8592) (xy 18.4277 41.8592)
				)
			)
		)
	)
	(footprint ""
		(layer "F.Cu")
		(at 3.302 34.163 180)
		(property "Reference" "R130"
			(at 0 0 180)
			(layer "F.SilkS")
			(hide yes)
			(effects
				(font
					(size 1.27 1.27)
				)
			)
		)
		(property "Value" "2K"
			(at -0.148158 1.3462 270)
			(unlocked yes)
			(layer "F.Fab")
			(hide yes)
			(effects
				(font
					(size 1.27 0.9652)
					(thickness 0.000001)
				)
				(justify left)
			)
		)
		(property "Device Type" "REST0138"
			(at -0.148158 1.3462 270)
			(unlocked yes)
			(layer "F.Fab")
			(hide yes)
			(effects
				(font
					(size 1.27 0.9652)
					(thickness 0.000001)
				)
				(justify left)
			)
		)
		(duplicate_pad_numbers_are_jumpers no)
		(fp_poly
			(pts
				(xy 0.635 1.0668) (xy 0.635 -1.0668) (xy -0.635 -1.0668) (xy -0.635 1.0668)
			)
			(stroke
				(width 0)
				(type default)
			)
			(fill no)
			(layer "F.CrtYd")
		)
		(fp_line
			(start 0.254 0.508)
			(end -0.254 0.508)
			(stroke
				(width 0.0254)
				(type default)
			)
			(layer "F.Fab")
		)
		(fp_line
			(start 0.254 -0.508)
			(end 0.254 0.508)
			(stroke
				(width 0.0254)
				(type default)
			)
			(layer "F.Fab")
		)
		(fp_line
			(start -0.254 0.508)
			(end -0.254 -0.508)
			(stroke
				(width 0.0254)
				(type default)
			)
			(layer "F.Fab")
		)
		(fp_line
			(start -0.254 -0.508)
			(end 0.254 -0.508)
			(stroke
				(width 0.0254)
				(type default)
			)
			(layer "F.Fab")
		)
		(pad "1" smd rect
			(at 0 -0.4191 180)
			(size 0.508 0.5334)
			(layers "F.Cu" "F.Mask" "F.Paste")
			(net "PSU_I2C_SDA")
		)
		(pad "2" smd rect
			(at 0 0.4191 180)
			(size 0.508 0.5334)
			(layers "F.Cu" "F.Mask" "F.Paste")
			(net "EXT_3.3V")
		)
		(zone
			(layer "F.Cu")
			(hatch none 0.5)
			(connect_pads
				(clearance 0)
			)
			(min_thickness 0.25)
			(keepout
				(tracks not_allowed)
				(vias allowed)
				(pads allowed)
				(copperpour not_allowed)
				(footprints allowed)
			)
			(placement
				(enabled no)
				(sheetname "")
			)
			(fill
				(thermal_gap 0.5)
				(thermal_bridge_width 0.5)
				(island_removal_mode 0)
			)
			(polygon
				(pts
					(xy 3.2766 34.1884) (xy 3.2766 34.1376) (xy 3.3274 34.1376) (xy 3.3274 34.1884)
				)
			)
		)
	)
	(footprint ""
		(layer "F.Cu")
		(at 37.719 41.656 180)
		(property "Reference" "R401"
			(at 0 0 180)
			(layer "F.SilkS")
			(hide yes)
			(effects
				(font
					(size 1.27 1.27)
				)
			)
		)
		(property "Value" "680"
			(at -0.148158 1.7526 270)
			(unlocked yes)
			(layer "F.Fab")
			(hide yes)
			(effects
				(font
					(size 1.27 0.9652)
					(thickness 0.000001)
				)
				(justify left)
			)
		)
		(property "Device Type" "REST0283"
			(at -0.148158 1.7526 270)
			(unlocked yes)
			(layer "F.Fab")
			(hide yes)
			(effects
				(font
					(size 1.27 0.9652)
					(thickness 0.000001)
				)
				(justify left)
			)
		)
		(duplicate_pad_numbers_are_jumpers no)
		(fp_circle
			(center 0 0)
			(end -0.127 0)
			(stroke
				(width 0.2032)
				(type default)
			)
			(fill no)
			(layer "F.SilkS")
		)
		(fp_poly
			(pts
				(xy 0.7874 -1.6637) (xy -0.7874 -1.6637) (xy -0.7874 1.6637) (xy 0.7874 1.6637)
			)
			(stroke
				(width 0)
				(type default)
			)
			(fill no)
			(layer "F.CrtYd")
		)
		(fp_line
			(start 0.4064 0.8128)
			(end -0.4064 0.8128)
			(stroke
				(width 0.0254)
				(type default)
			)
			(layer "F.Fab")
		)
		(fp_line
			(start 0.4064 -0.8128)
			(end 0.4064 0.8128)
			(stroke
				(width 0.0254)
				(type default)
			)
			(layer "F.Fab")
		)
		(fp_line
			(start -0.4064 0.8128)
			(end -0.4064 -0.8128)
			(stroke
				(width 0.0254)
				(type default)
			)
			(layer "F.Fab")
		)
		(fp_line
			(start -0.4064 -0.8128)
			(end 0.4064 -0.8128)
			(stroke
				(width 0.0254)
				(type default)
			)
			(layer "F.Fab")
		)
		(pad "1" smd rect
			(at 0 -0.8001 180)
			(size 0.762 0.9652)
			(layers "F.Cu" "F.Mask" "F.Paste")
			(net "EXT_12.0V")
		)
		(pad "2" smd rect
			(at 0 0.8001 180)
			(size 0.762 0.9652)
			(layers "F.Cu" "F.Mask" "F.Paste")
			(net "10N2370")
		)
		(zone
			(layer "F.Cu")
			(hatch none 0.5)
			(connect_pads
				(clearance 0)
			)
			(min_thickness 0.25)
			(keepout
				(tracks not_allowed)
				(vias allowed)
				(pads allowed)
				(copperpour not_allowed)
				(footprints allowed)
			)
			(placement
				(enabled no)
				(sheetname "")
			)
			(fill
				(thermal_gap 0.5)
				(thermal_bridge_width 0.5)
				(island_removal_mode 0)
			)
			(polygon
				(pts
					(xy 37.7825 41.91) (xy 37.6555 41.91) (xy 37.6555 41.402) (xy 37.7825 41.402)
				)
			)
		)
	)
	(footprint ""
		(layer "F.Cu")
		(at 3.429 31.75)
		(property "Reference" "TP48"
			(at 1.67767 1.778 90)
			(unlocked yes)
			(layer "F.SilkS")
			(effects
				(font
					(size 0.7874 0.5842)
					(thickness 0.127)
				)
				(justify left)
			)
		)
		(property "Value" "*"
			(at -0.4826 -0.14732 0)
			(unlocked yes)
			(layer "F.Fab")
			(hide yes)
			(effects
				(font
					(size 1.27 0.9652)
					(thickness 0.000001)
				)
				(justify left)
			)
		)
		(property "Device Type" "TP_SMALL"
			(at -0.4826 -0.14732 0)
			(unlocked yes)
			(layer "F.Fab")
			(hide yes)
			(effects
				(font
					(size 1.27 0.9652)
					(thickness 0.000001)
				)
				(justify left)
			)
		)
		(duplicate_pad_numbers_are_jumpers no)
		(fp_line
			(start -0.8636 -0.8636)
			(end -0.8636 0.8636)
			(stroke
				(width 0.1524)
				(type default)
			)
			(layer "F.SilkS")
		)
		(fp_line
			(start -0.8636 0.8636)
			(end 0.8636 0.8636)
			(stroke
				(width 0.1524)
				(type default)
			)
			(layer "F.SilkS")
		)
		(fp_line
			(start 0.8636 -0.8636)
			(end -0.8636 -0.8636)
			(stroke
				(width 0.1524)
				(type default)
			)
			(layer "F.SilkS")
		)
		(fp_line
			(start 0.8636 0.8636)
			(end 0.8636 -0.8636)
			(stroke
				(width 0.1524)
				(type default)
			)
			(layer "F.SilkS")
		)
		(fp_poly
			(pts
				(xy -0.635 -0.635) (xy -0.635 0.635) (xy 0.635 0.635) (xy 0.635 -0.635)
			)
			(stroke
				(width 0)
				(type default)
			)
			(fill no)
			(layer "F.CrtYd")
		)
		(pad "1" smd rect
			(at 0 0)
			(size 1.27 1.27)
			(layers "F.Cu" "F.Mask" "F.Paste")
			(net "VDD_1.2V")
		)
	)
	(footprint ""
		(layer "F.Cu")
		(at 25.908 37.719 90)
		(property "Reference" "R88"
			(at 0 0 90)
			(layer "F.SilkS")
			(hide yes)
			(effects
				(font
					(size 1.27 1.27)
				)
			)
		)
		(property "Value" "4.75K"
			(at -0.148158 1.3462 180)
			(unlocked yes)
			(layer "F.Fab")
			(hide yes)
			(effects
				(font
					(size 1.27 0.9652)
					(thickness 0.000001)
				)
				(justify left)
			)
		)
		(property "Device Type" "REST4024"
			(at -0.148158 1.3462 180)
			(unlocked yes)
			(layer "F.Fab")
			(hide yes)
			(effects
				(font
					(size 1.27 0.9652)
					(thickness 0.000001)
				)
				(justify left)
			)
		)
		(duplicate_pad_numbers_are_jumpers no)
		(fp_poly
			(pts
				(xy 0.635 1.0668) (xy 0.635 -1.0668) (xy -0.635 -1.0668) (xy -0.635 1.0668)
			)
			(stroke
				(width 0)
				(type default)
			)
			(fill no)
			(layer "F.CrtYd")
		)
		(fp_line
			(start 0.254 -0.508)
			(end 0.254 0.508)
			(stroke
				(width 0.0254)
				(type default)
			)
			(layer "F.Fab")
		)
		(fp_line
			(start -0.254 -0.508)
			(end 0.254 -0.508)
			(stroke
				(width 0.0254)
				(type default)
			)
			(layer "F.Fab")
		)
		(fp_line
			(start 0.254 0.508)
			(end -0.254 0.508)
			(stroke
				(width 0.0254)
				(type default)
			)
			(layer "F.Fab")
		)
		(fp_line
			(start -0.254 0.508)
			(end -0.254 -0.508)
			(stroke
				(width 0.0254)
				(type default)
			)
			(layer "F.Fab")
		)
		(pad "1" smd rect
			(at 0 -0.4191 90)
			(size 0.508 0.5334)
			(layers "F.Cu" "F.Mask" "F.Paste")
			(net "GND")
		)
		(pad "2" smd rect
			(at 0 0.4191 90)
			(size 0.508 0.5334)
			(layers "F.Cu" "F.Mask" "F.Paste")
			(net "VDD_CORE_EN")
		)
		(zone
			(layer "F.Cu")
			(hatch none 0.5)
			(connect_pads
				(clearance 0)
			)
			(min_thickness 0.25)
			(keepout
				(tracks not_allowed)
				(vias allowed)
				(pads allowed)
				(copperpour not_allowed)
				(footprints allowed)
			)
			(placement
				(enabled no)
				(sheetname "")
			)
			(fill
				(thermal_gap 0.5)
				(thermal_bridge_width 0.5)
				(island_removal_mode 0)
			)
			(polygon
				(pts
					(xy 25.8826 37.6936) (xy 25.9334 37.6936) (xy 25.9334 37.7444) (xy 25.8826 37.7444)
				)
			)
		)
	)
	(footprint ""
		(layer "F.Cu")
		(at 30.988 32.639 180)
		(property "Reference" "R94"
			(at 0 0 180)
			(layer "F.SilkS")
			(hide yes)
			(effects
				(font
					(size 1.27 1.27)
				)
			)
		)
		(property "Value" "4.75K"
			(at -0.148158 1.3462 270)
			(unlocked yes)
			(layer "F.Fab")
			(hide yes)
			(effects
				(font
					(size 1.27 0.9652)
					(thickness 0.000001)
				)
				(justify left)
			)
		)
		(property "Device Type" "REST4024"
			(at -0.148158 1.3462 270)
			(unlocked yes)
			(layer "F.Fab")
			(hide yes)
			(effects
				(font
					(size 1.27 0.9652)
					(thickness 0.000001)
				)
				(justify left)
			)
		)
		(duplicate_pad_numbers_are_jumpers no)
		(fp_poly
			(pts
				(xy 0.635 1.0668) (xy 0.635 -1.0668) (xy -0.635 -1.0668) (xy -0.635 1.0668)
			)
			(stroke
				(width 0)
				(type default)
			)
			(fill no)
			(layer "F.CrtYd")
		)
		(fp_line
			(start 0.254 0.508)
			(end -0.254 0.508)
			(stroke
				(width 0.0254)
				(type default)
			)
			(layer "F.Fab")
		)
		(fp_line
			(start 0.254 -0.508)
			(end 0.254 0.508)
			(stroke
				(width 0.0254)
				(type default)
			)
			(layer "F.Fab")
		)
		(fp_line
			(start -0.254 0.508)
			(end -0.254 -0.508)
			(stroke
				(width 0.0254)
				(type default)
			)
			(layer "F.Fab")
		)
		(fp_line
			(start -0.254 -0.508)
			(end 0.254 -0.508)
			(stroke
				(width 0.0254)
				(type default)
			)
			(layer "F.Fab")
		)
		(pad "1" smd rect
			(at 0 -0.4191 180)
			(size 0.508 0.5334)
			(layers "F.Cu" "F.Mask" "F.Paste")
			(net "_NFP_CORE_VID3")
		)
		(pad "2" smd rect
			(at 0 0.4191 180)
			(size 0.508 0.5334)
			(layers "F.Cu" "F.Mask" "F.Paste")
			(net "VDD_1.2V")
		)
		(zone
			(layer "F.Cu")
			(hatch none 0.5)
			(connect_pads
				(clearance 0)
			)
			(min_thickness 0.25)
			(keepout
				(tracks not_allowed)
				(vias allowed)
				(pads allowed)
				(copperpour not_allowed)
				(footprints allowed)
			)
			(placement
				(enabled no)
				(sheetname "")
			)
			(fill
				(thermal_gap 0.5)
				(thermal_bridge_width 0.5)
				(island_removal_mode 0)
			)
			(polygon
				(pts
					(xy 30.9626 32.6644) (xy 30.9626 32.6136) (xy 31.0134 32.6136) (xy 31.0134 32.6644)
				)
			)
		)
	)
	(footprint ""
		(layer "F.Cu")
		(at 35.433 32.639)
		(property "Reference" "R80"
			(at 0 0 0)
			(layer "F.SilkS")
			(hide yes)
			(effects
				(font
					(size 1.27 1.27)
				)
			)
		)
		(property "Value" "4.75K"
			(at -0.148158 1.3462 90)
			(unlocked yes)
			(layer "F.Fab")
			(hide yes)
			(effects
				(font
					(size 1.27 0.9652)
					(thickness 0.000001)
				)
				(justify left)
			)
		)
		(property "Device Type" "REST4024"
			(at -0.148158 1.3462 90)
			(unlocked yes)
			(layer "F.Fab")
			(hide yes)
			(effects
				(font
					(size 1.27 0.9652)
					(thickness 0.000001)
				)
				(justify left)
			)
		)
		(duplicate_pad_numbers_are_jumpers no)
		(fp_poly
			(pts
				(xy 0.635 1.0668) (xy 0.635 -1.0668) (xy -0.635 -1.0668) (xy -0.635 1.0668)
			)
			(stroke
				(width 0)
				(type default)
			)
			(fill no)
			(layer "F.CrtYd")
		)
		(fp_line
			(start -0.254 -0.508)
			(end 0.254 -0.508)
			(stroke
				(width 0.0254)
				(type default)
			)
			(layer "F.Fab")
		)
		(fp_line
			(start -0.254 0.508)
			(end -0.254 -0.508)
			(stroke
				(width 0.0254)
				(type default)
			)
			(layer "F.Fab")
		)
		(fp_line
			(start 0.254 -0.508)
			(end 0.254 0.508)
			(stroke
				(width 0.0254)
				(type default)
			)
			(layer "F.Fab")
		)
		(fp_line
			(start 0.254 0.508)
			(end -0.254 0.508)
			(stroke
				(width 0.0254)
				(type default)
			)
			(layer "F.Fab")
		)
		(pad "1" smd rect
			(at 0 -0.4191)
			(size 0.508 0.5334)
			(layers "F.Cu" "F.Mask" "F.Paste")
			(net "GND")
		)
		(pad "2" smd rect
			(at 0 0.4191)
			(size 0.508 0.5334)
			(layers "F.Cu" "F.Mask" "F.Paste")
			(net "_NFP_CORE_VID6")
		)
		(zone
			(layer "F.Cu")
			(hatch none 0.5)
			(connect_pads
				(clearance 0)
			)
			(min_thickness 0.25)
			(keepout
				(tracks not_allowed)
				(vias allowed)
				(pads allowed)
				(copperpour not_allowed)
				(footprints allowed)
			)
			(placement
				(enabled no)
				(sheetname "")
			)
			(fill
				(thermal_gap 0.5)
				(thermal_bridge_width 0.5)
				(island_removal_mode 0)
			)
			(polygon
				(pts
					(xy 35.4584 32.6136) (xy 35.4584 32.6644) (xy 35.4076 32.6644) (xy 35.4076 32.6136)
				)
			)
		)
	)
	(footprint ""
		(layer "F.Cu")
		(at 80.645 20.574 -90)
		(property "Reference" "C215"
			(at -0.889 -0.53467 90)
			(unlocked yes)
			(layer "F.SilkS")
			(effects
				(font
					(size 0.7874 0.5842)
					(thickness 0.127)
				)
				(justify left)
			)
		)
		(property "Value" "1UF"
			(at -0.091846 0.2921 0)
			(unlocked yes)
			(layer "F.Fab")
			(hide yes)
			(effects
				(font
					(size 0.7874 0.5842)
					(thickness 0.2032)
				)
				(justify left)
			)
		)
		(property "Device Type" "CAPC0028"
			(at -0.091846 0.2921 0)
			(unlocked yes)
			(layer "F.Fab")
			(hide yes)
			(effects
				(font
					(size 0.7874 0.5842)
					(thickness 0.2032)
				)
				(justify left)
			)
		)
		(duplicate_pad_numbers_are_jumpers no)
		(fp_poly
			(pts
				(xy 0.635 1.0668) (xy 0.635 -1.0668) (xy -0.635 -1.0668) (xy -0.635 1.0668)
			)
			(stroke
				(width 0)
				(type default)
			)
			(fill no)
			(layer "F.CrtYd")
		)
		(fp_line
			(start -0.254 0.508)
			(end -0.254 -0.508)
			(stroke
				(width 0.0254)
				(type default)
			)
			(layer "F.Fab")
		)
		(fp_line
			(start 0.254 0.508)
			(end -0.254 0.508)
			(stroke
				(width 0.0254)
				(type default)
			)
			(layer "F.Fab")
		)
		(fp_line
			(start -0.254 -0.508)
			(end 0.254 -0.508)
			(stroke
				(width 0.0254)
				(type default)
			)
			(layer "F.Fab")
		)
		(fp_line
			(start 0.254 -0.508)
			(end 0.254 0.508)
			(stroke
				(width 0.0254)
				(type default)
			)
			(layer "F.Fab")
		)
		(pad "1" smd rect
			(at 0 -0.4191 270)
			(size 0.508 0.5334)
			(layers "F.Cu" "F.Mask" "F.Paste")
			(net "DDR_VDDQ")
		)
		(pad "2" smd rect
			(at 0 0.4191 270)
			(size 0.508 0.5334)
			(layers "F.Cu" "F.Mask" "F.Paste")
			(net "GND")
		)
		(zone
			(layer "F.Cu")
			(hatch none 0.5)
			(connect_pads
				(clearance 0)
			)
			(min_thickness 0.25)
			(keepout
				(tracks not_allowed)
				(vias allowed)
				(pads allowed)
				(copperpour not_allowed)
				(footprints allowed)
			)
			(placement
				(enabled no)
				(sheetname "")
			)
			(fill
				(thermal_gap 0.5)
				(thermal_bridge_width 0.5)
				(island_removal_mode 0)
			)
			(polygon
				(pts
					(xy 80.6704 20.5994) (xy 80.6196 20.5994) (xy 80.6196 20.5486) (xy 80.6704 20.5486)
				)
			)
		)
	)
	(footprint ""
		(layer "F.Cu")
		(at 74.651006 18.255996)
		(property "Reference" "V_A-DM2"
			(at 0 0 0)
			(layer "F.SilkS")
			(hide yes)
			(effects
				(font
					(size 1.27 1.27)
				)
			)
		)
		(property "Value" ""
			(at 0 0 0)
			(layer "F.Fab")
			(effects
				(font
					(size 1.27 1.27)
				)
			)
		)
		(duplicate_pad_numbers_are_jumpers no)
		(pad "1" thru_hole circle
			(at 0 0)
			(size 0.762 0.762)
			(drill 0.20574)
			(layers "*.Cu" "*.Mask")
			(remove_unused_layers no)
			(net "DDR0_32A_DM2")
			(clearance 0.127)
			(thermal_gap 0.127)
			(padstack
				(mode front_inner_back)
				(layer "Inner"
					(shape circle)
					(size 0.4572 0.4572)
					(clearance 0.1143)
				)
				(layer "B.Cu"
					(shape circle)
					(size 0.4572 0.4572)
					(clearance 0.1143)
				)
			)
		)
	)
	(footprint ""
		(layer "F.Cu")
		(at 77.216 4.572)
		(property "Reference" "C206"
			(at 0 0 0)
			(layer "F.SilkS")
			(hide yes)
			(effects
				(font
					(size 1.27 1.27)
				)
			)
		)
		(property "Value" "1UF"
			(at -0.091846 0.2921 90)
			(unlocked yes)
			(layer "F.Fab")
			(hide yes)
			(effects
				(font
					(size 0.7874 0.5842)
					(thickness 0.2032)
				)
				(justify left)
			)
		)
		(property "Device Type" "CAPC0028"
			(at -0.091846 0.2921 90)
			(unlocked yes)
			(layer "F.Fab")
			(hide yes)
			(effects
				(font
					(size 0.7874 0.5842)
					(thickness 0.2032)
				)
				(justify left)
			)
		)
		(duplicate_pad_numbers_are_jumpers no)
		(fp_poly
			(pts
				(xy 0.635 1.0668) (xy 0.635 -1.0668) (xy -0.635 -1.0668) (xy -0.635 1.0668)
			)
			(stroke
				(width 0)
				(type default)
			)
			(fill no)
			(layer "F.CrtYd")
		)
		(fp_line
			(start -0.254 -0.508)
			(end 0.254 -0.508)
			(stroke
				(width 0.0254)
				(type default)
			)
			(layer "F.Fab")
		)
		(fp_line
			(start -0.254 0.508)
			(end -0.254 -0.508)
			(stroke
				(width 0.0254)
				(type default)
			)
			(layer "F.Fab")
		)
		(fp_line
			(start 0.254 -0.508)
			(end 0.254 0.508)
			(stroke
				(width 0.0254)
				(type default)
			)
			(layer "F.Fab")
		)
		(fp_line
			(start 0.254 0.508)
			(end -0.254 0.508)
			(stroke
				(width 0.0254)
				(type default)
			)
			(layer "F.Fab")
		)
		(pad "1" smd rect
			(at 0 -0.4191)
			(size 0.508 0.5334)
			(layers "F.Cu" "F.Mask" "F.Paste")
			(net "DDR0_32A_VREF0B")
		)
		(pad "2" smd rect
			(at 0 0.4191)
			(size 0.508 0.5334)
			(layers "F.Cu" "F.Mask" "F.Paste")
			(net "GND")
		)
		(zone
			(layer "F.Cu")
			(hatch none 0.5)
			(connect_pads
				(clearance 0)
			)
			(min_thickness 0.25)
			(keepout
				(tracks not_allowed)
				(vias allowed)
				(pads allowed)
				(copperpour not_allowed)
				(footprints allowed)
			)
			(placement
				(enabled no)
				(sheetname "")
			)
			(fill
				(thermal_gap 0.5)
				(thermal_bridge_width 0.5)
				(island_removal_mode 0)
			)
			(polygon
				(pts
					(xy 77.2414 4.5466) (xy 77.2414 4.5974) (xy 77.1906 4.5974) (xy 77.1906 4.5466)
				)
			)
		)
	)
	(footprint ""
		(layer "F.Cu")
		(at 33.655 32.639 180)
		(property "Reference" "R77"
			(at 0 0 180)
			(layer "F.SilkS")
			(hide yes)
			(effects
				(font
					(size 1.27 1.27)
				)
			)
		)
		(property "Value" "4.75K"
			(at -0.148158 1.3462 270)
			(unlocked yes)
			(layer "F.Fab")
			(hide yes)
			(effects
				(font
					(size 1.27 0.9652)
					(thickness 0.000001)
				)
				(justify left)
			)
		)
		(property "Device Type" "REST4024"
			(at -0.148158 1.3462 270)
			(unlocked yes)
			(layer "F.Fab")
			(hide yes)
			(effects
				(font
					(size 1.27 0.9652)
					(thickness 0.000001)
				)
				(justify left)
			)
		)
		(duplicate_pad_numbers_are_jumpers no)
		(fp_poly
			(pts
				(xy 0.635 1.0668) (xy 0.635 -1.0668) (xy -0.635 -1.0668) (xy -0.635 1.0668)
			)
			(stroke
				(width 0)
				(type default)
			)
			(fill no)
			(layer "F.CrtYd")
		)
		(fp_line
			(start 0.254 0.508)
			(end -0.254 0.508)
			(stroke
				(width 0.0254)
				(type default)
			)
			(layer "F.Fab")
		)
		(fp_line
			(start 0.254 -0.508)
			(end 0.254 0.508)
			(stroke
				(width 0.0254)
				(type default)
			)
			(layer "F.Fab")
		)
		(fp_line
			(start -0.254 0.508)
			(end -0.254 -0.508)
			(stroke
				(width 0.0254)
				(type default)
			)
			(layer "F.Fab")
		)
		(fp_line
			(start -0.254 -0.508)
			(end 0.254 -0.508)
			(stroke
				(width 0.0254)
				(type default)
			)
			(layer "F.Fab")
		)
		(pad "1" smd rect
			(at 0 -0.4191 180)
			(size 0.508 0.5334)
			(layers "F.Cu" "F.Mask" "F.Paste")
			(net "_NFP_CORE_VID5")
		)
		(pad "2" smd rect
			(at 0 0.4191 180)
			(size 0.508 0.5334)
			(layers "F.Cu" "F.Mask" "F.Paste")
			(net "VDD_1.2V")
		)
		(zone
			(layer "F.Cu")
			(hatch none 0.5)
			(connect_pads
				(clearance 0)
			)
			(min_thickness 0.25)
			(keepout
				(tracks not_allowed)
				(vias allowed)
				(pads allowed)
				(copperpour not_allowed)
				(footprints allowed)
			)
			(placement
				(enabled no)
				(sheetname "")
			)
			(fill
				(thermal_gap 0.5)
				(thermal_bridge_width 0.5)
				(island_removal_mode 0)
			)
			(polygon
				(pts
					(xy 33.6296 32.6644) (xy 33.6296 32.6136) (xy 33.6804 32.6136) (xy 33.6804 32.6644)
				)
			)
		)
	)
	(footprint ""
		(layer "F.Cu")
		(at 22.479 47.498)
		(property "Reference" "TP18"
			(at 1.67767 1.397 90)
			(unlocked yes)
			(layer "F.SilkS")
			(effects
				(font
					(size 0.7874 0.5842)
					(thickness 0.127)
				)
				(justify left)
			)
		)
		(property "Value" "*"
			(at -0.4826 -0.14732 0)
			(unlocked yes)
			(layer "F.Fab")
			(hide yes)
			(effects
				(font
					(size 1.27 0.9652)
					(thickness 0.000001)
				)
				(justify left)
			)
		)
		(property "Device Type" "TP_SMALL"
			(at -0.4826 -0.14732 0)
			(unlocked yes)
			(layer "F.Fab")
			(hide yes)
			(effects
				(font
					(size 1.27 0.9652)
					(thickness 0.000001)
				)
				(justify left)
			)
		)
		(duplicate_pad_numbers_are_jumpers no)
		(fp_line
			(start -0.8636 -0.8636)
			(end -0.8636 0.8636)
			(stroke
				(width 0.1524)
				(type default)
			)
			(layer "F.SilkS")
		)
		(fp_line
			(start -0.8636 0.8636)
			(end 0.8636 0.8636)
			(stroke
				(width 0.1524)
				(type default)
			)
			(layer "F.SilkS")
		)
		(fp_line
			(start 0.8636 -0.8636)
			(end -0.8636 -0.8636)
			(stroke
				(width 0.1524)
				(type default)
			)
			(layer "F.SilkS")
		)
		(fp_line
			(start 0.8636 0.8636)
			(end 0.8636 -0.8636)
			(stroke
				(width 0.1524)
				(type default)
			)
			(layer "F.SilkS")
		)
		(fp_poly
			(pts
				(xy -0.635 -0.635) (xy -0.635 0.635) (xy 0.635 0.635) (xy 0.635 -0.635)
			)
			(stroke
				(width 0)
				(type default)
			)
			(fill no)
			(layer "F.CrtYd")
		)
		(pad "1" smd rect
			(at 0 0)
			(size 1.27 1.27)
			(layers "F.Cu" "F.Mask" "F.Paste")
			(net "HOST_RESET_REQ_L")
		)
	)
	(footprint ""
		(layer "F.Cu")
		(at 33.274 48.641)
		(property "Reference" "TP61"
			(at 1.143 0.53467 0)
			(unlocked yes)
			(layer "F.SilkS")
			(effects
				(font
					(size 0.7874 0.5842)
					(thickness 0.127)
				)
				(justify left)
			)
		)
		(property "Value" "*"
			(at -0.4826 -0.14732 0)
			(unlocked yes)
			(layer "F.Fab")
			(hide yes)
			(effects
				(font
					(size 1.27 0.9652)
					(thickness 0.000001)
				)
				(justify left)
			)
		)
		(property "Device Type" "TP_SMALL"
			(at -0.4826 -0.14732 0)
			(unlocked yes)
			(layer "F.Fab")
			(hide yes)
			(effects
				(font
					(size 1.27 0.9652)
					(thickness 0.000001)
				)
				(justify left)
			)
		)
		(duplicate_pad_numbers_are_jumpers no)
		(fp_line
			(start -0.8636 -0.8636)
			(end -0.8636 0.8636)
			(stroke
				(width 0.1524)
				(type default)
			)
			(layer "F.SilkS")
		)
		(fp_line
			(start -0.8636 0.8636)
			(end 0.8636 0.8636)
			(stroke
				(width 0.1524)
				(type default)
			)
			(layer "F.SilkS")
		)
		(fp_line
			(start 0.8636 -0.8636)
			(end -0.8636 -0.8636)
			(stroke
				(width 0.1524)
				(type default)
			)
			(layer "F.SilkS")
		)
		(fp_line
			(start 0.8636 0.8636)
			(end 0.8636 -0.8636)
			(stroke
				(width 0.1524)
				(type default)
			)
			(layer "F.SilkS")
		)
		(fp_poly
			(pts
				(xy -0.635 -0.635) (xy -0.635 0.635) (xy 0.635 0.635) (xy 0.635 -0.635)
			)
			(stroke
				(width 0)
				(type default)
			)
			(fill no)
			(layer "F.CrtYd")
		)
		(pad "1" smd rect
			(at 0 0)
			(size 1.27 1.27)
			(layers "F.Cu" "F.Mask" "F.Paste")
			(net "VDD_5.0V_PGOOD")
		)
	)
	(footprint ""
		(layer "F.Cu")
		(at 84.6328 22.987 180)
		(property "Reference" "R213"
			(at 0.0508 -1.29667 0)
			(unlocked yes)
			(layer "F.SilkS")
			(effects
				(font
					(size 0.7874 0.5842)
					(thickness 0.127)
				)
				(justify left)
			)
		)
		(property "Value" "39.0"
			(at -0.148158 1.3462 270)
			(unlocked yes)
			(layer "F.Fab")
			(hide yes)
			(effects
				(font
					(size 1.27 0.9652)
					(thickness 0.000001)
				)
				(justify left)
			)
		)
		(property "Device Type" "REST0108"
			(at -0.148158 1.3462 270)
			(unlocked yes)
			(layer "F.Fab")
			(hide yes)
			(effects
				(font
					(size 1.27 0.9652)
					(thickness 0.000001)
				)
				(justify left)
			)
		)
		(duplicate_pad_numbers_are_jumpers no)
		(fp_poly
			(pts
				(xy 0.635 1.0668) (xy 0.635 -1.0668) (xy -0.635 -1.0668) (xy -0.635 1.0668)
			)
			(stroke
				(width 0)
				(type default)
			)
			(fill no)
			(layer "F.CrtYd")
		)
		(fp_line
			(start 0.254 0.508)
			(end -0.254 0.508)
			(stroke
				(width 0.0254)
				(type default)
			)
			(layer "F.Fab")
		)
		(fp_line
			(start 0.254 -0.508)
			(end 0.254 0.508)
			(stroke
				(width 0.0254)
				(type default)
			)
			(layer "F.Fab")
		)
		(fp_line
			(start -0.254 0.508)
			(end -0.254 -0.508)
			(stroke
				(width 0.0254)
				(type default)
			)
			(layer "F.Fab")
		)
		(fp_line
			(start -0.254 -0.508)
			(end 0.254 -0.508)
			(stroke
				(width 0.0254)
				(type default)
			)
			(layer "F.Fab")
		)
		(pad "1" smd rect
			(at 0 -0.4191 180)
			(size 0.508 0.5334)
			(layers "F.Cu" "F.Mask" "F.Paste")
			(net "DDR0_32A_A7")
		)
		(pad "2" smd rect
			(at 0 0.4191 180)
			(size 0.508 0.5334)
			(layers "F.Cu" "F.Mask" "F.Paste")
			(net "DDR_VTT")
		)
		(zone
			(layer "F.Cu")
			(hatch none 0.5)
			(connect_pads
				(clearance 0)
			)
			(min_thickness 0.25)
			(keepout
				(tracks not_allowed)
				(vias allowed)
				(pads allowed)
				(copperpour not_allowed)
				(footprints allowed)
			)
			(placement
				(enabled no)
				(sheetname "")
			)
			(fill
				(thermal_gap 0.5)
				(thermal_bridge_width 0.5)
				(island_removal_mode 0)
			)
			(polygon
				(pts
					(xy 84.6074 23.0124) (xy 84.6074 22.9616) (xy 84.6582 22.9616) (xy 84.6582 23.0124)
				)
			)
		)
	)
	(footprint ""
		(layer "F.Cu")
		(at 7.493 47.752 -90)
		(property "Reference" "TP45"
			(at 1.55067 -0.508 0)
			(unlocked yes)
			(layer "F.SilkS")
			(effects
				(font
					(size 0.7874 0.5842)
					(thickness 0.127)
				)
				(justify left)
			)
		)
		(property "Value" "*"
			(at -0.4826 -0.14732 270)
			(unlocked yes)
			(layer "F.Fab")
			(hide yes)
			(effects
				(font
					(size 1.27 0.9652)
					(thickness 0.000001)
				)
				(justify left)
			)
		)
		(property "Device Type" "TP_SMALL"
			(at -0.4826 -0.14732 270)
			(unlocked yes)
			(layer "F.Fab")
			(hide yes)
			(effects
				(font
					(size 1.27 0.9652)
					(thickness 0.000001)
				)
				(justify left)
			)
		)
		(duplicate_pad_numbers_are_jumpers no)
		(fp_line
			(start -0.8636 0.8636)
			(end 0.8636 0.8636)
			(stroke
				(width 0.1524)
				(type default)
			)
			(layer "F.SilkS")
		)
		(fp_line
			(start 0.8636 0.8636)
			(end 0.8636 -0.8636)
			(stroke
				(width 0.1524)
				(type default)
			)
			(layer "F.SilkS")
		)
		(fp_line
			(start -0.8636 -0.8636)
			(end -0.8636 0.8636)
			(stroke
				(width 0.1524)
				(type default)
			)
			(layer "F.SilkS")
		)
		(fp_line
			(start 0.8636 -0.8636)
			(end -0.8636 -0.8636)
			(stroke
				(width 0.1524)
				(type default)
			)
			(layer "F.SilkS")
		)
		(fp_poly
			(pts
				(xy -0.635 -0.635) (xy -0.635 0.635) (xy 0.635 0.635) (xy 0.635 -0.635)
			)
			(stroke
				(width 0)
				(type default)
			)
			(fill no)
			(layer "F.CrtYd")
		)
		(pad "1" smd rect
			(at 0 0 270)
			(size 1.27 1.27)
			(layers "F.Cu" "F.Mask" "F.Paste")
			(net "GND")
		)
	)
	(footprint ""
		(layer "F.Cu")
		(at 45.085 51.816 180)
		(property "Reference" "R316"
			(at 0 0 180)
			(layer "F.SilkS")
			(hide yes)
			(effects
				(font
					(size 1.27 1.27)
				)
			)
		)
		(property "Value" "1.0K"
			(at -0.148158 1.3462 270)
			(unlocked yes)
			(layer "F.Fab")
			(hide yes)
			(effects
				(font
					(size 1.27 0.9652)
					(thickness 0.000001)
				)
				(justify left)
			)
		)
		(property "Device Type" "REST0025"
			(at -0.148158 1.3462 270)
			(unlocked yes)
			(layer "F.Fab")
			(hide yes)
			(effects
				(font
					(size 1.27 0.9652)
					(thickness 0.000001)
				)
				(justify left)
			)
		)
		(duplicate_pad_numbers_are_jumpers no)
		(fp_poly
			(pts
				(xy 0.635 1.0668) (xy 0.635 -1.0668) (xy -0.635 -1.0668) (xy -0.635 1.0668)
			)
			(stroke
				(width 0)
				(type default)
			)
			(fill no)
			(layer "F.CrtYd")
		)
		(fp_line
			(start 0.254 0.508)
			(end -0.254 0.508)
			(stroke
				(width 0.0254)
				(type default)
			)
			(layer "F.Fab")
		)
		(fp_line
			(start 0.254 -0.508)
			(end 0.254 0.508)
			(stroke
				(width 0.0254)
				(type default)
			)
			(layer "F.Fab")
		)
		(fp_line
			(start -0.254 0.508)
			(end -0.254 -0.508)
			(stroke
				(width 0.0254)
				(type default)
			)
			(layer "F.Fab")
		)
		(fp_line
			(start -0.254 -0.508)
			(end 0.254 -0.508)
			(stroke
				(width 0.0254)
				(type default)
			)
			(layer "F.Fab")
		)
		(pad "1" smd rect
			(at 0 -0.4191 180)
			(size 0.508 0.5334)
			(layers "F.Cu" "F.Mask" "F.Paste")
			(net "GND")
		)
		(pad "2" smd rect
			(at 0 0.4191 180)
			(size 0.508 0.5334)
			(layers "F.Cu" "F.Mask" "F.Paste")
			(net "EXT_3.3V_THRESHOLD")
		)
		(zone
			(layer "F.Cu")
			(hatch none 0.5)
			(connect_pads
				(clearance 0)
			)
			(min_thickness 0.25)
			(keepout
				(tracks not_allowed)
				(vias allowed)
				(pads allowed)
				(copperpour not_allowed)
				(footprints allowed)
			)
			(placement
				(enabled no)
				(sheetname "")
			)
			(fill
				(thermal_gap 0.5)
				(thermal_bridge_width 0.5)
				(island_removal_mode 0)
			)
			(polygon
				(pts
					(xy 45.0596 51.8414) (xy 45.0596 51.7906) (xy 45.1104 51.7906) (xy 45.1104 51.8414)
				)
			)
		)
	)
	(footprint ""
		(layer "F.Cu")
		(at 80.772 46.4312 180)
		(property "Reference" "R109"
			(at 0.73533 -0.8128 90)
			(unlocked yes)
			(layer "F.SilkS")
			(effects
				(font
					(size 0.7874 0.5842)
					(thickness 0.127)
				)
				(justify left)
			)
		)
		(property "Value" "2.2"
			(at -0.148158 1.3462 270)
			(unlocked yes)
			(layer "F.Fab")
			(hide yes)
			(effects
				(font
					(size 1.27 0.9652)
					(thickness 0.000001)
				)
				(justify left)
			)
		)
		(property "Device Type" "REST0114"
			(at -0.148158 1.3462 270)
			(unlocked yes)
			(layer "F.Fab")
			(hide yes)
			(effects
				(font
					(size 1.27 0.9652)
					(thickness 0.000001)
				)
				(justify left)
			)
		)
		(duplicate_pad_numbers_are_jumpers no)
		(fp_poly
			(pts
				(xy 0.635 1.0668) (xy 0.635 -1.0668) (xy -0.635 -1.0668) (xy -0.635 1.0668)
			)
			(stroke
				(width 0)
				(type default)
			)
			(fill no)
			(layer "F.CrtYd")
		)
		(fp_line
			(start 0.254 0.508)
			(end -0.254 0.508)
			(stroke
				(width 0.0254)
				(type default)
			)
			(layer "F.Fab")
		)
		(fp_line
			(start 0.254 -0.508)
			(end 0.254 0.508)
			(stroke
				(width 0.0254)
				(type default)
			)
			(layer "F.Fab")
		)
		(fp_line
			(start -0.254 0.508)
			(end -0.254 -0.508)
			(stroke
				(width 0.0254)
				(type default)
			)
			(layer "F.Fab")
		)
		(fp_line
			(start -0.254 -0.508)
			(end 0.254 -0.508)
			(stroke
				(width 0.0254)
				(type default)
			)
			(layer "F.Fab")
		)
		(pad "1" smd rect
			(at 0 -0.4191 180)
			(size 0.508 0.5334)
			(layers "F.Cu" "F.Mask" "F.Paste")
			(net "11N2258")
		)
		(pad "2" smd rect
			(at 0 0.4191 180)
			(size 0.508 0.5334)
			(layers "F.Cu" "F.Mask" "F.Paste")
			(net "11N2253")
		)
		(zone
			(layer "F.Cu")
			(hatch none 0.5)
			(connect_pads
				(clearance 0)
			)
			(min_thickness 0.25)
			(keepout
				(tracks not_allowed)
				(vias allowed)
				(pads allowed)
				(copperpour not_allowed)
				(footprints allowed)
			)
			(placement
				(enabled no)
				(sheetname "")
			)
			(fill
				(thermal_gap 0.5)
				(thermal_bridge_width 0.5)
				(island_removal_mode 0)
			)
			(polygon
				(pts
					(xy 80.7466 46.4566) (xy 80.7466 46.4058) (xy 80.7974 46.4058) (xy 80.7974 46.4566)
				)
			)
		)
	)
	(footprint ""
		(layer "F.Cu")
		(at 83.7438 22.987 180)
		(property "Reference" "R211"
			(at 0 0 180)
			(layer "F.SilkS")
			(hide yes)
			(effects
				(font
					(size 1.27 1.27)
				)
			)
		)
		(property "Value" "39.0"
			(at -0.148158 1.3462 270)
			(unlocked yes)
			(layer "F.Fab")
			(hide yes)
			(effects
				(font
					(size 1.27 0.9652)
					(thickness 0.000001)
				)
				(justify left)
			)
		)
		(property "Device Type" "REST0108"
			(at -0.148158 1.3462 270)
			(unlocked yes)
			(layer "F.Fab")
			(hide yes)
			(effects
				(font
					(size 1.27 0.9652)
					(thickness 0.000001)
				)
				(justify left)
			)
		)
		(duplicate_pad_numbers_are_jumpers no)
		(fp_poly
			(pts
				(xy 0.635 1.0668) (xy 0.635 -1.0668) (xy -0.635 -1.0668) (xy -0.635 1.0668)
			)
			(stroke
				(width 0)
				(type default)
			)
			(fill no)
			(layer "F.CrtYd")
		)
		(fp_line
			(start 0.254 0.508)
			(end -0.254 0.508)
			(stroke
				(width 0.0254)
				(type default)
			)
			(layer "F.Fab")
		)
		(fp_line
			(start 0.254 -0.508)
			(end 0.254 0.508)
			(stroke
				(width 0.0254)
				(type default)
			)
			(layer "F.Fab")
		)
		(fp_line
			(start -0.254 0.508)
			(end -0.254 -0.508)
			(stroke
				(width 0.0254)
				(type default)
			)
			(layer "F.Fab")
		)
		(fp_line
			(start -0.254 -0.508)
			(end 0.254 -0.508)
			(stroke
				(width 0.0254)
				(type default)
			)
			(layer "F.Fab")
		)
		(pad "1" smd rect
			(at 0 -0.4191 180)
			(size 0.508 0.5334)
			(layers "F.Cu" "F.Mask" "F.Paste")
			(net "DDR0_32A_A5")
		)
		(pad "2" smd rect
			(at 0 0.4191 180)
			(size 0.508 0.5334)
			(layers "F.Cu" "F.Mask" "F.Paste")
			(net "DDR_VTT")
		)
		(zone
			(layer "F.Cu")
			(hatch none 0.5)
			(connect_pads
				(clearance 0)
			)
			(min_thickness 0.25)
			(keepout
				(tracks not_allowed)
				(vias allowed)
				(pads allowed)
				(copperpour not_allowed)
				(footprints allowed)
			)
			(placement
				(enabled no)
				(sheetname "")
			)
			(fill
				(thermal_gap 0.5)
				(thermal_bridge_width 0.5)
				(island_removal_mode 0)
			)
			(polygon
				(pts
					(xy 83.7184 23.0124) (xy 83.7184 22.9616) (xy 83.7692 22.9616) (xy 83.7692 23.0124)
				)
			)
		)
	)
	(footprint ""
		(layer "F.Cu")
		(at 20.955 47.498)
		(property "Reference" "TP44"
			(at 0.635 2.18567 0)
			(unlocked yes)
			(layer "F.SilkS")
			(effects
				(font
					(size 0.7874 0.5842)
					(thickness 0.127)
				)
				(justify left)
			)
		)
		(property "Value" "*"
			(at -0.4826 -0.14732 0)
			(unlocked yes)
			(layer "F.Fab")
			(hide yes)
			(effects
				(font
					(size 1.27 0.9652)
					(thickness 0.000001)
				)
				(justify left)
			)
		)
		(property "Device Type" "TP_SMALL"
			(at -0.4826 -0.14732 0)
			(unlocked yes)
			(layer "F.Fab")
			(hide yes)
			(effects
				(font
					(size 1.27 0.9652)
					(thickness 0.000001)
				)
				(justify left)
			)
		)
		(duplicate_pad_numbers_are_jumpers no)
		(fp_line
			(start -0.8636 -0.8636)
			(end -0.8636 0.8636)
			(stroke
				(width 0.1524)
				(type default)
			)
			(layer "F.SilkS")
		)
		(fp_line
			(start -0.8636 0.8636)
			(end 0.8636 0.8636)
			(stroke
				(width 0.1524)
				(type default)
			)
			(layer "F.SilkS")
		)
		(fp_line
			(start 0.8636 -0.8636)
			(end -0.8636 -0.8636)
			(stroke
				(width 0.1524)
				(type default)
			)
			(layer "F.SilkS")
		)
		(fp_line
			(start 0.8636 0.8636)
			(end 0.8636 -0.8636)
			(stroke
				(width 0.1524)
				(type default)
			)
			(layer "F.SilkS")
		)
		(fp_poly
			(pts
				(xy -0.635 -0.635) (xy -0.635 0.635) (xy 0.635 0.635) (xy 0.635 -0.635)
			)
			(stroke
				(width 0)
				(type default)
			)
			(fill no)
			(layer "F.CrtYd")
		)
		(pad "1" smd rect
			(at 0 0)
			(size 1.27 1.27)
			(layers "F.Cu" "F.Mask" "F.Paste")
			(net "DDR_1.8V")
		)
	)
	(footprint ""
		(layer "F.Cu")
		(at 24.384 29.337 180)
		(property "Reference" "R65"
			(at 0 0 180)
			(layer "F.SilkS")
			(hide yes)
			(effects
				(font
					(size 1.27 1.27)
				)
			)
		)
		(property "Value" "4.75K"
			(at -0.148158 1.3462 270)
			(unlocked yes)
			(layer "F.Fab")
			(hide yes)
			(effects
				(font
					(size 1.27 0.9652)
					(thickness 0.000001)
				)
				(justify left)
			)
		)
		(property "Device Type" "REST4024"
			(at -0.148158 1.3462 270)
			(unlocked yes)
			(layer "F.Fab")
			(hide yes)
			(effects
				(font
					(size 1.27 0.9652)
					(thickness 0.000001)
				)
				(justify left)
			)
		)
		(duplicate_pad_numbers_are_jumpers no)
		(fp_poly
			(pts
				(xy 0.635 1.0668) (xy 0.635 -1.0668) (xy -0.635 -1.0668) (xy -0.635 1.0668)
			)
			(stroke
				(width 0)
				(type default)
			)
			(fill no)
			(layer "F.CrtYd")
		)
		(fp_line
			(start 0.254 0.508)
			(end -0.254 0.508)
			(stroke
				(width 0.0254)
				(type default)
			)
			(layer "F.Fab")
		)
		(fp_line
			(start 0.254 -0.508)
			(end 0.254 0.508)
			(stroke
				(width 0.0254)
				(type default)
			)
			(layer "F.Fab")
		)
		(fp_line
			(start -0.254 0.508)
			(end -0.254 -0.508)
			(stroke
				(width 0.0254)
				(type default)
			)
			(layer "F.Fab")
		)
		(fp_line
			(start -0.254 -0.508)
			(end 0.254 -0.508)
			(stroke
				(width 0.0254)
				(type default)
			)
			(layer "F.Fab")
		)
		(pad "1" smd rect
			(at 0 -0.4191 180)
			(size 0.508 0.5334)
			(layers "F.Cu" "F.Mask" "F.Paste")
			(net "DEBUG_CPLD_PGRM_JTAG_TCK")
		)
		(pad "2" smd rect
			(at 0 0.4191 180)
			(size 0.508 0.5334)
			(layers "F.Cu" "F.Mask" "F.Paste")
			(net "GND")
		)
		(zone
			(layer "F.Cu")
			(hatch none 0.5)
			(connect_pads
				(clearance 0)
			)
			(min_thickness 0.25)
			(keepout
				(tracks not_allowed)
				(vias allowed)
				(pads allowed)
				(copperpour not_allowed)
				(footprints allowed)
			)
			(placement
				(enabled no)
				(sheetname "")
			)
			(fill
				(thermal_gap 0.5)
				(thermal_bridge_width 0.5)
				(island_removal_mode 0)
			)
			(polygon
				(pts
					(xy 24.3586 29.3624) (xy 24.3586 29.3116) (xy 24.4094 29.3116) (xy 24.4094 29.3624)
				)
			)
		)
	)
	(footprint ""
		(layer "F.Cu")
		(at 4.064 36.83)
		(property "Reference" "TP16"
			(at -1.397 -1.37033 0)
			(unlocked yes)
			(layer "F.SilkS")
			(effects
				(font
					(size 0.7874 0.5842)
					(thickness 0.127)
				)
				(justify left)
			)
		)
		(property "Value" "*"
			(at -0.4826 -0.14732 0)
			(unlocked yes)
			(layer "F.Fab")
			(hide yes)
			(effects
				(font
					(size 1.27 0.9652)
					(thickness 0.000001)
				)
				(justify left)
			)
		)
		(property "Device Type" "TP_SMALL"
			(at -0.4826 -0.14732 0)
			(unlocked yes)
			(layer "F.Fab")
			(hide yes)
			(effects
				(font
					(size 1.27 0.9652)
					(thickness 0.000001)
				)
				(justify left)
			)
		)
		(duplicate_pad_numbers_are_jumpers no)
		(fp_line
			(start -0.8636 -0.8636)
			(end -0.8636 0.8636)
			(stroke
				(width 0.1524)
				(type default)
			)
			(layer "F.SilkS")
		)
		(fp_line
			(start -0.8636 0.8636)
			(end 0.8636 0.8636)
			(stroke
				(width 0.1524)
				(type default)
			)
			(layer "F.SilkS")
		)
		(fp_line
			(start 0.8636 -0.8636)
			(end -0.8636 -0.8636)
			(stroke
				(width 0.1524)
				(type default)
			)
			(layer "F.SilkS")
		)
		(fp_line
			(start 0.8636 0.8636)
			(end 0.8636 -0.8636)
			(stroke
				(width 0.1524)
				(type default)
			)
			(layer "F.SilkS")
		)
		(fp_poly
			(pts
				(xy -0.635 -0.635) (xy -0.635 0.635) (xy 0.635 0.635) (xy 0.635 -0.635)
			)
			(stroke
				(width 0)
				(type default)
			)
			(fill no)
			(layer "F.CrtYd")
		)
		(pad "1" smd rect
			(at 0 0)
			(size 1.27 1.27)
			(layers "F.Cu" "F.Mask" "F.Paste")
			(net "PSU_I2C_SDA")
		)
	)
	(footprint ""
		(layer "F.Cu")
		(at 79.248 32.576414)
		(property "Reference" "R231"
			(at -0.35433 3.618586 90)
			(unlocked yes)
			(layer "F.SilkS")
			(effects
				(font
					(size 0.7874 0.5842)
					(thickness 0.127)
				)
				(justify left)
			)
		)
		(property "Value" "39.0"
			(at -0.148158 1.3462 90)
			(unlocked yes)
			(layer "F.Fab")
			(hide yes)
			(effects
				(font
					(size 1.27 0.9652)
					(thickness 0.000001)
				)
				(justify left)
			)
		)
		(property "Device Type" "REST0108"
			(at -0.148158 1.3462 90)
			(unlocked yes)
			(layer "F.Fab")
			(hide yes)
			(effects
				(font
					(size 1.27 0.9652)
					(thickness 0.000001)
				)
				(justify left)
			)
		)
		(duplicate_pad_numbers_are_jumpers no)
		(fp_poly
			(pts
				(xy 0.635 1.0668) (xy 0.635 -1.0668) (xy -0.635 -1.0668) (xy -0.635 1.0668)
			)
			(stroke
				(width 0)
				(type default)
			)
			(fill no)
			(layer "F.CrtYd")
		)
		(fp_line
			(start -0.254 -0.508)
			(end 0.254 -0.508)
			(stroke
				(width 0.0254)
				(type default)
			)
			(layer "F.Fab")
		)
		(fp_line
			(start -0.254 0.508)
			(end -0.254 -0.508)
			(stroke
				(width 0.0254)
				(type default)
			)
			(layer "F.Fab")
		)
		(fp_line
			(start 0.254 -0.508)
			(end 0.254 0.508)
			(stroke
				(width 0.0254)
				(type default)
			)
			(layer "F.Fab")
		)
		(fp_line
			(start 0.254 0.508)
			(end -0.254 0.508)
			(stroke
				(width 0.0254)
				(type default)
			)
			(layer "F.Fab")
		)
		(pad "1" smd rect
			(at 0 -0.4191)
			(size 0.508 0.5334)
			(layers "F.Cu" "F.Mask" "F.Paste")
			(net "DDR0_32A_CKE0")
		)
		(pad "2" smd rect
			(at 0 0.4191)
			(size 0.508 0.5334)
			(layers "F.Cu" "F.Mask" "F.Paste")
			(net "DDR_VTT")
		)
		(zone
			(layer "F.Cu")
			(hatch none 0.5)
			(connect_pads
				(clearance 0)
			)
			(min_thickness 0.25)
			(keepout
				(tracks not_allowed)
				(vias allowed)
				(pads allowed)
				(copperpour not_allowed)
				(footprints allowed)
			)
			(placement
				(enabled no)
				(sheetname "")
			)
			(fill
				(thermal_gap 0.5)
				(thermal_bridge_width 0.5)
				(island_removal_mode 0)
			)
			(polygon
				(pts
					(xy 79.2734 32.551014) (xy 79.2734 32.601814) (xy 79.2226 32.601814) (xy 79.2226 32.551014)
				)
			)
		)
	)
	(footprint ""
		(layer "F.Cu")
		(at 31.75 42.545 -90)
		(property "Reference" "C50"
			(at 0 0 270)
			(layer "F.SilkS")
			(hide yes)
			(effects
				(font
					(size 1.27 1.27)
				)
			)
		)
		(property "Value" "1000PF"
			(at -0.091846 0.2921 0)
			(unlocked yes)
			(layer "F.Fab")
			(hide yes)
			(effects
				(font
					(size 0.7874 0.5842)
					(thickness 0.2032)
				)
				(justify left)
			)
		)
		(property "Device Type" "CAPC0083"
			(at -0.091846 0.2921 0)
			(unlocked yes)
			(layer "F.Fab")
			(hide yes)
			(effects
				(font
					(size 0.7874 0.5842)
					(thickness 0.2032)
				)
				(justify left)
			)
		)
		(duplicate_pad_numbers_are_jumpers no)
		(fp_poly
			(pts
				(xy 0.635 1.0668) (xy 0.635 -1.0668) (xy -0.635 -1.0668) (xy -0.635 1.0668)
			)
			(stroke
				(width 0)
				(type default)
			)
			(fill no)
			(layer "F.CrtYd")
		)
		(fp_line
			(start -0.254 0.508)
			(end -0.254 -0.508)
			(stroke
				(width 0.0254)
				(type default)
			)
			(layer "F.Fab")
		)
		(fp_line
			(start 0.254 0.508)
			(end -0.254 0.508)
			(stroke
				(width 0.0254)
				(type default)
			)
			(layer "F.Fab")
		)
		(fp_line
			(start -0.254 -0.508)
			(end 0.254 -0.508)
			(stroke
				(width 0.0254)
				(type default)
			)
			(layer "F.Fab")
		)
		(fp_line
			(start 0.254 -0.508)
			(end 0.254 0.508)
			(stroke
				(width 0.0254)
				(type default)
			)
			(layer "F.Fab")
		)
		(pad "1" smd rect
			(at 0 -0.4191 270)
			(size 0.508 0.5334)
			(layers "F.Cu" "F.Mask" "F.Paste")
			(net "10N2535")
		)
		(pad "2" smd rect
			(at 0 0.4191 270)
			(size 0.508 0.5334)
			(layers "F.Cu" "F.Mask" "F.Paste")
			(net "GND")
		)
		(zone
			(layer "F.Cu")
			(hatch none 0.5)
			(connect_pads
				(clearance 0)
			)
			(min_thickness 0.25)
			(keepout
				(tracks not_allowed)
				(vias allowed)
				(pads allowed)
				(copperpour not_allowed)
				(footprints allowed)
			)
			(placement
				(enabled no)
				(sheetname "")
			)
			(fill
				(thermal_gap 0.5)
				(thermal_bridge_width 0.5)
				(island_removal_mode 0)
			)
			(polygon
				(pts
					(xy 31.7754 42.5704) (xy 31.7246 42.5704) (xy 31.7246 42.5196) (xy 31.7754 42.5196)
				)
			)
		)
	)
	(footprint ""
		(layer "F.Cu")
		(at 5.715 36.957)
		(property "Reference" "TP22"
			(at -0.254 -1.37033 0)
			(unlocked yes)
			(layer "F.SilkS")
			(effects
				(font
					(size 0.7874 0.5842)
					(thickness 0.127)
				)
				(justify left)
			)
		)
		(property "Value" "*"
			(at -0.4826 -0.14732 0)
			(unlocked yes)
			(layer "F.Fab")
			(hide yes)
			(effects
				(font
					(size 1.27 0.9652)
					(thickness 0.000001)
				)
				(justify left)
			)
		)
		(property "Device Type" "TP_SMALL"
			(at -0.4826 -0.14732 0)
			(unlocked yes)
			(layer "F.Fab")
			(hide yes)
			(effects
				(font
					(size 1.27 0.9652)
					(thickness 0.000001)
				)
				(justify left)
			)
		)
		(duplicate_pad_numbers_are_jumpers no)
		(fp_line
			(start -0.8636 -0.8636)
			(end -0.8636 0.8636)
			(stroke
				(width 0.1524)
				(type default)
			)
			(layer "F.SilkS")
		)
		(fp_line
			(start -0.8636 0.8636)
			(end 0.8636 0.8636)
			(stroke
				(width 0.1524)
				(type default)
			)
			(layer "F.SilkS")
		)
		(fp_line
			(start 0.8636 -0.8636)
			(end -0.8636 -0.8636)
			(stroke
				(width 0.1524)
				(type default)
			)
			(layer "F.SilkS")
		)
		(fp_line
			(start 0.8636 0.8636)
			(end 0.8636 -0.8636)
			(stroke
				(width 0.1524)
				(type default)
			)
			(layer "F.SilkS")
		)
		(fp_poly
			(pts
				(xy -0.635 -0.635) (xy -0.635 0.635) (xy 0.635 0.635) (xy 0.635 -0.635)
			)
			(stroke
				(width 0)
				(type default)
			)
			(fill no)
			(layer "F.CrtYd")
		)
		(pad "1" smd rect
			(at 0 0)
			(size 1.27 1.27)
			(layers "F.Cu" "F.Mask" "F.Paste")
			(net "CPLD_GPIO_0")
		)
	)
	(footprint ""
		(layer "F.Cu")
		(at 64.77 46.609 180)
		(property "Reference" "R99"
			(at 0 0 180)
			(layer "F.SilkS")
			(hide yes)
			(effects
				(font
					(size 1.27 1.27)
				)
			)
		)
		(property "Value" "4.75K"
			(at -0.148158 1.3462 270)
			(unlocked yes)
			(layer "F.Fab")
			(hide yes)
			(effects
				(font
					(size 1.27 0.9652)
					(thickness 0.000001)
				)
				(justify left)
			)
		)
		(property "Device Type" "REST4024"
			(at -0.148158 1.3462 270)
			(unlocked yes)
			(layer "F.Fab")
			(hide yes)
			(effects
				(font
					(size 1.27 0.9652)
					(thickness 0.000001)
				)
				(justify left)
			)
		)
		(duplicate_pad_numbers_are_jumpers no)
		(fp_poly
			(pts
				(xy 0.635 1.0668) (xy 0.635 -1.0668) (xy -0.635 -1.0668) (xy -0.635 1.0668)
			)
			(stroke
				(width 0)
				(type default)
			)
			(fill no)
			(layer "F.CrtYd")
		)
		(fp_line
			(start 0.254 0.508)
			(end -0.254 0.508)
			(stroke
				(width 0.0254)
				(type default)
			)
			(layer "F.Fab")
		)
		(fp_line
			(start 0.254 -0.508)
			(end 0.254 0.508)
			(stroke
				(width 0.0254)
				(type default)
			)
			(layer "F.Fab")
		)
		(fp_line
			(start -0.254 0.508)
			(end -0.254 -0.508)
			(stroke
				(width 0.0254)
				(type default)
			)
			(layer "F.Fab")
		)
		(fp_line
			(start -0.254 -0.508)
			(end 0.254 -0.508)
			(stroke
				(width 0.0254)
				(type default)
			)
			(layer "F.Fab")
		)
		(pad "1" smd rect
			(at 0 -0.4191 180)
			(size 0.508 0.5334)
			(layers "F.Cu" "F.Mask" "F.Paste")
			(net "VDD_5.0V_PGOOD")
		)
		(pad "2" smd rect
			(at 0 0.4191 180)
			(size 0.508 0.5334)
			(layers "F.Cu" "F.Mask" "F.Paste")
			(net "EXT_3.3V")
		)
		(zone
			(layer "F.Cu")
			(hatch none 0.5)
			(connect_pads
				(clearance 0)
			)
			(min_thickness 0.25)
			(keepout
				(tracks not_allowed)
				(vias allowed)
				(pads allowed)
				(copperpour not_allowed)
				(footprints allowed)
			)
			(placement
				(enabled no)
				(sheetname "")
			)
			(fill
				(thermal_gap 0.5)
				(thermal_bridge_width 0.5)
				(island_removal_mode 0)
			)
			(polygon
				(pts
					(xy 64.7446 46.6344) (xy 64.7446 46.5836) (xy 64.7954 46.5836) (xy 64.7954 46.6344)
				)
			)
		)
	)
	(footprint ""
		(layer "F.Cu")
		(at 39.624 43.307)
		(property "Reference" "C61"
			(at 1.29667 -1.27 90)
			(unlocked yes)
			(layer "F.SilkS")
			(effects
				(font
					(size 0.7874 0.5842)
					(thickness 0.127)
				)
				(justify left)
			)
		)
		(property "Value" "100UF"
			(at -0.78232 0.4826 90)
			(unlocked yes)
			(layer "F.Fab")
			(hide yes)
			(effects
				(font
					(size 1.27 0.9652)
					(thickness 0.000001)
				)
				(justify left)
			)
		)
		(property "Device Type" "CAPC0087"
			(at -0.78232 0.4826 90)
			(unlocked yes)
			(layer "F.Fab")
			(hide yes)
			(effects
				(font
					(size 1.27 0.9652)
					(thickness 0.000001)
				)
				(justify left)
			)
		)
		(duplicate_pad_numbers_are_jumpers no)
		(fp_circle
			(center 0 0)
			(end 0.508 0)
			(stroke
				(width 0.2032)
				(type default)
			)
			(fill no)
			(layer "F.SilkS")
		)
		(fp_circle
			(center 0 0)
			(end 0.508 0)
			(stroke
				(width 0.2032)
				(type default)
			)
			(fill no)
			(layer "F.SilkS")
		)
		(fp_poly
			(pts
				(xy -1.27 2.9464) (xy 1.27 2.9464) (xy 1.27 -2.9464) (xy -1.27 -2.9464)
			)
			(stroke
				(width 0)
				(type default)
			)
			(fill no)
			(layer "F.CrtYd")
		)
		(fp_line
			(start -1.016 -2.794)
			(end 1.016 -2.794)
			(stroke
				(width 0.0254)
				(type default)
			)
			(layer "F.Fab")
		)
		(fp_line
			(start -1.016 2.794)
			(end -1.016 -2.794)
			(stroke
				(width 0.0254)
				(type default)
			)
			(layer "F.Fab")
		)
		(fp_line
			(start 1.016 -2.794)
			(end 1.016 2.794)
			(stroke
				(width 0.0254)
				(type default)
			)
			(layer "F.Fab")
		)
		(fp_line
			(start 1.016 2.794)
			(end -1.016 2.794)
			(stroke
				(width 0.0254)
				(type default)
			)
			(layer "F.Fab")
		)
		(pad "1" smd rect
			(at 0 -1.6764)
			(size 1.524 1.524)
			(layers "F.Cu" "F.Mask" "F.Paste")
			(net "VDD_CORE")
		)
		(pad "2" smd rect
			(at 0 1.6764)
			(size 1.524 1.524)
			(layers "F.Cu" "F.Mask" "F.Paste")
			(net "GND")
		)
		(zone
			(layer "F.Cu")
			(hatch none 0.5)
			(connect_pads
				(clearance 0)
			)
			(min_thickness 0.25)
			(keepout
				(tracks not_allowed)
				(vias allowed)
				(pads allowed)
				(copperpour not_allowed)
				(footprints allowed)
			)
			(placement
				(enabled no)
				(sheetname "")
			)
			(fill
				(thermal_gap 0.5)
				(thermal_bridge_width 0.5)
				(island_removal_mode 0)
			)
			(polygon
				(pts
					(xy 38.8366 42.418) (xy 40.4114 42.418) (xy 40.4114 42.5704) (xy 38.8366 42.5704)
				)
			)
		)
		(zone
			(layer "F.Cu")
			(hatch none 0.5)
			(connect_pads
				(clearance 0)
			)
			(min_thickness 0.25)
			(keepout
				(tracks not_allowed)
				(vias allowed)
				(pads allowed)
				(copperpour not_allowed)
				(footprints allowed)
			)
			(placement
				(enabled no)
				(sheetname "")
			)
			(fill
				(thermal_gap 0.5)
				(thermal_bridge_width 0.5)
				(island_removal_mode 0)
			)
			(polygon
				(pts
					(xy 38.8366 44.0436) (xy 40.4114 44.0436) (xy 40.4114 44.196) (xy 38.8366 44.196)
				)
			)
		)
		(zone
			(layer "F.Cu")
			(hatch none 0.5)
			(connect_pads
				(clearance 0)
			)
			(min_thickness 0.25)
			(keepout
				(tracks allowed)
				(vias not_allowed)
				(pads allowed)
				(copperpour not_allowed)
				(footprints allowed)
			)
			(placement
				(enabled no)
				(sheetname "")
			)
			(fill
				(thermal_gap 0.5)
				(thermal_bridge_width 0.5)
				(island_removal_mode 0)
			)
			(polygon
				(pts
					(xy 38.8366 44.9072) (xy 40.4114 44.9072) (xy 40.4114 41.7068) (xy 38.8366 41.7068)
				)
			)
		)
	)
	(footprint ""
		(layer "F.Cu")
		(at 73.851008 17.455998)
		(property "Reference" "V_A-DQS3-P"
			(at 0 0 0)
			(layer "F.SilkS")
			(hide yes)
			(effects
				(font
					(size 1.27 1.27)
				)
			)
		)
		(property "Value" ""
			(at 0 0 0)
			(layer "F.Fab")
			(effects
				(font
					(size 1.27 1.27)
				)
			)
		)
		(duplicate_pad_numbers_are_jumpers no)
		(pad "1" thru_hole circle
			(at 0 0)
			(size 0.762 0.762)
			(drill 0.20574)
			(layers "*.Cu" "*.Mask")
			(remove_unused_layers no)
			(net "DDR0_32A_DQS3_P")
			(clearance 0.127)
			(thermal_gap 0.127)
			(padstack
				(mode front_inner_back)
				(layer "Inner"
					(shape circle)
					(size 0.4572 0.4572)
					(clearance 0.1143)
				)
				(layer "B.Cu"
					(shape circle)
					(size 0.4572 0.4572)
					(clearance 0.1143)
				)
			)
		)
	)
	(footprint ""
		(layer "F.Cu")
		(at 30.226 45.72 90)
		(property "Reference" "R313"
			(at -3.302 0.53467 90)
			(unlocked yes)
			(layer "F.SilkS")
			(effects
				(font
					(size 0.7874 0.5842)
					(thickness 0.127)
				)
				(justify left)
			)
		)
		(property "Value" "1.0K"
			(at -0.148158 1.3462 180)
			(unlocked yes)
			(layer "F.Fab")
			(hide yes)
			(effects
				(font
					(size 1.27 0.9652)
					(thickness 0.000001)
				)
				(justify left)
			)
		)
		(property "Device Type" "REST0025"
			(at -0.148158 1.3462 180)
			(unlocked yes)
			(layer "F.Fab")
			(hide yes)
			(effects
				(font
					(size 1.27 0.9652)
					(thickness 0.000001)
				)
				(justify left)
			)
		)
		(duplicate_pad_numbers_are_jumpers no)
		(fp_poly
			(pts
				(xy 0.635 1.0668) (xy 0.635 -1.0668) (xy -0.635 -1.0668) (xy -0.635 1.0668)
			)
			(stroke
				(width 0)
				(type default)
			)
			(fill no)
			(layer "F.CrtYd")
		)
		(fp_line
			(start 0.254 -0.508)
			(end 0.254 0.508)
			(stroke
				(width 0.0254)
				(type default)
			)
			(layer "F.Fab")
		)
		(fp_line
			(start -0.254 -0.508)
			(end 0.254 -0.508)
			(stroke
				(width 0.0254)
				(type default)
			)
			(layer "F.Fab")
		)
		(fp_line
			(start 0.254 0.508)
			(end -0.254 0.508)
			(stroke
				(width 0.0254)
				(type default)
			)
			(layer "F.Fab")
		)
		(fp_line
			(start -0.254 0.508)
			(end -0.254 -0.508)
			(stroke
				(width 0.0254)
				(type default)
			)
			(layer "F.Fab")
		)
		(pad "1" smd rect
			(at 0 -0.4191 90)
			(size 0.508 0.5334)
			(layers "F.Cu" "F.Mask" "F.Paste")
			(net "10N2504")
		)
		(pad "2" smd rect
			(at 0 0.4191 90)
			(size 0.508 0.5334)
			(layers "F.Cu" "F.Mask" "F.Paste")
			(net "NFP_VDD_CORE_SENSE_VDD")
		)
		(zone
			(layer "F.Cu")
			(hatch none 0.5)
			(connect_pads
				(clearance 0)
			)
			(min_thickness 0.25)
			(keepout
				(tracks not_allowed)
				(vias allowed)
				(pads allowed)
				(copperpour not_allowed)
				(footprints allowed)
			)
			(placement
				(enabled no)
				(sheetname "")
			)
			(fill
				(thermal_gap 0.5)
				(thermal_bridge_width 0.5)
				(island_removal_mode 0)
			)
			(polygon
				(pts
					(xy 30.2006 45.6946) (xy 30.2514 45.6946) (xy 30.2514 45.7454) (xy 30.2006 45.7454)
				)
			)
		)
	)
	(footprint ""
		(layer "F.Cu")
		(at 33.782 44.323 180)
		(property "Reference" "R13"
			(at 1.27 -0.91567 0)
			(unlocked yes)
			(layer "F.SilkS")
			(effects
				(font
					(size 0.7874 0.5842)
					(thickness 0.127)
				)
				(justify left)
			)
		)
		(property "Value" ""
			(at 0 0 180)
			(layer "F.Fab")
			(effects
				(font
					(size 1.27 1.27)
				)
			)
		)
		(duplicate_pad_numbers_are_jumpers no)
		(fp_line
			(start 0.0254 0.127)
			(end -0.0254 0.127)
			(stroke
				(width 0.1016)
				(type default)
			)
			(layer "F.SilkS")
		)
		(fp_line
			(start 0.0254 -0.127)
			(end 0.0254 0.127)
			(stroke
				(width 0.1016)
				(type default)
			)
			(layer "F.SilkS")
		)
		(fp_line
			(start -0.0254 0.127)
			(end -0.0254 -0.127)
			(stroke
				(width 0.1016)
				(type default)
			)
			(layer "F.SilkS")
		)
		(fp_line
			(start -0.0254 -0.127)
			(end 0.0254 -0.127)
			(stroke
				(width 0.1016)
				(type default)
			)
			(layer "F.SilkS")
		)
		(fp_poly
			(pts
				(xy 0.889 -0.4953) (xy 0.889 0.4953) (xy -0.889 0.4953) (xy -0.889 -0.4953)
			)
			(stroke
				(width 0)
				(type default)
			)
			(fill no)
			(layer "F.CrtYd")
		)
		(fp_line
			(start 0.508 0.254)
			(end 0.508 -0.254)
			(stroke
				(width 0.0254)
				(type default)
			)
			(layer "F.Fab")
		)
		(fp_line
			(start 0.508 -0.254)
			(end -0.508 -0.254)
			(stroke
				(width 0.0254)
				(type default)
			)
			(layer "F.Fab")
		)
		(fp_line
			(start -0.508 0.254)
			(end 0.508 0.254)
			(stroke
				(width 0.0254)
				(type default)
			)
			(layer "F.Fab")
		)
		(fp_line
			(start -0.508 -0.254)
			(end -0.508 0.254)
			(stroke
				(width 0.0254)
				(type default)
			)
			(layer "F.Fab")
		)
		(pad "1" smd rect
			(at -0.4699 0 180)
			(size 0.5334 0.508)
			(layers "F.Cu" "F.Mask" "F.Paste")
			(net "NFP_VDD_CORE_TCOMPB")
		)
		(pad "2" smd rect
			(at 0.4699 0 180)
			(size 0.5334 0.508)
			(layers "F.Cu" "F.Mask" "F.Paste")
			(net "10N2528")
		)
	)
	(footprint ""
		(layer "F.Cu")
		(at 85.344 35.306)
		(property "Reference" "TP65"
			(at 1.67767 1.016 90)
			(unlocked yes)
			(layer "F.SilkS")
			(effects
				(font
					(size 0.7874 0.5842)
					(thickness 0.127)
				)
				(justify left)
			)
		)
		(property "Value" "*"
			(at -0.4826 -0.14732 0)
			(unlocked yes)
			(layer "F.Fab")
			(hide yes)
			(effects
				(font
					(size 1.27 0.9652)
					(thickness 0.000001)
				)
				(justify left)
			)
		)
		(property "Device Type" "TP_SMALL"
			(at -0.4826 -0.14732 0)
			(unlocked yes)
			(layer "F.Fab")
			(hide yes)
			(effects
				(font
					(size 1.27 0.9652)
					(thickness 0.000001)
				)
				(justify left)
			)
		)
		(duplicate_pad_numbers_are_jumpers no)
		(fp_line
			(start -0.8636 -0.8636)
			(end -0.8636 0.8636)
			(stroke
				(width 0.1524)
				(type default)
			)
			(layer "F.SilkS")
		)
		(fp_line
			(start -0.8636 0.8636)
			(end 0.8636 0.8636)
			(stroke
				(width 0.1524)
				(type default)
			)
			(layer "F.SilkS")
		)
		(fp_line
			(start 0.8636 -0.8636)
			(end -0.8636 -0.8636)
			(stroke
				(width 0.1524)
				(type default)
			)
			(layer "F.SilkS")
		)
		(fp_line
			(start 0.8636 0.8636)
			(end 0.8636 -0.8636)
			(stroke
				(width 0.1524)
				(type default)
			)
			(layer "F.SilkS")
		)
		(fp_poly
			(pts
				(xy -0.635 -0.635) (xy -0.635 0.635) (xy 0.635 0.635) (xy 0.635 -0.635)
			)
			(stroke
				(width 0)
				(type default)
			)
			(fill no)
			(layer "F.CrtYd")
		)
		(pad "1" smd rect
			(at 0 0)
			(size 1.27 1.27)
			(layers "F.Cu" "F.Mask" "F.Paste")
			(net "VDDQ_VTT_EN")
		)
	)
	(footprint ""
		(layer "F.Cu")
		(at 13.208 30.607)
		(property "Reference" "TP42"
			(at -1.75133 1.016 90)
			(unlocked yes)
			(layer "F.SilkS")
			(effects
				(font
					(size 0.7874 0.5842)
					(thickness 0.127)
				)
				(justify left)
			)
		)
		(property "Value" "*"
			(at -0.4826 -0.14732 0)
			(unlocked yes)
			(layer "F.Fab")
			(hide yes)
			(effects
				(font
					(size 1.27 0.9652)
					(thickness 0.000001)
				)
				(justify left)
			)
		)
		(property "Device Type" "TP_SMALL"
			(at -0.4826 -0.14732 0)
			(unlocked yes)
			(layer "F.Fab")
			(hide yes)
			(effects
				(font
					(size 1.27 0.9652)
					(thickness 0.000001)
				)
				(justify left)
			)
		)
		(duplicate_pad_numbers_are_jumpers no)
		(fp_line
			(start -0.8636 -0.8636)
			(end -0.8636 0.8636)
			(stroke
				(width 0.1524)
				(type default)
			)
			(layer "F.SilkS")
		)
		(fp_line
			(start -0.8636 0.8636)
			(end 0.8636 0.8636)
			(stroke
				(width 0.1524)
				(type default)
			)
			(layer "F.SilkS")
		)
		(fp_line
			(start 0.8636 -0.8636)
			(end -0.8636 -0.8636)
			(stroke
				(width 0.1524)
				(type default)
			)
			(layer "F.SilkS")
		)
		(fp_line
			(start 0.8636 0.8636)
			(end 0.8636 -0.8636)
			(stroke
				(width 0.1524)
				(type default)
			)
			(layer "F.SilkS")
		)
		(fp_poly
			(pts
				(xy -0.635 -0.635) (xy -0.635 0.635) (xy 0.635 0.635) (xy 0.635 -0.635)
			)
			(stroke
				(width 0)
				(type default)
			)
			(fill no)
			(layer "F.CrtYd")
		)
		(pad "1" smd rect
			(at 0 0)
			(size 1.27 1.27)
			(layers "F.Cu" "F.Mask" "F.Paste")
			(net "VDD_5.0V")
		)
	)
	(footprint ""
		(layer "F.Cu")
		(at 18.0594 40.894 90)
		(property "Reference" "C132"
			(at 0.98933 -1.2954 0)
			(unlocked yes)
			(layer "F.SilkS")
			(effects
				(font
					(size 0.7874 0.5842)
					(thickness 0.127)
				)
				(justify left)
			)
		)
		(property "Value" "10UF"
			(at -0.148158 1.7526 180)
			(unlocked yes)
			(layer "F.Fab")
			(hide yes)
			(effects
				(font
					(size 1.27 0.9652)
					(thickness 0.000001)
				)
				(justify left)
			)
		)
		(property "Device Type" "CAPC0058"
			(at -0.148158 1.7526 180)
			(unlocked yes)
			(layer "F.Fab")
			(hide yes)
			(effects
				(font
					(size 1.27 0.9652)
					(thickness 0.000001)
				)
				(justify left)
			)
		)
		(duplicate_pad_numbers_are_jumpers no)
		(fp_circle
			(center 0 0)
			(end 0 0.127)
			(stroke
				(width 0.2032)
				(type default)
			)
			(fill no)
			(layer "F.SilkS")
		)
		(fp_poly
			(pts
				(xy 0.7874 -1.6637) (xy -0.7874 -1.6637) (xy -0.7874 1.6637) (xy 0.7874 1.6637)
			)
			(stroke
				(width 0)
				(type default)
			)
			(fill no)
			(layer "F.CrtYd")
		)
		(fp_line
			(start 0.4064 -0.7874)
			(end 0.4064 0.8128)
			(stroke
				(width 0.0254)
				(type default)
			)
			(layer "F.Fab")
		)
		(fp_line
			(start -0.4064 -0.7874)
			(end 0.4064 -0.7874)
			(stroke
				(width 0.0254)
				(type default)
			)
			(layer "F.Fab")
		)
		(fp_line
			(start 0.4064 0.8128)
			(end -0.4064 0.8128)
			(stroke
				(width 0.0254)
				(type default)
			)
			(layer "F.Fab")
		)
		(fp_line
			(start -0.4064 0.8128)
			(end -0.4064 -0.7874)
			(stroke
				(width 0.0254)
				(type default)
			)
			(layer "F.Fab")
		)
		(pad "1" smd rect
			(at 0 -0.8001 90)
			(size 0.8636 0.9652)
			(layers "F.Cu" "F.Mask" "F.Paste")
			(net "VDD_5.0V")
		)
		(pad "2" smd rect
			(at 0 0.8001 90)
			(size 0.8636 0.9652)
			(layers "F.Cu" "F.Mask" "F.Paste")
			(net "GND")
		)
	)
	(footprint ""
		(layer "F.Cu")
		(at 24.511 16.8529)
		(property "Reference" "R23"
			(at 0 0 0)
			(layer "F.SilkS")
			(hide yes)
			(effects
				(font
					(size 1.27 1.27)
				)
			)
		)
		(property "Value" "4.75K"
			(at -0.148158 1.3462 90)
			(unlocked yes)
			(layer "F.Fab")
			(hide yes)
			(effects
				(font
					(size 1.27 0.9652)
					(thickness 0.000001)
				)
				(justify left)
			)
		)
		(property "Device Type" "REST4024"
			(at -0.148158 1.3462 90)
			(unlocked yes)
			(layer "F.Fab")
			(hide yes)
			(effects
				(font
					(size 1.27 0.9652)
					(thickness 0.000001)
				)
				(justify left)
			)
		)
		(duplicate_pad_numbers_are_jumpers no)
		(fp_poly
			(pts
				(xy 0.635 1.0668) (xy 0.635 -1.0668) (xy -0.635 -1.0668) (xy -0.635 1.0668)
			)
			(stroke
				(width 0)
				(type default)
			)
			(fill no)
			(layer "F.CrtYd")
		)
		(fp_line
			(start -0.254 -0.508)
			(end 0.254 -0.508)
			(stroke
				(width 0.0254)
				(type default)
			)
			(layer "F.Fab")
		)
		(fp_line
			(start -0.254 0.508)
			(end -0.254 -0.508)
			(stroke
				(width 0.0254)
				(type default)
			)
			(layer "F.Fab")
		)
		(fp_line
			(start 0.254 -0.508)
			(end 0.254 0.508)
			(stroke
				(width 0.0254)
				(type default)
			)
			(layer "F.Fab")
		)
		(fp_line
			(start 0.254 0.508)
			(end -0.254 0.508)
			(stroke
				(width 0.0254)
				(type default)
			)
			(layer "F.Fab")
		)
		(pad "1" smd rect
			(at 0 -0.4191)
			(size 0.508 0.5334)
			(layers "F.Cu" "F.Mask" "F.Paste")
			(net "VDD_3.3V")
		)
		(pad "2" smd rect
			(at 0 0.4191)
			(size 0.508 0.5334)
			(layers "F.Cu" "F.Mask" "F.Paste")
			(net "NFP_ARM_SPI_FLASH_MOSI")
		)
		(zone
			(layer "F.Cu")
			(hatch none 0.5)
			(connect_pads
				(clearance 0)
			)
			(min_thickness 0.25)
			(keepout
				(tracks not_allowed)
				(vias allowed)
				(pads allowed)
				(copperpour not_allowed)
				(footprints allowed)
			)
			(placement
				(enabled no)
				(sheetname "")
			)
			(fill
				(thermal_gap 0.5)
				(thermal_bridge_width 0.5)
				(island_removal_mode 0)
			)
			(polygon
				(pts
					(xy 24.5364 16.8275) (xy 24.5364 16.8783) (xy 24.4856 16.8783) (xy 24.4856 16.8275)
				)
			)
		)
	)
	(footprint ""
		(layer "F.Cu")
		(at 1.524 34.163 180)
		(property "Reference" "R100"
			(at 0 0 180)
			(layer "F.SilkS")
			(hide yes)
			(effects
				(font
					(size 1.27 1.27)
				)
			)
		)
		(property "Value" "4.75K"
			(at -0.148158 1.3462 270)
			(unlocked yes)
			(layer "F.Fab")
			(hide yes)
			(effects
				(font
					(size 1.27 0.9652)
					(thickness 0.000001)
				)
				(justify left)
			)
		)
		(property "Device Type" "REST4024"
			(at -0.148158 1.3462 270)
			(unlocked yes)
			(layer "F.Fab")
			(hide yes)
			(effects
				(font
					(size 1.27 0.9652)
					(thickness 0.000001)
				)
				(justify left)
			)
		)
		(duplicate_pad_numbers_are_jumpers no)
		(fp_poly
			(pts
				(xy 0.635 1.0668) (xy 0.635 -1.0668) (xy -0.635 -1.0668) (xy -0.635 1.0668)
			)
			(stroke
				(width 0)
				(type default)
			)
			(fill no)
			(layer "F.CrtYd")
		)
		(fp_line
			(start 0.254 0.508)
			(end -0.254 0.508)
			(stroke
				(width 0.0254)
				(type default)
			)
			(layer "F.Fab")
		)
		(fp_line
			(start 0.254 -0.508)
			(end 0.254 0.508)
			(stroke
				(width 0.0254)
				(type default)
			)
			(layer "F.Fab")
		)
		(fp_line
			(start -0.254 0.508)
			(end -0.254 -0.508)
			(stroke
				(width 0.0254)
				(type default)
			)
			(layer "F.Fab")
		)
		(fp_line
			(start -0.254 -0.508)
			(end 0.254 -0.508)
			(stroke
				(width 0.0254)
				(type default)
			)
			(layer "F.Fab")
		)
		(pad "1" smd rect
			(at 0 -0.4191 180)
			(size 0.508 0.5334)
			(layers "F.Cu" "F.Mask" "F.Paste")
			(net "VDD_7401_PGOOD")
		)
		(pad "2" smd rect
			(at 0 0.4191 180)
			(size 0.508 0.5334)
			(layers "F.Cu" "F.Mask" "F.Paste")
			(net "EXT_3.3V")
		)
		(zone
			(layer "F.Cu")
			(hatch none 0.5)
			(connect_pads
				(clearance 0)
			)
			(min_thickness 0.25)
			(keepout
				(tracks not_allowed)
				(vias allowed)
				(pads allowed)
				(copperpour not_allowed)
				(footprints allowed)
			)
			(placement
				(enabled no)
				(sheetname "")
			)
			(fill
				(thermal_gap 0.5)
				(thermal_bridge_width 0.5)
				(island_removal_mode 0)
			)
			(polygon
				(pts
					(xy 1.4986 34.1884) (xy 1.4986 34.1376) (xy 1.5494 34.1376) (xy 1.5494 34.1884)
				)
			)
		)
	)
	(footprint ""
		(layer "F.Cu")
		(at 10.16 44.196)
		(property "Reference" "L11"
			(at -2.51333 -0.381 90)
			(unlocked yes)
			(layer "F.SilkS")
			(effects
				(font
					(size 0.7874 0.5842)
					(thickness 0.127)
				)
				(justify left)
			)
		)
		(property "Value" "2.2UH"
			(at -0.483362 -0.148082 0)
			(unlocked yes)
			(layer "F.Fab")
			(hide yes)
			(effects
				(font
					(size 1.27 0.9652)
					(thickness 0.000001)
				)
				(justify left)
			)
		)
		(property "Device Type" "INDS0060"
			(at -0.483362 -0.148082 0)
			(unlocked yes)
			(layer "F.Fab")
			(hide yes)
			(effects
				(font
					(size 1.27 0.9652)
					(thickness 0.000001)
				)
				(justify left)
			)
		)
		(duplicate_pad_numbers_are_jumpers no)
		(fp_line
			(start -1.27 -1.397)
			(end 1.27 -1.397)
			(stroke
				(width 0.1524)
				(type default)
			)
			(layer "F.SilkS")
		)
		(fp_line
			(start 1.27 1.397)
			(end -1.27 1.397)
			(stroke
				(width 0.1524)
				(type default)
			)
			(layer "F.SilkS")
		)
		(fp_poly
			(pts
				(xy 2.159 -1.651) (xy 2.159 1.651) (xy -1.794535 1.651) (xy -1.794535 -1.651)
			)
			(stroke
				(width 0)
				(type default)
			)
			(fill no)
			(layer "F.CrtYd")
		)
		(fp_line
			(start -1.3462 -1.1049)
			(end -1.3462 1.1049)
			(stroke
				(width 0.1524)
				(type default)
			)
			(layer "F.Fab")
		)
		(fp_line
			(start -1.3462 1.1049)
			(end 1.3462 1.1049)
			(stroke
				(width 0.1524)
				(type default)
			)
			(layer "F.Fab")
		)
		(fp_line
			(start 1.3462 -1.1049)
			(end -1.3462 -1.1049)
			(stroke
				(width 0.1524)
				(type default)
			)
			(layer "F.Fab")
		)
		(fp_line
			(start 1.3462 1.1049)
			(end 1.3462 -1.1049)
			(stroke
				(width 0.1524)
				(type default)
			)
			(layer "F.Fab")
		)
		(pad "1" smd rect
			(at -1.1303 0)
			(size 1.1938 2.3368)
			(layers "F.Cu" "F.Mask" "F.Paste")
			(net "VDD_1.5V")
		)
		(pad "2" smd rect
			(at 1.1303 0)
			(size 1.1938 2.3368)
			(layers "F.Cu" "F.Mask" "F.Paste")
			(net "11N1968")
		)
		(zone
			(layer "F.Cu")
			(hatch none 0.5)
			(connect_pads
				(clearance 0)
			)
			(min_thickness 0.25)
			(keepout
				(tracks allowed)
				(vias not_allowed)
				(pads allowed)
				(copperpour not_allowed)
				(footprints allowed)
			)
			(placement
				(enabled no)
				(sheetname "")
			)
			(fill
				(thermal_gap 0.5)
				(thermal_bridge_width 0.5)
				(island_removal_mode 0)
			)
			(polygon
				(pts
					(xy 8.8138 45.3009) (xy 11.5062 45.3009) (xy 11.5062 43.0911) (xy 8.8138 43.0911)
				)
			)
		)
	)
	(footprint ""
		(layer "F.Cu")
		(at 19.304 1.397 -90)
		(property "Reference" "R371"
			(at -0.381 0.22733 90)
			(unlocked yes)
			(layer "F.SilkS")
			(effects
				(font
					(size 0.7874 0.5842)
					(thickness 0.127)
				)
				(justify left)
			)
		)
		(property "Value" "4.75K"
			(at -0.148158 1.3462 0)
			(unlocked yes)
			(layer "F.Fab")
			(hide yes)
			(effects
				(font
					(size 1.27 0.9652)
					(thickness 0.000001)
				)
				(justify left)
			)
		)
		(property "Device Type" "REST4024"
			(at -0.148158 1.3462 0)
			(unlocked yes)
			(layer "F.Fab")
			(hide yes)
			(effects
				(font
					(size 1.27 0.9652)
					(thickness 0.000001)
				)
				(justify left)
			)
		)
		(duplicate_pad_numbers_are_jumpers no)
		(fp_poly
			(pts
				(xy 0.635 1.0668) (xy 0.635 -1.0668) (xy -0.635 -1.0668) (xy -0.635 1.0668)
			)
			(stroke
				(width 0)
				(type default)
			)
			(fill no)
			(layer "F.CrtYd")
		)
		(fp_line
			(start -0.254 0.508)
			(end -0.254 -0.508)
			(stroke
				(width 0.0254)
				(type default)
			)
			(layer "F.Fab")
		)
		(fp_line
			(start 0.254 0.508)
			(end -0.254 0.508)
			(stroke
				(width 0.0254)
				(type default)
			)
			(layer "F.Fab")
		)
		(fp_line
			(start -0.254 -0.508)
			(end 0.254 -0.508)
			(stroke
				(width 0.0254)
				(type default)
			)
			(layer "F.Fab")
		)
		(fp_line
			(start 0.254 -0.508)
			(end 0.254 0.508)
			(stroke
				(width 0.0254)
				(type default)
			)
			(layer "F.Fab")
		)
		(pad "1" smd rect
			(at 0 -0.4191 270)
			(size 0.508 0.5334)
			(layers "F.Cu" "F.Mask" "F.Paste")
			(net "13N4315")
		)
		(pad "2" smd rect
			(at 0 0.4191 270)
			(size 0.508 0.5334)
			(layers "F.Cu" "F.Mask" "F.Paste")
			(net "GND")
		)
		(zone
			(layer "F.Cu")
			(hatch none 0.5)
			(connect_pads
				(clearance 0)
			)
			(min_thickness 0.25)
			(keepout
				(tracks not_allowed)
				(vias allowed)
				(pads allowed)
				(copperpour not_allowed)
				(footprints allowed)
			)
			(placement
				(enabled no)
				(sheetname "")
			)
			(fill
				(thermal_gap 0.5)
				(thermal_bridge_width 0.5)
				(island_removal_mode 0)
			)
			(polygon
				(pts
					(xy 19.3294 1.4224) (xy 19.2786 1.4224) (xy 19.2786 1.3716) (xy 19.3294 1.3716)
				)
			)
		)
	)
	(footprint ""
		(layer "F.Cu")
		(at 53.086 52.0192 -90)
		(property "Reference" "C64"
			(at 1.34747 -0.127 0)
			(unlocked yes)
			(layer "F.SilkS")
			(effects
				(font
					(size 0.7874 0.5842)
					(thickness 0.127)
				)
				(justify left)
			)
		)
		(property "Value" "100UF"
			(at -0.78232 0.4826 0)
			(unlocked yes)
			(layer "F.Fab")
			(hide yes)
			(effects
				(font
					(size 1.27 0.9652)
					(thickness 0.000001)
				)
				(justify left)
			)
		)
		(property "Device Type" "CAPC0087"
			(at -0.78232 0.4826 0)
			(unlocked yes)
			(layer "F.Fab")
			(hide yes)
			(effects
				(font
					(size 1.27 0.9652)
					(thickness 0.000001)
				)
				(justify left)
			)
		)
		(duplicate_pad_numbers_are_jumpers no)
		(fp_circle
			(center 0 0)
			(end 0 -0.508)
			(stroke
				(width 0.2032)
				(type default)
			)
			(fill no)
			(layer "F.SilkS")
		)
		(fp_circle
			(center 0 0)
			(end 0 -0.508)
			(stroke
				(width 0.2032)
				(type default)
			)
			(fill no)
			(layer "F.SilkS")
		)
		(fp_poly
			(pts
				(xy -1.27 2.9464) (xy 1.27 2.9464) (xy 1.27 -2.9464) (xy -1.27 -2.9464)
			)
			(stroke
				(width 0)
				(type default)
			)
			(fill no)
			(layer "F.CrtYd")
		)
		(fp_line
			(start -1.016 2.794)
			(end -1.016 -2.794)
			(stroke
				(width 0.0254)
				(type default)
			)
			(layer "F.Fab")
		)
		(fp_line
			(start 1.016 2.794)
			(end -1.016 2.794)
			(stroke
				(width 0.0254)
				(type default)
			)
			(layer "F.Fab")
		)
		(fp_line
			(start -1.016 -2.794)
			(end 1.016 -2.794)
			(stroke
				(width 0.0254)
				(type default)
			)
			(layer "F.Fab")
		)
		(fp_line
			(start 1.016 -2.794)
			(end 1.016 2.794)
			(stroke
				(width 0.0254)
				(type default)
			)
			(layer "F.Fab")
		)
		(pad "1" smd rect
			(at 0 -1.6764 270)
			(size 1.524 1.524)
			(layers "F.Cu" "F.Mask" "F.Paste")
			(net "VDD_CORE")
		)
		(pad "2" smd rect
			(at 0 1.6764 270)
			(size 1.524 1.524)
			(layers "F.Cu" "F.Mask" "F.Paste")
			(net "GND")
		)
		(zone
			(layer "F.Cu")
			(hatch none 0.5)
			(connect_pads
				(clearance 0)
			)
			(min_thickness 0.25)
			(keepout
				(tracks allowed)
				(vias not_allowed)
				(pads allowed)
				(copperpour not_allowed)
				(footprints allowed)
			)
			(placement
				(enabled no)
				(sheetname "")
			)
			(fill
				(thermal_gap 0.5)
				(thermal_bridge_width 0.5)
				(island_removal_mode 0)
			)
			(polygon
				(pts
					(xy 51.4858 51.2318) (xy 51.4858 52.8066) (xy 54.6862 52.8066) (xy 54.6862 51.2318)
				)
			)
		)
		(zone
			(layer "F.Cu")
			(hatch none 0.5)
			(connect_pads
				(clearance 0)
			)
			(min_thickness 0.25)
			(keepout
				(tracks not_allowed)
				(vias allowed)
				(pads allowed)
				(copperpour not_allowed)
				(footprints allowed)
			)
			(placement
				(enabled no)
				(sheetname "")
			)
			(fill
				(thermal_gap 0.5)
				(thermal_bridge_width 0.5)
				(island_removal_mode 0)
			)
			(polygon
				(pts
					(xy 52.3494 51.2318) (xy 52.3494 52.8066) (xy 52.197 52.8066) (xy 52.197 51.2318)
				)
			)
		)
		(zone
			(layer "F.Cu")
			(hatch none 0.5)
			(connect_pads
				(clearance 0)
			)
			(min_thickness 0.25)
			(keepout
				(tracks not_allowed)
				(vias allowed)
				(pads allowed)
				(copperpour not_allowed)
				(footprints allowed)
			)
			(placement
				(enabled no)
				(sheetname "")
			)
			(fill
				(thermal_gap 0.5)
				(thermal_bridge_width 0.5)
				(island_removal_mode 0)
			)
			(polygon
				(pts
					(xy 53.975 51.2318) (xy 53.975 52.8066) (xy 53.8226 52.8066) (xy 53.8226 51.2318)
				)
			)
		)
	)
	(footprint ""
		(layer "F.Cu")
		(at 77.051002 14.256004)
		(property "Reference" "V_A-DQ19"
			(at 0 0 0)
			(layer "F.SilkS")
			(hide yes)
			(effects
				(font
					(size 1.27 1.27)
				)
			)
		)
		(property "Value" ""
			(at 0 0 0)
			(layer "F.Fab")
			(effects
				(font
					(size 1.27 1.27)
				)
			)
		)
		(duplicate_pad_numbers_are_jumpers no)
		(pad "1" thru_hole circle
			(at 0 0)
			(size 0.762 0.762)
			(drill 0.20574)
			(layers "*.Cu" "*.Mask")
			(remove_unused_layers no)
			(net "DDR0_32A_DQ19")
			(clearance 0.127)
			(thermal_gap 0.127)
			(padstack
				(mode front_inner_back)
				(layer "Inner"
					(shape circle)
					(size 0.4572 0.4572)
					(clearance 0.1143)
				)
				(layer "B.Cu"
					(shape circle)
					(size 0.4572 0.4572)
					(clearance 0.1143)
				)
			)
		)
	)
	(footprint ""
		(layer "F.Cu")
		(at 0.635 34.163)
		(property "Reference" "R103"
			(at 0 0 0)
			(layer "F.SilkS")
			(hide yes)
			(effects
				(font
					(size 1.27 1.27)
				)
			)
		)
		(property "Value" "4.75K"
			(at -0.148158 1.3462 90)
			(unlocked yes)
			(layer "F.Fab")
			(hide yes)
			(effects
				(font
					(size 1.27 0.9652)
					(thickness 0.000001)
				)
				(justify left)
			)
		)
		(property "Device Type" "REST4024"
			(at -0.148158 1.3462 90)
			(unlocked yes)
			(layer "F.Fab")
			(hide yes)
			(effects
				(font
					(size 1.27 0.9652)
					(thickness 0.000001)
				)
				(justify left)
			)
		)
		(duplicate_pad_numbers_are_jumpers no)
		(fp_poly
			(pts
				(xy 0.635 1.0668) (xy 0.635 -1.0668) (xy -0.635 -1.0668) (xy -0.635 1.0668)
			)
			(stroke
				(width 0)
				(type default)
			)
			(fill no)
			(layer "F.CrtYd")
		)
		(fp_line
			(start -0.254 -0.508)
			(end 0.254 -0.508)
			(stroke
				(width 0.0254)
				(type default)
			)
			(layer "F.Fab")
		)
		(fp_line
			(start -0.254 0.508)
			(end -0.254 -0.508)
			(stroke
				(width 0.0254)
				(type default)
			)
			(layer "F.Fab")
		)
		(fp_line
			(start 0.254 -0.508)
			(end 0.254 0.508)
			(stroke
				(width 0.0254)
				(type default)
			)
			(layer "F.Fab")
		)
		(fp_line
			(start 0.254 0.508)
			(end -0.254 0.508)
			(stroke
				(width 0.0254)
				(type default)
			)
			(layer "F.Fab")
		)
		(pad "1" smd rect
			(at 0 -0.4191)
			(size 0.508 0.5334)
			(layers "F.Cu" "F.Mask" "F.Paste")
			(net "GND")
		)
		(pad "2" smd rect
			(at 0 0.4191)
			(size 0.508 0.5334)
			(layers "F.Cu" "F.Mask" "F.Paste")
			(net "VDD_7401_EN")
		)
		(zone
			(layer "F.Cu")
			(hatch none 0.5)
			(connect_pads
				(clearance 0)
			)
			(min_thickness 0.25)
			(keepout
				(tracks not_allowed)
				(vias allowed)
				(pads allowed)
				(copperpour not_allowed)
				(footprints allowed)
			)
			(placement
				(enabled no)
				(sheetname "")
			)
			(fill
				(thermal_gap 0.5)
				(thermal_bridge_width 0.5)
				(island_removal_mode 0)
			)
			(polygon
				(pts
					(xy 0.6604 34.1376) (xy 0.6604 34.1884) (xy 0.6096 34.1884) (xy 0.6096 34.1376)
				)
			)
		)
	)
	(footprint ""
		(layer "F.Cu")
		(at 74.651006 14.256004)
		(property "Reference" "V_A-DQ16"
			(at 0 0 0)
			(layer "F.SilkS")
			(hide yes)
			(effects
				(font
					(size 1.27 1.27)
				)
			)
		)
		(property "Value" ""
			(at 0 0 0)
			(layer "F.Fab")
			(effects
				(font
					(size 1.27 1.27)
				)
			)
		)
		(duplicate_pad_numbers_are_jumpers no)
		(pad "1" thru_hole circle
			(at 0 0)
			(size 0.762 0.762)
			(drill 0.20574)
			(layers "*.Cu" "*.Mask")
			(remove_unused_layers no)
			(net "DDR0_32A_DQ16")
			(clearance 0.127)
			(thermal_gap 0.127)
			(padstack
				(mode front_inner_back)
				(layer "Inner"
					(shape circle)
					(size 0.4572 0.4572)
					(clearance 0.1143)
				)
				(layer "B.Cu"
					(shape circle)
					(size 0.4572 0.4572)
					(clearance 0.1143)
				)
			)
		)
	)
	(footprint ""
		(layer "F.Cu")
		(at 75.438 23.495 -90)
		(property "Reference" "R364"
			(at 0 0 270)
			(layer "F.SilkS")
			(hide yes)
			(effects
				(font
					(size 1.27 1.27)
				)
			)
		)
		(property "Value" "100"
			(at -0.148158 1.3462 0)
			(unlocked yes)
			(layer "F.Fab")
			(hide yes)
			(effects
				(font
					(size 1.27 0.9652)
					(thickness 0.000001)
				)
				(justify left)
			)
		)
		(property "Device Type" "REST4030"
			(at -0.148158 1.3462 0)
			(unlocked yes)
			(layer "F.Fab")
			(hide yes)
			(effects
				(font
					(size 1.27 0.9652)
					(thickness 0.000001)
				)
				(justify left)
			)
		)
		(duplicate_pad_numbers_are_jumpers no)
		(fp_poly
			(pts
				(xy 0.635 1.0668) (xy 0.635 -1.0668) (xy -0.635 -1.0668) (xy -0.635 1.0668)
			)
			(stroke
				(width 0)
				(type default)
			)
			(fill no)
			(layer "F.CrtYd")
		)
		(fp_line
			(start -0.254 0.508)
			(end -0.254 -0.508)
			(stroke
				(width 0.0254)
				(type default)
			)
			(layer "F.Fab")
		)
		(fp_line
			(start 0.254 0.508)
			(end -0.254 0.508)
			(stroke
				(width 0.0254)
				(type default)
			)
			(layer "F.Fab")
		)
		(fp_line
			(start -0.254 -0.508)
			(end 0.254 -0.508)
			(stroke
				(width 0.0254)
				(type default)
			)
			(layer "F.Fab")
		)
		(fp_line
			(start 0.254 -0.508)
			(end 0.254 0.508)
			(stroke
				(width 0.0254)
				(type default)
			)
			(layer "F.Fab")
		)
		(pad "1" smd rect
			(at 0 -0.4191 270)
			(size 0.508 0.5334)
			(layers "F.Cu" "F.Mask" "F.Paste")
			(net "DDR0_32A_VREF1B")
		)
		(pad "2" smd rect
			(at 0 0.4191 270)
			(size 0.508 0.5334)
			(layers "F.Cu" "F.Mask" "F.Paste")
			(net "DDR_VDDQ")
		)
		(zone
			(layer "F.Cu")
			(hatch none 0.5)
			(connect_pads
				(clearance 0)
			)
			(min_thickness 0.25)
			(keepout
				(tracks not_allowed)
				(vias allowed)
				(pads allowed)
				(copperpour not_allowed)
				(footprints allowed)
			)
			(placement
				(enabled no)
				(sheetname "")
			)
			(fill
				(thermal_gap 0.5)
				(thermal_bridge_width 0.5)
				(island_removal_mode 0)
			)
			(polygon
				(pts
					(xy 75.4634 23.5204) (xy 75.4126 23.5204) (xy 75.4126 23.4696) (xy 75.4634 23.4696)
				)
			)
		)
	)
	(footprint ""
		(layer "F.Cu")
		(at 25.527 29.337 180)
		(property "Reference" "R60"
			(at -0.02667 0.889 90)
			(unlocked yes)
			(layer "F.SilkS")
			(effects
				(font
					(size 0.7874 0.5842)
					(thickness 0.127)
				)
				(justify left)
			)
		)
		(property "Value" "4.75K"
			(at -0.148158 1.3462 270)
			(unlocked yes)
			(layer "F.Fab")
			(hide yes)
			(effects
				(font
					(size 1.27 0.9652)
					(thickness 0.000001)
				)
				(justify left)
			)
		)
		(property "Device Type" "REST4024"
			(at -0.148158 1.3462 270)
			(unlocked yes)
			(layer "F.Fab")
			(hide yes)
			(effects
				(font
					(size 1.27 0.9652)
					(thickness 0.000001)
				)
				(justify left)
			)
		)
		(duplicate_pad_numbers_are_jumpers no)
		(fp_poly
			(pts
				(xy 0.635 1.0668) (xy 0.635 -1.0668) (xy -0.635 -1.0668) (xy -0.635 1.0668)
			)
			(stroke
				(width 0)
				(type default)
			)
			(fill no)
			(layer "F.CrtYd")
		)
		(fp_line
			(start 0.254 0.508)
			(end -0.254 0.508)
			(stroke
				(width 0.0254)
				(type default)
			)
			(layer "F.Fab")
		)
		(fp_line
			(start 0.254 -0.508)
			(end 0.254 0.508)
			(stroke
				(width 0.0254)
				(type default)
			)
			(layer "F.Fab")
		)
		(fp_line
			(start -0.254 0.508)
			(end -0.254 -0.508)
			(stroke
				(width 0.0254)
				(type default)
			)
			(layer "F.Fab")
		)
		(fp_line
			(start -0.254 -0.508)
			(end 0.254 -0.508)
			(stroke
				(width 0.0254)
				(type default)
			)
			(layer "F.Fab")
		)
		(pad "1" smd rect
			(at 0 -0.4191 180)
			(size 0.508 0.5334)
			(layers "F.Cu" "F.Mask" "F.Paste")
			(net "CPLD_PGRM_JTAG_SEL")
		)
		(pad "2" smd rect
			(at 0 0.4191 180)
			(size 0.508 0.5334)
			(layers "F.Cu" "F.Mask" "F.Paste")
			(net "GND")
		)
		(zone
			(layer "F.Cu")
			(hatch none 0.5)
			(connect_pads
				(clearance 0)
			)
			(min_thickness 0.25)
			(keepout
				(tracks not_allowed)
				(vias allowed)
				(pads allowed)
				(copperpour not_allowed)
				(footprints allowed)
			)
			(placement
				(enabled no)
				(sheetname "")
			)
			(fill
				(thermal_gap 0.5)
				(thermal_bridge_width 0.5)
				(island_removal_mode 0)
			)
			(polygon
				(pts
					(xy 25.5016 29.3624) (xy 25.5016 29.3116) (xy 25.5524 29.3116) (xy 25.5524 29.3624)
				)
			)
		)
	)
	(footprint ""
		(layer "F.Cu")
		(at 36.2712 42.545 90)
		(property "Reference" "R111"
			(at 0 0 90)
			(layer "F.SilkS")
			(hide yes)
			(effects
				(font
					(size 1.27 1.27)
				)
			)
		)
		(property "Value" "10"
			(at -0.148158 1.3462 180)
			(unlocked yes)
			(layer "F.Fab")
			(hide yes)
			(effects
				(font
					(size 1.27 0.9652)
					(thickness 0.000001)
				)
				(justify left)
			)
		)
		(property "Device Type" "REST0076"
			(at -0.148158 1.3462 180)
			(unlocked yes)
			(layer "F.Fab")
			(hide yes)
			(effects
				(font
					(size 1.27 0.9652)
					(thickness 0.000001)
				)
				(justify left)
			)
		)
		(duplicate_pad_numbers_are_jumpers no)
		(fp_poly
			(pts
				(xy 0.635 1.0668) (xy 0.635 -1.0668) (xy -0.635 -1.0668) (xy -0.635 1.0668)
			)
			(stroke
				(width 0)
				(type default)
			)
			(fill no)
			(layer "F.CrtYd")
		)
		(fp_line
			(start 0.254 -0.508)
			(end 0.254 0.508)
			(stroke
				(width 0.0254)
				(type default)
			)
			(layer "F.Fab")
		)
		(fp_line
			(start -0.254 -0.508)
			(end 0.254 -0.508)
			(stroke
				(width 0.0254)
				(type default)
			)
			(layer "F.Fab")
		)
		(fp_line
			(start 0.254 0.508)
			(end -0.254 0.508)
			(stroke
				(width 0.0254)
				(type default)
			)
			(layer "F.Fab")
		)
		(fp_line
			(start -0.254 0.508)
			(end -0.254 -0.508)
			(stroke
				(width 0.0254)
				(type default)
			)
			(layer "F.Fab")
		)
		(pad "1" smd rect
			(at 0 -0.4191 90)
			(size 0.508 0.5334)
			(layers "F.Cu" "F.Mask" "F.Paste")
			(net "10N2410")
		)
		(pad "2" smd rect
			(at 0 0.4191 90)
			(size 0.508 0.5334)
			(layers "F.Cu" "F.Mask" "F.Paste")
			(net "NFP_VDD_CORE_ISEN2_N")
		)
		(zone
			(layer "F.Cu")
			(hatch none 0.5)
			(connect_pads
				(clearance 0)
			)
			(min_thickness 0.25)
			(keepout
				(tracks not_allowed)
				(vias allowed)
				(pads allowed)
				(copperpour not_allowed)
				(footprints allowed)
			)
			(placement
				(enabled no)
				(sheetname "")
			)
			(fill
				(thermal_gap 0.5)
				(thermal_bridge_width 0.5)
				(island_removal_mode 0)
			)
			(polygon
				(pts
					(xy 36.2458 42.5196) (xy 36.2966 42.5196) (xy 36.2966 42.5704) (xy 36.2458 42.5704)
				)
			)
		)
	)
	(footprint ""
		(layer "F.Cu")
		(at 31.115 38.1)
		(property "Reference" "U10"
			(at 3.96367 2.667 90)
			(unlocked yes)
			(layer "F.SilkS")
			(effects
				(font
					(size 0.7874 0.5842)
					(thickness 0.127)
				)
				(justify left)
			)
		)
		(property "Value" "*"
			(at -0.2921 1.813154 0)
			(unlocked yes)
			(layer "F.Fab")
			(hide yes)
			(effects
				(font
					(size 0.7874 0.5842)
					(thickness 0.2032)
				)
				(justify left)
			)
		)
		(property "Device Type" "ICSO0124"
			(at -0.2921 1.813154 0)
			(unlocked yes)
			(layer "F.Fab")
			(hide yes)
			(effects
				(font
					(size 0.7874 0.5842)
					(thickness 0.2032)
				)
				(justify left)
			)
		)
		(duplicate_pad_numbers_are_jumpers no)
		(fp_line
			(start -3.302 -3.302)
			(end -3.302 -2.794)
			(stroke
				(width 0.1524)
				(type default)
			)
			(layer "F.SilkS")
		)
		(fp_line
			(start -3.302 -2.794)
			(end -2.794 -3.302)
			(stroke
				(width 0.1524)
				(type default)
			)
			(layer "F.SilkS")
		)
		(fp_line
			(start -3.302 -2.794)
			(end -2.794 -3.302)
			(stroke
				(width 0.1524)
				(type default)
			)
			(layer "F.SilkS")
		)
		(fp_line
			(start -2.794 -3.302)
			(end -3.302 -3.302)
			(stroke
				(width 0.1524)
				(type default)
			)
			(layer "F.SilkS")
		)
		(fp_line
			(start 3.302 2.794)
			(end 3.302 3.302)
			(stroke
				(width 0.1524)
				(type default)
			)
			(layer "F.SilkS")
		)
		(fp_line
			(start 3.302 3.302)
			(end 2.794 3.302)
			(stroke
				(width 0.1524)
				(type default)
			)
			(layer "F.SilkS")
		)
		(fp_arc
			(start -4.0894 -3.048)
			(mid -4.015005 -3.227605)
			(end -3.8354 -3.302)
			(stroke
				(width 0.1524)
				(type default)
			)
			(layer "F.SilkS")
		)
		(fp_arc
			(start -4.018788 -2.872257)
			(mid -4.071088 -2.953301)
			(end -4.0894 -3.048)
			(stroke
				(width 0.1524)
				(type default)
			)
			(layer "F.SilkS")
		)
		(fp_arc
			(start -3.8354 -3.302)
			(mid -3.655795 -3.227605)
			(end -3.5814 -3.048)
			(stroke
				(width 0.1524)
				(type default)
			)
			(layer "F.SilkS")
		)
		(fp_arc
			(start -3.5814 -3.048)
			(mid -3.596526 -2.961656)
			(end -3.640099 -2.885592)
			(stroke
				(width 0.1524)
				(type default)
			)
			(layer "F.SilkS")
		)
		(fp_circle
			(center -3.8354 -3.048)
			(end -3.5814 -3.048)
			(stroke
				(width 0.1524)
				(type default)
			)
			(fill no)
			(layer "F.SilkS")
		)
		(fp_poly
			(pts
				(xy -1.905 -0.8382) (xy -0.8382 -0.8382) (xy -0.8382 -1.905) (xy -1.905 -1.905)
			)
			(stroke
				(width 0)
				(type default)
			)
			(fill yes)
			(layer "F.Paste")
		)
		(fp_poly
			(pts
				(xy -1.905 0.5334) (xy -0.8382 0.5334) (xy -0.8382 -0.5334) (xy -1.905 -0.5334)
			)
			(stroke
				(width 0)
				(type default)
			)
			(fill yes)
			(layer "F.Paste")
		)
		(fp_poly
			(pts
				(xy -1.905 1.905) (xy -0.8382 1.905) (xy -0.8382 0.8382) (xy -1.905 0.8382)
			)
			(stroke
				(width 0)
				(type default)
			)
			(fill yes)
			(layer "F.Paste")
		)
		(fp_poly
			(pts
				(xy -0.5334 -0.8382) (xy 0.5334 -0.8382) (xy 0.5334 -1.905) (xy -0.5334 -1.905)
			)
			(stroke
				(width 0)
				(type default)
			)
			(fill yes)
			(layer "F.Paste")
		)
		(fp_poly
			(pts
				(xy -0.5334 0.5334) (xy 0.5334 0.5334) (xy 0.5334 -0.5334) (xy -0.5334 -0.5334)
			)
			(stroke
				(width 0)
				(type default)
			)
			(fill yes)
			(layer "F.Paste")
		)
		(fp_poly
			(pts
				(xy -0.5334 1.905) (xy 0.5334 1.905) (xy 0.5334 0.8382) (xy -0.5334 0.8382)
			)
			(stroke
				(width 0)
				(type default)
			)
			(fill yes)
			(layer "F.Paste")
		)
		(fp_poly
			(pts
				(xy 0.8382 -0.8382) (xy 1.905 -0.8382) (xy 1.905 -1.905) (xy 0.8382 -1.905)
			)
			(stroke
				(width 0)
				(type default)
			)
			(fill yes)
			(layer "F.Paste")
		)
		(fp_poly
			(pts
				(xy 0.8382 0.5334) (xy 1.905 0.5334) (xy 1.905 -0.5334) (xy 0.8382 -0.5334)
			)
			(stroke
				(width 0)
				(type default)
			)
			(fill yes)
			(layer "F.Paste")
		)
		(fp_poly
			(pts
				(xy 0.8382 1.905) (xy 1.905 1.905) (xy 1.905 0.8382) (xy 0.8382 0.8382)
			)
			(stroke
				(width 0)
				(type default)
			)
			(fill yes)
			(layer "F.Paste")
		)
		(fp_poly
			(pts
				(xy -3.937 2.54) (xy -3.937 -3.937) (xy 2.54 -3.937) (xy 3.937 -3.937) (xy 3.937 -2.54) (xy 3.937 3.937)
				(xy -2.54 3.937) (xy -3.937 3.937)
			)
			(stroke
				(width 0)
				(type default)
			)
			(fill no)
			(layer "F.CrtYd")
		)
		(fp_line
			(start -3.048 -3.048)
			(end -3.048 3.048)
			(stroke
				(width 0.1524)
				(type default)
			)
			(layer "F.Fab")
		)
		(fp_line
			(start -3.048 -2.413)
			(end -2.413 -3.048)
			(stroke
				(width 0.1524)
				(type default)
			)
			(layer "F.Fab")
		)
		(fp_line
			(start -3.048 3.048)
			(end 3.048 3.048)
			(stroke
				(width 0.1524)
				(type default)
			)
			(layer "F.Fab")
		)
		(fp_line
			(start 3.048 -3.048)
			(end -3.048 -3.048)
			(stroke
				(width 0.1524)
				(type default)
			)
			(layer "F.Fab")
		)
		(fp_line
			(start 3.048 3.048)
			(end 3.048 -3.048)
			(stroke
				(width 0.1524)
				(type default)
			)
			(layer "F.Fab")
		)
		(fp_circle
			(center -2.413 -2.286)
			(end -2.129003 -2.286)
			(stroke
				(width 0.1524)
				(type default)
			)
			(fill no)
			(layer "F.Fab")
		)
		(fp_text user "40"
			(at -2.667 -3.91033 0)
			(unlocked yes)
			(layer "F.SilkS")
			(effects
				(font
					(size 0.7874 0.5842)
					(thickness 0.127)
				)
				(justify left)
			)
		)
		(fp_text user "20"
			(at 2.286 3.83667 0)
			(unlocked yes)
			(layer "F.SilkS")
			(effects
				(font
					(size 0.7874 0.5842)
					(thickness 0.127)
				)
				(justify left)
			)
		)
		(pad "1" smd custom
			(at -2.9464 -2.250008 270)
			(size 0.06985 0.06985)
			(layers "F.Cu" "F.Mask" "F.Paste")
			(net "10N2412")
			(options
				(clearance outline)
				(anchor circle)
			)
			(primitives
				(gr_poly
					(pts
						(xy -0.1397 0.4064) (xy -0.1397 -0.3302) (xy -0.0635 -0.4064) (xy 0.1397 -0.4064) (xy 0.1397 0.4064)
					)
					(width 0)
					(fill yes)
				)
			)
		)
		(pad "2" smd rect
			(at -2.9464 -1.750009 270)
			(size 0.2794 0.8128)
			(layers "F.Cu" "F.Mask" "F.Paste")
			(net "CORE_FB_ALERT_L")
		)
		(pad "3" smd rect
			(at -2.9464 -1.25001 270)
			(size 0.2794 0.8128)
			(layers "F.Cu" "F.Mask" "F.Paste")
			(net "CORE_FB_FAULT_L")
		)
		(pad "4" smd rect
			(at -2.9464 -0.750011 270)
			(size 0.2794 0.8128)
			(layers "F.Cu" "F.Mask" "F.Paste")
			(net "PSU_I2C_SDA")
		)
		(pad "5" smd rect
			(at -2.9464 -0.250012 270)
			(size 0.2794 0.8128)
			(layers "F.Cu" "F.Mask" "F.Paste")
			(net "PSU_I2C_SCL")
		)
		(pad "6" smd rect
			(at -2.9464 0.250012 270)
			(size 0.2794 0.8128)
			(layers "F.Cu" "F.Mask" "F.Paste")
			(net "VDD_CORE_EN")
		)
		(pad "7" smd rect
			(at -2.9464 0.750011 270)
			(size 0.2794 0.8128)
			(layers "F.Cu" "F.Mask" "F.Paste")
			(net "GND")
		)
		(pad "8" smd rect
			(at -2.9464 1.25001 270)
			(size 0.2794 0.8128)
			(layers "F.Cu" "F.Mask" "F.Paste")
			(net "NFP_VDD_CORE_IMON")
		)
		(pad "9" smd rect
			(at -2.9464 1.750009 270)
			(size 0.2794 0.8128)
			(layers "F.Cu" "F.Mask" "F.Paste")
			(net "10N2411")
		)
		(pad "10" smd custom
			(at -2.9464 2.250008 270)
			(size 0.06985 0.06985)
			(layers "F.Cu" "F.Mask" "F.Paste")
			(net "10N2399")
			(options
				(clearance outline)
				(anchor circle)
			)
			(primitives
				(gr_poly
					(pts
						(xy 0.1397 0.4064) (xy 0.1397 -0.3302) (xy 0.0635 -0.4064) (xy -0.1397 -0.4064) (xy -0.1397 0.4064)
					)
					(width 0)
					(fill yes)
				)
			)
		)
		(pad "11" smd custom
			(at -2.250008 2.9464)
			(size 0.06985 0.06985)
			(layers "F.Cu" "F.Mask" "F.Paste")
			(net "10N2397")
			(options
				(clearance outline)
				(anchor circle)
			)
			(primitives
				(gr_poly
					(pts
						(xy -0.1397 0.4064) (xy -0.1397 -0.3302) (xy -0.0635 -0.4064) (xy 0.1397 -0.4064) (xy 0.1397 0.4064)
					)
					(width 0)
					(fill yes)
				)
			)
		)
		(pad "12" smd rect
			(at -1.750009 2.9464)
			(size 0.2794 0.8128)
			(layers "F.Cu" "F.Mask" "F.Paste")
			(net "10N2498")
		)
		(pad "13" smd rect
			(at -1.25001 2.9464)
			(size 0.2794 0.8128)
			(layers "F.Cu" "F.Mask" "F.Paste")
			(net "NFP_VDD_CORE_SENSE_VSS")
		)
		(pad "14" smd rect
			(at -0.750011 2.9464)
			(size 0.2794 0.8128)
			(layers "F.Cu" "F.Mask" "F.Paste")
			(net "10N2384")
		)
		(pad "15" smd rect
			(at -0.250012 2.9464)
			(size 0.2794 0.8128)
			(layers "F.Cu" "F.Mask" "F.Paste")
			(net "10N2504")
		)
		(pad "16" smd rect
			(at 0.250012 2.9464)
			(size 0.2794 0.8128)
			(layers "F.Cu" "F.Mask" "F.Paste")
			(net "10N2535")
		)
		(pad "17" smd rect
			(at 0.750011 2.9464)
			(size 0.2794 0.8128)
			(layers "F.Cu" "F.Mask" "F.Paste")
			(net "10N2528")
		)
		(pad "18" smd rect
			(at 1.25001 2.9464)
			(size 0.2794 0.8128)
			(layers "F.Cu" "F.Mask" "F.Paste")
			(net "NFP_VDD_CORE_TCOMPA")
		)
		(pad "19" smd rect
			(at 1.750009 2.9464)
			(size 0.2794 0.8128)
			(layers "F.Cu" "F.Mask" "F.Paste")
			(net "10N2381")
		)
		(pad "20" smd custom
			(at 2.250008 2.9464)
			(size 0.06985 0.06985)
			(layers "F.Cu" "F.Mask" "F.Paste")
			(net "VR_ODN_L")
			(options
				(clearance outline)
				(anchor circle)
			)
			(primitives
				(gr_poly
					(pts
						(xy 0.1397 0.4064) (xy 0.1397 -0.3302) (xy 0.0635 -0.4064) (xy -0.1397 -0.4064) (xy -0.1397 0.4064)
					)
					(width 0)
					(fill yes)
				)
			)
		)
		(pad "21" smd custom
			(at 2.9464 2.250008 90)
			(size 0.06985 0.06985)
			(layers "F.Cu" "F.Mask" "F.Paste")
			(net "VR_OD1_L")
			(options
				(clearance outline)
				(anchor circle)
			)
			(primitives
				(gr_poly
					(pts
						(xy -0.1397 0.4064) (xy -0.1397 -0.3302) (xy -0.0635 -0.4064) (xy 0.1397 -0.4064) (xy 0.1397 0.4064)
					)
					(width 0)
					(fill yes)
				)
			)
		)
		(pad "22" smd rect
			(at 2.9464 1.750009 90)
			(size 0.2794 0.8128)
			(layers "F.Cu" "F.Mask" "F.Paste")
			(net "_NC_NCP4200_SW4")
		)
		(pad "23" smd rect
			(at 2.9464 1.25001 90)
			(size 0.2794 0.8128)
			(layers "F.Cu" "F.Mask" "F.Paste")
			(net "_NC_NCP4200_SW3")
		)
		(pad "24" smd rect
			(at 2.9464 0.750011 90)
			(size 0.2794 0.8128)
			(layers "F.Cu" "F.Mask" "F.Paste")
			(net "_SW2")
		)
		(pad "25" smd rect
			(at 2.9464 0.250012 90)
			(size 0.2794 0.8128)
			(layers "F.Cu" "F.Mask" "F.Paste")
			(net "_SW1")
		)
		(pad "26" smd rect
			(at 2.9464 -0.250012 90)
			(size 0.2794 0.8128)
			(layers "F.Cu" "F.Mask" "F.Paste")
			(net "10N2403")
		)
		(pad "27" smd rect
			(at 2.9464 -0.750011 90)
			(size 0.2794 0.8128)
			(layers "F.Cu" "F.Mask" "F.Paste")
			(net "10N2409")
		)
		(pad "28" smd rect
			(at 2.9464 -1.25001 90)
			(size 0.2794 0.8128)
			(layers "F.Cu" "F.Mask" "F.Paste")
			(net "NFP_CORE_PWM2")
		)
		(pad "29" smd rect
			(at 2.9464 -1.750009 90)
			(size 0.2794 0.8128)
			(layers "F.Cu" "F.Mask" "F.Paste")
			(net "NFP_CORE_PWM1")
		)
		(pad "30" smd custom
			(at 2.9464 -2.250008 90)
			(size 0.06985 0.06985)
			(layers "F.Cu" "F.Mask" "F.Paste")
			(net "10N2370")
			(options
				(clearance outline)
				(anchor circle)
			)
			(primitives
				(gr_poly
					(pts
						(xy 0.1397 0.4064) (xy 0.1397 -0.3302) (xy 0.0635 -0.4064) (xy -0.1397 -0.4064) (xy -0.1397 0.4064)
					)
					(width 0)
					(fill yes)
				)
			)
		)
		(pad "31" smd custom
			(at 2.250008 -2.9464 180)
			(size 0.06985 0.06985)
			(layers "F.Cu" "F.Mask" "F.Paste")
			(net "_NFP_CORE_VID7")
			(options
				(clearance outline)
				(anchor circle)
			)
			(primitives
				(gr_poly
					(pts
						(xy -0.1397 0.4064) (xy -0.1397 -0.3302) (xy -0.0635 -0.4064) (xy 0.1397 -0.4064) (xy 0.1397 0.4064)
					)
					(width 0)
					(fill yes)
				)
			)
		)
		(pad "32" smd rect
			(at 1.750009 -2.9464 180)
			(size 0.2794 0.8128)
			(layers "F.Cu" "F.Mask" "F.Paste")
			(net "_NFP_CORE_VID6")
		)
		(pad "33" smd rect
			(at 1.25001 -2.9464 180)
			(size 0.2794 0.8128)
			(layers "F.Cu" "F.Mask" "F.Paste")
			(net "_NFP_CORE_VID5")
		)
		(pad "34" smd rect
			(at 0.750011 -2.9464 180)
			(size 0.2794 0.8128)
			(layers "F.Cu" "F.Mask" "F.Paste")
			(net "_NFP_CORE_VID4")
		)
		(pad "35" smd rect
			(at 0.250012 -2.9464 180)
			(size 0.2794 0.8128)
			(layers "F.Cu" "F.Mask" "F.Paste")
			(net "_NFP_CORE_VID3")
		)
		(pad "36" smd rect
			(at -0.250012 -2.9464 180)
			(size 0.2794 0.8128)
			(layers "F.Cu" "F.Mask" "F.Paste")
			(net "_NFP_CORE_VID2")
		)
		(pad "37" smd rect
			(at -0.750011 -2.9464 180)
			(size 0.2794 0.8128)
			(layers "F.Cu" "F.Mask" "F.Paste")
			(net "_NFP_CORE_VID1")
		)
		(pad "38" smd rect
			(at -1.25001 -2.9464 180)
			(size 0.2794 0.8128)
			(layers "F.Cu" "F.Mask" "F.Paste")
			(net "_NFP_CORE_VID0")
		)
		(pad "39" smd rect
			(at -1.750009 -2.9464 180)
			(size 0.2794 0.8128)
			(layers "F.Cu" "F.Mask" "F.Paste")
			(net "CPLD_CORE_PSI_L")
		)
		(pad "40" smd custom
			(at -2.250008 -2.9464 180)
			(size 0.06985 0.06985)
			(layers "F.Cu" "F.Mask" "F.Paste")
			(net "VDD_CORE_PGOOD")
			(options
				(clearance outline)
				(anchor circle)
			)
			(primitives
				(gr_poly
					(pts
						(xy 0.1397 0.4064) (xy 0.1397 -0.3302) (xy 0.0635 -0.4064) (xy -0.1397 -0.4064) (xy -0.1397 0.4064)
					)
					(width 0)
					(fill yes)
				)
			)
		)
		(pad "41" smd rect
			(at 0 0 90)
			(size 4.191 4.191)
			(layers "F.Cu" "F.Mask" "F.Paste")
			(net "GND")
		)
		(zone
			(layer "F.Cu")
			(hatch none 0.5)
			(connect_pads
				(clearance 0)
			)
			(min_thickness 0.25)
			(keepout
				(tracks allowed)
				(vias not_allowed)
				(pads allowed)
				(copperpour not_allowed)
				(footprints allowed)
			)
			(placement
				(enabled no)
				(sheetname "")
			)
			(fill
				(thermal_gap 0.5)
				(thermal_bridge_width 0.5)
				(island_removal_mode 0)
			)
			(polygon
				(pts
					(arc
						(start 27.6098 35.052)
						(mid 26.9494 35.052)
						(end 27.6098 35.052)
					)
				)
			)
		)
	)
	(footprint ""
		(layer "F.Cu")
		(at 20.955 29.337)
		(property "Reference" "R71"
			(at 0 0 0)
			(layer "F.SilkS")
			(hide yes)
			(effects
				(font
					(size 1.27 1.27)
				)
			)
		)
		(property "Value" "4.75K"
			(at -0.148158 1.3462 90)
			(unlocked yes)
			(layer "F.Fab")
			(hide yes)
			(effects
				(font
					(size 1.27 0.9652)
					(thickness 0.000001)
				)
				(justify left)
			)
		)
		(property "Device Type" "REST4024"
			(at -0.148158 1.3462 90)
			(unlocked yes)
			(layer "F.Fab")
			(hide yes)
			(effects
				(font
					(size 1.27 0.9652)
					(thickness 0.000001)
				)
				(justify left)
			)
		)
		(duplicate_pad_numbers_are_jumpers no)
		(fp_poly
			(pts
				(xy 0.635 1.0668) (xy 0.635 -1.0668) (xy -0.635 -1.0668) (xy -0.635 1.0668)
			)
			(stroke
				(width 0)
				(type default)
			)
			(fill no)
			(layer "F.CrtYd")
		)
		(fp_line
			(start -0.254 -0.508)
			(end 0.254 -0.508)
			(stroke
				(width 0.0254)
				(type default)
			)
			(layer "F.Fab")
		)
		(fp_line
			(start -0.254 0.508)
			(end -0.254 -0.508)
			(stroke
				(width 0.0254)
				(type default)
			)
			(layer "F.Fab")
		)
		(fp_line
			(start 0.254 -0.508)
			(end 0.254 0.508)
			(stroke
				(width 0.0254)
				(type default)
			)
			(layer "F.Fab")
		)
		(fp_line
			(start 0.254 0.508)
			(end -0.254 0.508)
			(stroke
				(width 0.0254)
				(type default)
			)
			(layer "F.Fab")
		)
		(pad "1" smd rect
			(at 0 -0.4191)
			(size 0.508 0.5334)
			(layers "F.Cu" "F.Mask" "F.Paste")
			(net "EXT_3.3V")
		)
		(pad "2" smd rect
			(at 0 0.4191)
			(size 0.508 0.5334)
			(layers "F.Cu" "F.Mask" "F.Paste")
			(net "DEBUG_CPLD_PGRM_JTAG_TDI")
		)
		(zone
			(layer "F.Cu")
			(hatch none 0.5)
			(connect_pads
				(clearance 0)
			)
			(min_thickness 0.25)
			(keepout
				(tracks not_allowed)
				(vias allowed)
				(pads allowed)
				(copperpour not_allowed)
				(footprints allowed)
			)
			(placement
				(enabled no)
				(sheetname "")
			)
			(fill
				(thermal_gap 0.5)
				(thermal_bridge_width 0.5)
				(island_removal_mode 0)
			)
			(polygon
				(pts
					(xy 20.9804 29.3116) (xy 20.9804 29.3624) (xy 20.9296 29.3624) (xy 20.9296 29.3116)
				)
			)
		)
	)
	(footprint ""
		(layer "F.Cu")
		(at 58.928 49.784 180)
		(property "Reference" "L21"
			(at 3.175 3.27533 0)
			(unlocked yes)
			(layer "F.SilkS")
			(effects
				(font
					(size 0.7874 0.5842)
					(thickness 0.127)
				)
				(justify left)
			)
		)
		(property "Value" "3.3UH"
			(at -0.4826 -0.14732 180)
			(unlocked yes)
			(layer "F.Fab")
			(hide yes)
			(effects
				(font
					(size 1.27 0.9652)
					(thickness 0.000001)
				)
				(justify left)
			)
		)
		(property "Device Type" "INDS0062"
			(at -0.4826 -0.14732 180)
			(unlocked yes)
			(layer "F.Fab")
			(hide yes)
			(effects
				(font
					(size 1.27 0.9652)
					(thickness 0.000001)
				)
				(justify left)
			)
		)
		(duplicate_pad_numbers_are_jumpers no)
		(fp_line
			(start 2.413 2.413)
			(end 0.1397 2.413)
			(stroke
				(width 0.1524)
				(type default)
			)
			(layer "F.SilkS")
		)
		(fp_line
			(start 2.413 2.413)
			(end -2.413 2.413)
			(stroke
				(width 0.1524)
				(type default)
			)
			(layer "F.SilkS")
		)
		(fp_line
			(start 2.413 -2.413)
			(end 2.413 2.413)
			(stroke
				(width 0.1524)
				(type default)
			)
			(layer "F.SilkS")
		)
		(fp_line
			(start -0.5334 -2.413)
			(end 0.2794 -2.413)
			(stroke
				(width 0.1524)
				(type default)
			)
			(layer "F.SilkS")
		)
		(fp_line
			(start -1.0287 2.413)
			(end -2.413 2.413)
			(stroke
				(width 0.1524)
				(type default)
			)
			(layer "F.SilkS")
		)
		(fp_line
			(start -2.413 2.413)
			(end -2.413 -1.970126)
			(stroke
				(width 0.1524)
				(type default)
			)
			(layer "F.SilkS")
		)
		(fp_line
			(start -2.413 2.413)
			(end -2.413 -2.413)
			(stroke
				(width 0.1524)
				(type default)
			)
			(layer "F.SilkS")
		)
		(fp_line
			(start -2.413 -2.413)
			(end 2.413 -2.413)
			(stroke
				(width 0.1524)
				(type default)
			)
			(layer "F.SilkS")
		)
		(fp_poly
			(pts
				(xy -2.54 2.54) (xy 2.54 2.54) (xy 2.54 -2.54) (xy -2.54 -2.54)
			)
			(stroke
				(width 0)
				(type default)
			)
			(fill no)
			(layer "F.CrtYd")
		)
		(fp_line
			(start 2.1463 2.1463)
			(end 2.1463 -2.1463)
			(stroke
				(width 0.1524)
				(type default)
			)
			(layer "F.Fab")
		)
		(fp_line
			(start 2.1463 -2.1463)
			(end -2.1463 -2.1463)
			(stroke
				(width 0.1524)
				(type default)
			)
			(layer "F.Fab")
		)
		(fp_line
			(start -2.1463 2.1463)
			(end 2.1463 2.1463)
			(stroke
				(width 0.1524)
				(type default)
			)
			(layer "F.Fab")
		)
		(fp_line
			(start -2.1463 -2.1463)
			(end -2.1463 2.1463)
			(stroke
				(width 0.1524)
				(type default)
			)
			(layer "F.Fab")
		)
		(pad "1" smd rect
			(at -1.2192 0 180)
			(size 1.3716 3.5814)
			(layers "F.Cu" "F.Mask" "F.Paste")
			(net "11N1952")
		)
		(pad "2" smd rect
			(at 1.2192 0 180)
			(size 1.3716 3.5814)
			(layers "F.Cu" "F.Mask" "F.Paste")
			(net "VDD_5.0V")
		)
	)
	(footprint ""
		(layer "F.Cu")
		(at 20.193 35.687 180)
		(property "Reference" "R62"
			(at 0.73533 -1.5875 90)
			(unlocked yes)
			(layer "F.SilkS")
			(effects
				(font
					(size 0.7874 0.5842)
					(thickness 0.127)
				)
				(justify left)
			)
		)
		(property "Value" "4.75K"
			(at -0.148158 1.3462 270)
			(unlocked yes)
			(layer "F.Fab")
			(hide yes)
			(effects
				(font
					(size 1.27 0.9652)
					(thickness 0.000001)
				)
				(justify left)
			)
		)
		(property "Device Type" "REST4024"
			(at -0.148158 1.3462 270)
			(unlocked yes)
			(layer "F.Fab")
			(hide yes)
			(effects
				(font
					(size 1.27 0.9652)
					(thickness 0.000001)
				)
				(justify left)
			)
		)
		(duplicate_pad_numbers_are_jumpers no)
		(fp_poly
			(pts
				(xy 0.635 1.0668) (xy 0.635 -1.0668) (xy -0.635 -1.0668) (xy -0.635 1.0668)
			)
			(stroke
				(width 0)
				(type default)
			)
			(fill no)
			(layer "F.CrtYd")
		)
		(fp_line
			(start 0.254 0.508)
			(end -0.254 0.508)
			(stroke
				(width 0.0254)
				(type default)
			)
			(layer "F.Fab")
		)
		(fp_line
			(start 0.254 -0.508)
			(end 0.254 0.508)
			(stroke
				(width 0.0254)
				(type default)
			)
			(layer "F.Fab")
		)
		(fp_line
			(start -0.254 0.508)
			(end -0.254 -0.508)
			(stroke
				(width 0.0254)
				(type default)
			)
			(layer "F.Fab")
		)
		(fp_line
			(start -0.254 -0.508)
			(end 0.254 -0.508)
			(stroke
				(width 0.0254)
				(type default)
			)
			(layer "F.Fab")
		)
		(pad "1" smd rect
			(at 0 -0.4191 180)
			(size 0.508 0.5334)
			(layers "F.Cu" "F.Mask" "F.Paste")
			(net "EXT_3.3V")
		)
		(pad "2" smd rect
			(at 0 0.4191 180)
			(size 0.508 0.5334)
			(layers "F.Cu" "F.Mask" "F.Paste")
			(net "CPLD_PGRM_JTAG_TDO")
		)
		(zone
			(layer "F.Cu")
			(hatch none 0.5)
			(connect_pads
				(clearance 0)
			)
			(min_thickness 0.25)
			(keepout
				(tracks not_allowed)
				(vias allowed)
				(pads allowed)
				(copperpour not_allowed)
				(footprints allowed)
			)
			(placement
				(enabled no)
				(sheetname "")
			)
			(fill
				(thermal_gap 0.5)
				(thermal_bridge_width 0.5)
				(island_removal_mode 0)
			)
			(polygon
				(pts
					(xy 20.1676 35.7124) (xy 20.1676 35.6616) (xy 20.2184 35.6616) (xy 20.2184 35.7124)
				)
			)
		)
	)
	(footprint ""
		(layer "F.Cu")
		(at 5.334 23.6728 180)
		(property "Reference" "C242"
			(at 6.45033 2.4638 90)
			(unlocked yes)
			(layer "F.SilkS")
			(effects
				(font
					(size 0.7874 0.5842)
					(thickness 0.127)
				)
				(justify left)
			)
		)
		(property "Value" "220UF"
			(at -0.4826 1.37668 180)
			(unlocked yes)
			(layer "F.Fab")
			(hide yes)
			(effects
				(font
					(size 1.27 0.9652)
					(thickness 0.000001)
				)
				(justify left)
			)
		)
		(property "Device Type" "CAPE0005"
			(at -0.4826 1.37668 180)
			(unlocked yes)
			(layer "F.Fab")
			(hide yes)
			(effects
				(font
					(size 1.27 0.9652)
					(thickness 0.000001)
				)
				(justify left)
			)
		)
		(duplicate_pad_numbers_are_jumpers no)
		(fp_line
			(start 5.588 5.588)
			(end 5.588 -3.302)
			(stroke
				(width 0.2032)
				(type default)
			)
			(layer "F.SilkS")
		)
		(fp_line
			(start 5.588 5.588)
			(end 5.588 -3.302)
			(stroke
				(width 0.2032)
				(type default)
			)
			(layer "F.SilkS")
		)
		(fp_line
			(start 5.588 -3.302)
			(end 3.302 -5.588)
			(stroke
				(width 0.2032)
				(type default)
			)
			(layer "F.SilkS")
		)
		(fp_line
			(start 5.588 -3.302)
			(end 3.302 -5.588)
			(stroke
				(width 0.2032)
				(type default)
			)
			(layer "F.SilkS")
		)
		(fp_line
			(start 3.302 -5.588)
			(end 1.640637 -5.588)
			(stroke
				(width 0.2032)
				(type default)
			)
			(layer "F.SilkS")
		)
		(fp_line
			(start 3.302 -5.588)
			(end 1.27 -5.588)
			(stroke
				(width 0.2032)
				(type default)
			)
			(layer "F.SilkS")
		)
		(fp_line
			(start 2.2606 -7.0104)
			(end 2.2606 -5.7404)
			(stroke
				(width 0.2032)
				(type default)
			)
			(layer "F.SilkS")
		)
		(fp_line
			(start 2.2606 -7.0104)
			(end 2.2606 -5.7404)
			(stroke
				(width 0.2032)
				(type default)
			)
			(layer "F.SilkS")
		)
		(fp_line
			(start 2.001825 -6.3754)
			(end 2.8956 -6.3754)
			(stroke
				(width 0.2032)
				(type default)
			)
			(layer "F.SilkS")
		)
		(fp_line
			(start 1.6256 -6.3754)
			(end 2.8956 -6.3754)
			(stroke
				(width 0.2032)
				(type default)
			)
			(layer "F.SilkS")
		)
		(fp_line
			(start 1.3081 5.588)
			(end 5.588 5.588)
			(stroke
				(width 0.2032)
				(type default)
			)
			(layer "F.SilkS")
		)
		(fp_line
			(start 1.27 5.588)
			(end 5.588 5.588)
			(stroke
				(width 0.2032)
				(type default)
			)
			(layer "F.SilkS")
		)
		(fp_line
			(start -1.27 -5.588)
			(end -3.302 -5.588)
			(stroke
				(width 0.2032)
				(type default)
			)
			(layer "F.SilkS")
		)
		(fp_line
			(start -1.3081 -5.588)
			(end -3.302 -5.588)
			(stroke
				(width 0.2032)
				(type default)
			)
			(layer "F.SilkS")
		)
		(fp_line
			(start -3.302 -5.588)
			(end -4.736389 -4.153611)
			(stroke
				(width 0.2032)
				(type default)
			)
			(layer "F.SilkS")
		)
		(fp_line
			(start -3.302 -5.588)
			(end -5.588 -3.302)
			(stroke
				(width 0.2032)
				(type default)
			)
			(layer "F.SilkS")
		)
		(fp_line
			(start -5.588 5.588)
			(end -1.27 5.588)
			(stroke
				(width 0.2032)
				(type default)
			)
			(layer "F.SilkS")
		)
		(fp_line
			(start -5.588 -3.302)
			(end -5.588 5.588)
			(stroke
				(width 0.2032)
				(type default)
			)
			(layer "F.SilkS")
		)
		(fp_line
			(start -5.588 -3.302)
			(end -5.588 5.588)
			(stroke
				(width 0.2032)
				(type default)
			)
			(layer "F.SilkS")
		)
		(fp_poly
			(pts
				(xy -5.7912 -5.842) (xy -1.524 -5.842) (xy -1.524 -7.112) (xy 1.524 -7.112) (xy 1.524 -5.842) (xy 5.254168 -5.842)
				(xy 5.254168 5.842) (xy 1.524 5.842) (xy 1.524 7.112) (xy -1.524 7.112) (xy -1.524 5.842) (xy -5.7912 5.842)
			)
			(stroke
				(width 0)
				(type default)
			)
			(fill no)
			(layer "F.CrtYd")
		)
		(fp_line
			(start 5.2578 5.2578)
			(end 5.2578 -3.2258)
			(stroke
				(width 0.2032)
				(type default)
			)
			(layer "F.Fab")
		)
		(fp_line
			(start 5.2578 -3.2258)
			(end 3.2258 -5.2578)
			(stroke
				(width 0.2032)
				(type default)
			)
			(layer "F.Fab")
		)
		(fp_line
			(start 3.2258 -5.2578)
			(end -3.2258 -5.2578)
			(stroke
				(width 0.2032)
				(type default)
			)
			(layer "F.Fab")
		)
		(fp_line
			(start 0.635 -3.937)
			(end -0.635 -3.937)
			(stroke
				(width 0.2032)
				(type default)
			)
			(layer "F.Fab")
		)
		(fp_line
			(start 0 -4.572)
			(end 0 -3.302)
			(stroke
				(width 0.2032)
				(type default)
			)
			(layer "F.Fab")
		)
		(fp_line
			(start -3.2258 -5.2578)
			(end -5.2578 -3.2258)
			(stroke
				(width 0.2032)
				(type default)
			)
			(layer "F.Fab")
		)
		(fp_line
			(start -5.2578 5.2578)
			(end 5.2578 5.2578)
			(stroke
				(width 0.2032)
				(type default)
			)
			(layer "F.Fab")
		)
		(fp_line
			(start -5.2578 -3.2258)
			(end -5.2578 5.2578)
			(stroke
				(width 0.2032)
				(type default)
			)
			(layer "F.Fab")
		)
		(pad "1" smd rect
			(at 0 -4.3561 180)
			(size 1.905 4.4196)
			(layers "F.Cu" "F.Mask" "F.Paste")
			(net "EXT_12.0V")
		)
		(pad "2" smd rect
			(at 0 4.3561 180)
			(size 1.905 4.4196)
			(layers "F.Cu" "F.Mask" "F.Paste")
			(net "GND")
		)
	)
	(footprint ""
		(layer "F.Cu")
		(at 27.051 12.827 -90)
		(property "Reference" "R139"
			(at 0 0 270)
			(layer "F.SilkS")
			(hide yes)
			(effects
				(font
					(size 1.27 1.27)
				)
			)
		)
		(property "Value" "0"
			(at -0.148158 1.3462 0)
			(unlocked yes)
			(layer "F.Fab")
			(hide yes)
			(effects
				(font
					(size 1.27 0.9652)
					(thickness 0.000001)
				)
				(justify left)
			)
		)
		(property "Device Type" "REST1111"
			(at -0.148158 1.3462 0)
			(unlocked yes)
			(layer "F.Fab")
			(hide yes)
			(effects
				(font
					(size 1.27 0.9652)
					(thickness 0.000001)
				)
				(justify left)
			)
		)
		(duplicate_pad_numbers_are_jumpers no)
		(fp_poly
			(pts
				(xy 0.635 1.0668) (xy 0.635 -1.0668) (xy -0.635 -1.0668) (xy -0.635 1.0668)
			)
			(stroke
				(width 0)
				(type default)
			)
			(fill no)
			(layer "F.CrtYd")
		)
		(fp_line
			(start -0.254 0.508)
			(end -0.254 -0.508)
			(stroke
				(width 0.0254)
				(type default)
			)
			(layer "F.Fab")
		)
		(fp_line
			(start 0.254 0.508)
			(end -0.254 0.508)
			(stroke
				(width 0.0254)
				(type default)
			)
			(layer "F.Fab")
		)
		(fp_line
			(start -0.254 -0.508)
			(end 0.254 -0.508)
			(stroke
				(width 0.0254)
				(type default)
			)
			(layer "F.Fab")
		)
		(fp_line
			(start 0.254 -0.508)
			(end 0.254 0.508)
			(stroke
				(width 0.0254)
				(type default)
			)
			(layer "F.Fab")
		)
		(pad "1" smd rect
			(at 0 -0.4191 270)
			(size 0.508 0.5334)
			(layers "F.Cu" "F.Mask" "F.Paste")
			(net "_PSU_I2C_SDA")
		)
		(pad "2" smd rect
			(at 0 0.4191 270)
			(size 0.508 0.5334)
			(layers "F.Cu" "F.Mask" "F.Paste")
			(net "PSU_I2C_SDA")
		)
		(zone
			(layer "F.Cu")
			(hatch none 0.5)
			(connect_pads
				(clearance 0)
			)
			(min_thickness 0.25)
			(keepout
				(tracks not_allowed)
				(vias allowed)
				(pads allowed)
				(copperpour not_allowed)
				(footprints allowed)
			)
			(placement
				(enabled no)
				(sheetname "")
			)
			(fill
				(thermal_gap 0.5)
				(thermal_bridge_width 0.5)
				(island_removal_mode 0)
			)
			(polygon
				(pts
					(xy 27.0764 12.8524) (xy 27.0256 12.8524) (xy 27.0256 12.8016) (xy 27.0764 12.8016)
				)
			)
		)
	)
	(footprint ""
		(layer "F.Cu")
		(at 76.327 11.557 180)
		(property "Reference" "R361"
			(at -0.15367 -1.905 90)
			(unlocked yes)
			(layer "F.SilkS")
			(effects
				(font
					(size 0.7874 0.5842)
					(thickness 0.127)
				)
				(justify left)
			)
		)
		(property "Value" "100"
			(at -0.148158 1.3462 270)
			(unlocked yes)
			(layer "F.Fab")
			(hide yes)
			(effects
				(font
					(size 1.27 0.9652)
					(thickness 0.000001)
				)
				(justify left)
			)
		)
		(property "Device Type" "REST4030"
			(at -0.148158 1.3462 270)
			(unlocked yes)
			(layer "F.Fab")
			(hide yes)
			(effects
				(font
					(size 1.27 0.9652)
					(thickness 0.000001)
				)
				(justify left)
			)
		)
		(duplicate_pad_numbers_are_jumpers no)
		(fp_poly
			(pts
				(xy 0.635 1.0668) (xy 0.635 -1.0668) (xy -0.635 -1.0668) (xy -0.635 1.0668)
			)
			(stroke
				(width 0)
				(type default)
			)
			(fill no)
			(layer "F.CrtYd")
		)
		(fp_line
			(start 0.254 0.508)
			(end -0.254 0.508)
			(stroke
				(width 0.0254)
				(type default)
			)
			(layer "F.Fab")
		)
		(fp_line
			(start 0.254 -0.508)
			(end 0.254 0.508)
			(stroke
				(width 0.0254)
				(type default)
			)
			(layer "F.Fab")
		)
		(fp_line
			(start -0.254 0.508)
			(end -0.254 -0.508)
			(stroke
				(width 0.0254)
				(type default)
			)
			(layer "F.Fab")
		)
		(fp_line
			(start -0.254 -0.508)
			(end 0.254 -0.508)
			(stroke
				(width 0.0254)
				(type default)
			)
			(layer "F.Fab")
		)
		(pad "1" smd rect
			(at 0 -0.4191 180)
			(size 0.508 0.5334)
			(layers "F.Cu" "F.Mask" "F.Paste")
			(net "GND")
		)
		(pad "2" smd rect
			(at 0 0.4191 180)
			(size 0.508 0.5334)
			(layers "F.Cu" "F.Mask" "F.Paste")
			(net "DDR0_32A_VREF1B")
		)
		(zone
			(layer "F.Cu")
			(hatch none 0.5)
			(connect_pads
				(clearance 0)
			)
			(min_thickness 0.25)
			(keepout
				(tracks not_allowed)
				(vias allowed)
				(pads allowed)
				(copperpour not_allowed)
				(footprints allowed)
			)
			(placement
				(enabled no)
				(sheetname "")
			)
			(fill
				(thermal_gap 0.5)
				(thermal_bridge_width 0.5)
				(island_removal_mode 0)
			)
			(polygon
				(pts
					(xy 76.3016 11.5824) (xy 76.3016 11.5316) (xy 76.3524 11.5316) (xy 76.3524 11.5824)
				)
			)
		)
	)
	(footprint ""
		(layer "F.Cu")
		(at 27.178 10.414 -90)
		(property "Reference" "R262"
			(at 0 0 270)
			(layer "F.SilkS")
			(hide yes)
			(effects
				(font
					(size 1.27 1.27)
				)
			)
		)
		(property "Value" "39.0"
			(at -0.148158 1.3462 0)
			(unlocked yes)
			(layer "F.Fab")
			(hide yes)
			(effects
				(font
					(size 1.27 0.9652)
					(thickness 0.000001)
				)
				(justify left)
			)
		)
		(property "Device Type" "REST0108"
			(at -0.148158 1.3462 0)
			(unlocked yes)
			(layer "F.Fab")
			(hide yes)
			(effects
				(font
					(size 1.27 0.9652)
					(thickness 0.000001)
				)
				(justify left)
			)
		)
		(duplicate_pad_numbers_are_jumpers no)
		(fp_poly
			(pts
				(xy 0.635 1.0668) (xy 0.635 -1.0668) (xy -0.635 -1.0668) (xy -0.635 1.0668)
			)
			(stroke
				(width 0)
				(type default)
			)
			(fill no)
			(layer "F.CrtYd")
		)
		(fp_line
			(start -0.254 0.508)
			(end -0.254 -0.508)
			(stroke
				(width 0.0254)
				(type default)
			)
			(layer "F.Fab")
		)
		(fp_line
			(start 0.254 0.508)
			(end -0.254 0.508)
			(stroke
				(width 0.0254)
				(type default)
			)
			(layer "F.Fab")
		)
		(fp_line
			(start -0.254 -0.508)
			(end 0.254 -0.508)
			(stroke
				(width 0.0254)
				(type default)
			)
			(layer "F.Fab")
		)
		(fp_line
			(start 0.254 -0.508)
			(end 0.254 0.508)
			(stroke
				(width 0.0254)
				(type default)
			)
			(layer "F.Fab")
		)
		(pad "1" smd rect
			(at 0 -0.4191 270)
			(size 0.508 0.5334)
			(layers "F.Cu" "F.Mask" "F.Paste")
			(net "_PGRM_JTAG_TDO")
		)
		(pad "2" smd rect
			(at 0 0.4191 270)
			(size 0.508 0.5334)
			(layers "F.Cu" "F.Mask" "F.Paste")
			(net "PGRM_JTAG_TDO")
		)
		(zone
			(layer "F.Cu")
			(hatch none 0.5)
			(connect_pads
				(clearance 0)
			)
			(min_thickness 0.25)
			(keepout
				(tracks not_allowed)
				(vias allowed)
				(pads allowed)
				(copperpour not_allowed)
				(footprints allowed)
			)
			(placement
				(enabled no)
				(sheetname "")
			)
			(fill
				(thermal_gap 0.5)
				(thermal_bridge_width 0.5)
				(island_removal_mode 0)
			)
			(polygon
				(pts
					(xy 27.2034 10.4394) (xy 27.1526 10.4394) (xy 27.1526 10.3886) (xy 27.2034 10.3886)
				)
			)
		)
	)
	(footprint ""
		(layer "F.Cu")
		(at 35.941 8.636 90)
		(property "Reference" "R134"
			(at 0 0 90)
			(layer "F.SilkS")
			(hide yes)
			(effects
				(font
					(size 1.27 1.27)
				)
			)
		)
		(property "Value" "0"
			(at -0.148158 1.3462 180)
			(unlocked yes)
			(layer "F.Fab")
			(hide yes)
			(effects
				(font
					(size 1.27 0.9652)
					(thickness 0.000001)
				)
				(justify left)
			)
		)
		(property "Device Type" "REST1111"
			(at -0.148158 1.3462 180)
			(unlocked yes)
			(layer "F.Fab")
			(hide yes)
			(effects
				(font
					(size 1.27 0.9652)
					(thickness 0.000001)
				)
				(justify left)
			)
		)
		(duplicate_pad_numbers_are_jumpers no)
		(fp_poly
			(pts
				(xy 0.635 1.0668) (xy 0.635 -1.0668) (xy -0.635 -1.0668) (xy -0.635 1.0668)
			)
			(stroke
				(width 0)
				(type default)
			)
			(fill no)
			(layer "F.CrtYd")
		)
		(fp_line
			(start 0.254 -0.508)
			(end 0.254 0.508)
			(stroke
				(width 0.0254)
				(type default)
			)
			(layer "F.Fab")
		)
		(fp_line
			(start -0.254 -0.508)
			(end 0.254 -0.508)
			(stroke
				(width 0.0254)
				(type default)
			)
			(layer "F.Fab")
		)
		(fp_line
			(start 0.254 0.508)
			(end -0.254 0.508)
			(stroke
				(width 0.0254)
				(type default)
			)
			(layer "F.Fab")
		)
		(fp_line
			(start -0.254 0.508)
			(end -0.254 -0.508)
			(stroke
				(width 0.0254)
				(type default)
			)
			(layer "F.Fab")
		)
		(pad "1" smd rect
			(at 0 -0.4191 90)
			(size 0.508 0.5334)
			(layers "F.Cu" "F.Mask" "F.Paste")
			(net "3N2302")
		)
		(pad "2" smd rect
			(at 0 0.4191 90)
			(size 0.508 0.5334)
			(layers "F.Cu" "F.Mask" "F.Paste")
			(net "NFP_CLK_REF_P")
		)
		(zone
			(layer "F.Cu")
			(hatch none 0.5)
			(connect_pads
				(clearance 0)
			)
			(min_thickness 0.25)
			(keepout
				(tracks not_allowed)
				(vias allowed)
				(pads allowed)
				(copperpour not_allowed)
				(footprints allowed)
			)
			(placement
				(enabled no)
				(sheetname "")
			)
			(fill
				(thermal_gap 0.5)
				(thermal_bridge_width 0.5)
				(island_removal_mode 0)
			)
			(polygon
				(pts
					(xy 35.9156 8.6106) (xy 35.9664 8.6106) (xy 35.9664 8.6614) (xy 35.9156 8.6614)
				)
			)
		)
	)
	(footprint ""
		(layer "F.Cu")
		(at 81.915 26.924)
		(property "Reference" "R206"
			(at 0 0 0)
			(layer "F.SilkS")
			(hide yes)
			(effects
				(font
					(size 1.27 1.27)
				)
			)
		)
		(property "Value" "39.0"
			(at -0.148158 1.3462 90)
			(unlocked yes)
			(layer "F.Fab")
			(hide yes)
			(effects
				(font
					(size 1.27 0.9652)
					(thickness 0.000001)
				)
				(justify left)
			)
		)
		(property "Device Type" "REST0108"
			(at -0.148158 1.3462 90)
			(unlocked yes)
			(layer "F.Fab")
			(hide yes)
			(effects
				(font
					(size 1.27 0.9652)
					(thickness 0.000001)
				)
				(justify left)
			)
		)
		(duplicate_pad_numbers_are_jumpers no)
		(fp_poly
			(pts
				(xy 0.635 1.0668) (xy 0.635 -1.0668) (xy -0.635 -1.0668) (xy -0.635 1.0668)
			)
			(stroke
				(width 0)
				(type default)
			)
			(fill no)
			(layer "F.CrtYd")
		)
		(fp_line
			(start -0.254 -0.508)
			(end 0.254 -0.508)
			(stroke
				(width 0.0254)
				(type default)
			)
			(layer "F.Fab")
		)
		(fp_line
			(start -0.254 0.508)
			(end -0.254 -0.508)
			(stroke
				(width 0.0254)
				(type default)
			)
			(layer "F.Fab")
		)
		(fp_line
			(start 0.254 -0.508)
			(end 0.254 0.508)
			(stroke
				(width 0.0254)
				(type default)
			)
			(layer "F.Fab")
		)
		(fp_line
			(start 0.254 0.508)
			(end -0.254 0.508)
			(stroke
				(width 0.0254)
				(type default)
			)
			(layer "F.Fab")
		)
		(pad "1" smd rect
			(at 0 -0.4191)
			(size 0.508 0.5334)
			(layers "F.Cu" "F.Mask" "F.Paste")
			(net "DDR0_32A_A0")
		)
		(pad "2" smd rect
			(at 0 0.4191)
			(size 0.508 0.5334)
			(layers "F.Cu" "F.Mask" "F.Paste")
			(net "DDR_VTT")
		)
		(zone
			(layer "F.Cu")
			(hatch none 0.5)
			(connect_pads
				(clearance 0)
			)
			(min_thickness 0.25)
			(keepout
				(tracks not_allowed)
				(vias allowed)
				(pads allowed)
				(copperpour not_allowed)
				(footprints allowed)
			)
			(placement
				(enabled no)
				(sheetname "")
			)
			(fill
				(thermal_gap 0.5)
				(thermal_bridge_width 0.5)
				(island_removal_mode 0)
			)
			(polygon
				(pts
					(xy 81.9404 26.8986) (xy 81.9404 26.9494) (xy 81.8896 26.9494) (xy 81.8896 26.8986)
				)
			)
		)
	)
	(footprint ""
		(layer "F.Cu")
		(at 78.867 20.574 90)
		(property "Reference" "R352"
			(at 0.73533 -1.651 0)
			(unlocked yes)
			(layer "F.SilkS")
			(effects
				(font
					(size 0.7874 0.5842)
					(thickness 0.127)
				)
				(justify left)
			)
		)
		(property "Value" "240"
			(at -0.148158 1.3462 180)
			(unlocked yes)
			(layer "F.Fab")
			(hide yes)
			(effects
				(font
					(size 1.27 0.9652)
					(thickness 0.000001)
				)
				(justify left)
			)
		)
		(property "Device Type" "REST0009"
			(at -0.148158 1.3462 180)
			(unlocked yes)
			(layer "F.Fab")
			(hide yes)
			(effects
				(font
					(size 1.27 0.9652)
					(thickness 0.000001)
				)
				(justify left)
			)
		)
		(duplicate_pad_numbers_are_jumpers no)
		(fp_poly
			(pts
				(xy 0.635 1.0668) (xy 0.635 -1.0668) (xy -0.635 -1.0668) (xy -0.635 1.0668)
			)
			(stroke
				(width 0)
				(type default)
			)
			(fill no)
			(layer "F.CrtYd")
		)
		(fp_line
			(start 0.254 -0.508)
			(end 0.254 0.508)
			(stroke
				(width 0.0254)
				(type default)
			)
			(layer "F.Fab")
		)
		(fp_line
			(start -0.254 -0.508)
			(end 0.254 -0.508)
			(stroke
				(width 0.0254)
				(type default)
			)
			(layer "F.Fab")
		)
		(fp_line
			(start 0.254 0.508)
			(end -0.254 0.508)
			(stroke
				(width 0.0254)
				(type default)
			)
			(layer "F.Fab")
		)
		(fp_line
			(start -0.254 0.508)
			(end -0.254 -0.508)
			(stroke
				(width 0.0254)
				(type default)
			)
			(layer "F.Fab")
		)
		(pad "1" smd rect
			(at 0 -0.4191 90)
			(size 0.508 0.5334)
			(layers "F.Cu" "F.Mask" "F.Paste")
			(net "GND")
		)
		(pad "2" smd rect
			(at 0 0.4191 90)
			(size 0.508 0.5334)
			(layers "F.Cu" "F.Mask" "F.Paste")
			(net "12N3057")
		)
		(zone
			(layer "F.Cu")
			(hatch none 0.5)
			(connect_pads
				(clearance 0)
			)
			(min_thickness 0.25)
			(keepout
				(tracks not_allowed)
				(vias allowed)
				(pads allowed)
				(copperpour not_allowed)
				(footprints allowed)
			)
			(placement
				(enabled no)
				(sheetname "")
			)
			(fill
				(thermal_gap 0.5)
				(thermal_bridge_width 0.5)
				(island_removal_mode 0)
			)
			(polygon
				(pts
					(xy 78.8416 20.5486) (xy 78.8924 20.5486) (xy 78.8924 20.5994) (xy 78.8416 20.5994)
				)
			)
		)
	)
	(footprint ""
		(layer "F.Cu")
		(at 19.177 4.318 -90)
		(property "Reference" "C282"
			(at 0 0 270)
			(layer "F.SilkS")
			(hide yes)
			(effects
				(font
					(size 1.27 1.27)
				)
			)
		)
		(property "Value" "4.7UF"
			(at -0.091846 0.2921 0)
			(unlocked yes)
			(layer "F.Fab")
			(hide yes)
			(effects
				(font
					(size 0.7874 0.5842)
					(thickness 0.2032)
				)
				(justify left)
			)
		)
		(property "Device Type" "CAPC0065"
			(at -0.091846 0.2921 0)
			(unlocked yes)
			(layer "F.Fab")
			(hide yes)
			(effects
				(font
					(size 0.7874 0.5842)
					(thickness 0.2032)
				)
				(justify left)
			)
		)
		(duplicate_pad_numbers_are_jumpers no)
		(fp_poly
			(pts
				(xy 0.635 1.0668) (xy 0.635 -1.0668) (xy -0.635 -1.0668) (xy -0.635 1.0668)
			)
			(stroke
				(width 0)
				(type default)
			)
			(fill no)
			(layer "F.CrtYd")
		)
		(fp_line
			(start -0.254 0.508)
			(end -0.254 -0.508)
			(stroke
				(width 0.0254)
				(type default)
			)
			(layer "F.Fab")
		)
		(fp_line
			(start 0.254 0.508)
			(end -0.254 0.508)
			(stroke
				(width 0.0254)
				(type default)
			)
			(layer "F.Fab")
		)
		(fp_line
			(start -0.254 -0.508)
			(end 0.254 -0.508)
			(stroke
				(width 0.0254)
				(type default)
			)
			(layer "F.Fab")
		)
		(fp_line
			(start 0.254 -0.508)
			(end 0.254 0.508)
			(stroke
				(width 0.0254)
				(type default)
			)
			(layer "F.Fab")
		)
		(pad "1" smd rect
			(at 0 -0.4191 270)
			(size 0.508 0.5334)
			(layers "F.Cu" "F.Mask" "F.Paste")
			(net "13N4321")
		)
		(pad "2" smd rect
			(at 0 0.4191 270)
			(size 0.508 0.5334)
			(layers "F.Cu" "F.Mask" "F.Paste")
			(net "GND")
		)
		(zone
			(layer "F.Cu")
			(hatch none 0.5)
			(connect_pads
				(clearance 0)
			)
			(min_thickness 0.25)
			(keepout
				(tracks not_allowed)
				(vias allowed)
				(pads allowed)
				(copperpour not_allowed)
				(footprints allowed)
			)
			(placement
				(enabled no)
				(sheetname "")
			)
			(fill
				(thermal_gap 0.5)
				(thermal_bridge_width 0.5)
				(island_removal_mode 0)
			)
			(polygon
				(pts
					(xy 19.2024 4.3434) (xy 19.1516 4.3434) (xy 19.1516 4.2926) (xy 19.2024 4.2926)
				)
			)
		)
	)
	(footprint ""
		(layer "F.Cu")
		(at 25.908 39.497 -90)
		(property "Reference" "R323"
			(at 0 0 270)
			(layer "F.SilkS")
			(hide yes)
			(effects
				(font
					(size 1.27 1.27)
				)
			)
		)
		(property "Value" "4.02K"
			(at -0.148158 1.3462 0)
			(unlocked yes)
			(layer "F.Fab")
			(hide yes)
			(effects
				(font
					(size 1.27 0.9652)
					(thickness 0.000001)
				)
				(justify left)
			)
		)
		(property "Device Type" "REST0067"
			(at -0.148158 1.3462 0)
			(unlocked yes)
			(layer "F.Fab")
			(hide yes)
			(effects
				(font
					(size 1.27 0.9652)
					(thickness 0.000001)
				)
				(justify left)
			)
		)
		(duplicate_pad_numbers_are_jumpers no)
		(fp_poly
			(pts
				(xy 0.635 1.0668) (xy 0.635 -1.0668) (xy -0.635 -1.0668) (xy -0.635 1.0668)
			)
			(stroke
				(width 0)
				(type default)
			)
			(fill no)
			(layer "F.CrtYd")
		)
		(fp_line
			(start -0.254 0.508)
			(end -0.254 -0.508)
			(stroke
				(width 0.0254)
				(type default)
			)
			(layer "F.Fab")
		)
		(fp_line
			(start 0.254 0.508)
			(end -0.254 0.508)
			(stroke
				(width 0.0254)
				(type default)
			)
			(layer "F.Fab")
		)
		(fp_line
			(start -0.254 -0.508)
			(end 0.254 -0.508)
			(stroke
				(width 0.0254)
				(type default)
			)
			(layer "F.Fab")
		)
		(fp_line
			(start 0.254 -0.508)
			(end 0.254 0.508)
			(stroke
				(width 0.0254)
				(type default)
			)
			(layer "F.Fab")
		)
		(pad "1" smd rect
			(at 0 -0.4191 270)
			(size 0.508 0.5334)
			(layers "F.Cu" "F.Mask" "F.Paste")
			(net "NFP_VDD_CORE_IMON")
		)
		(pad "2" smd rect
			(at 0 0.4191 270)
			(size 0.508 0.5334)
			(layers "F.Cu" "F.Mask" "F.Paste")
			(net "NFP_VDD_CORE_SENSE_VSS")
		)
		(zone
			(layer "F.Cu")
			(hatch none 0.5)
			(connect_pads
				(clearance 0)
			)
			(min_thickness 0.25)
			(keepout
				(tracks not_allowed)
				(vias allowed)
				(pads allowed)
				(copperpour not_allowed)
				(footprints allowed)
			)
			(placement
				(enabled no)
				(sheetname "")
			)
			(fill
				(thermal_gap 0.5)
				(thermal_bridge_width 0.5)
				(island_removal_mode 0)
			)
			(polygon
				(pts
					(xy 25.9334 39.5224) (xy 25.8826 39.5224) (xy 25.8826 39.4716) (xy 25.9334 39.4716)
				)
			)
		)
	)
	(footprint ""
		(layer "F.Cu")
		(at 35.941 6.35 90)
		(property "Reference" "R133"
			(at 0 0 90)
			(layer "F.SilkS")
			(hide yes)
			(effects
				(font
					(size 1.27 1.27)
				)
			)
		)
		(property "Value" "0"
			(at -0.148158 1.3462 180)
			(unlocked yes)
			(layer "F.Fab")
			(hide yes)
			(effects
				(font
					(size 1.27 0.9652)
					(thickness 0.000001)
				)
				(justify left)
			)
		)
		(property "Device Type" "REST1111"
			(at -0.148158 1.3462 180)
			(unlocked yes)
			(layer "F.Fab")
			(hide yes)
			(effects
				(font
					(size 1.27 0.9652)
					(thickness 0.000001)
				)
				(justify left)
			)
		)
		(duplicate_pad_numbers_are_jumpers no)
		(fp_poly
			(pts
				(xy 0.635 1.0668) (xy 0.635 -1.0668) (xy -0.635 -1.0668) (xy -0.635 1.0668)
			)
			(stroke
				(width 0)
				(type default)
			)
			(fill no)
			(layer "F.CrtYd")
		)
		(fp_line
			(start 0.254 -0.508)
			(end 0.254 0.508)
			(stroke
				(width 0.0254)
				(type default)
			)
			(layer "F.Fab")
		)
		(fp_line
			(start -0.254 -0.508)
			(end 0.254 -0.508)
			(stroke
				(width 0.0254)
				(type default)
			)
			(layer "F.Fab")
		)
		(fp_line
			(start 0.254 0.508)
			(end -0.254 0.508)
			(stroke
				(width 0.0254)
				(type default)
			)
			(layer "F.Fab")
		)
		(fp_line
			(start -0.254 0.508)
			(end -0.254 -0.508)
			(stroke
				(width 0.0254)
				(type default)
			)
			(layer "F.Fab")
		)
		(pad "1" smd rect
			(at 0 -0.4191 90)
			(size 0.508 0.5334)
			(layers "F.Cu" "F.Mask" "F.Paste")
			(net "3N2291")
		)
		(pad "2" smd rect
			(at 0 0.4191 90)
			(size 0.508 0.5334)
			(layers "F.Cu" "F.Mask" "F.Paste")
			(net "NFP_SERDES012_SYSCLK_IN_P")
		)
		(zone
			(layer "F.Cu")
			(hatch none 0.5)
			(connect_pads
				(clearance 0)
			)
			(min_thickness 0.25)
			(keepout
				(tracks not_allowed)
				(vias allowed)
				(pads allowed)
				(copperpour not_allowed)
				(footprints allowed)
			)
			(placement
				(enabled no)
				(sheetname "")
			)
			(fill
				(thermal_gap 0.5)
				(thermal_bridge_width 0.5)
				(island_removal_mode 0)
			)
			(polygon
				(pts
					(xy 35.9156 6.3246) (xy 35.9664 6.3246) (xy 35.9664 6.3754) (xy 35.9156 6.3754)
				)
			)
		)
	)
	(footprint ""
		(layer "F.Cu")
		(at 23.749 35.687 180)
		(property "Reference" "R66"
			(at 0 0 180)
			(layer "F.SilkS")
			(hide yes)
			(effects
				(font
					(size 1.27 1.27)
				)
			)
		)
		(property "Value" "4.75K"
			(at -0.148158 1.3462 270)
			(unlocked yes)
			(layer "F.Fab")
			(hide yes)
			(effects
				(font
					(size 1.27 0.9652)
					(thickness 0.000001)
				)
				(justify left)
			)
		)
		(property "Device Type" "REST4024"
			(at -0.148158 1.3462 270)
			(unlocked yes)
			(layer "F.Fab")
			(hide yes)
			(effects
				(font
					(size 1.27 0.9652)
					(thickness 0.000001)
				)
				(justify left)
			)
		)
		(duplicate_pad_numbers_are_jumpers no)
		(fp_poly
			(pts
				(xy 0.635 1.0668) (xy 0.635 -1.0668) (xy -0.635 -1.0668) (xy -0.635 1.0668)
			)
			(stroke
				(width 0)
				(type default)
			)
			(fill no)
			(layer "F.CrtYd")
		)
		(fp_line
			(start 0.254 0.508)
			(end -0.254 0.508)
			(stroke
				(width 0.0254)
				(type default)
			)
			(layer "F.Fab")
		)
		(fp_line
			(start 0.254 -0.508)
			(end 0.254 0.508)
			(stroke
				(width 0.0254)
				(type default)
			)
			(layer "F.Fab")
		)
		(fp_line
			(start -0.254 0.508)
			(end -0.254 -0.508)
			(stroke
				(width 0.0254)
				(type default)
			)
			(layer "F.Fab")
		)
		(fp_line
			(start -0.254 -0.508)
			(end 0.254 -0.508)
			(stroke
				(width 0.0254)
				(type default)
			)
			(layer "F.Fab")
		)
		(pad "1" smd rect
			(at 0 -0.4191 180)
			(size 0.508 0.5334)
			(layers "F.Cu" "F.Mask" "F.Paste")
			(net "VDD_3.3V")
		)
		(pad "2" smd rect
			(at 0 0.4191 180)
			(size 0.508 0.5334)
			(layers "F.Cu" "F.Mask" "F.Paste")
			(net "NFP_CPLD_PRGM_JTAG_TMS")
		)
		(zone
			(layer "F.Cu")
			(hatch none 0.5)
			(connect_pads
				(clearance 0)
			)
			(min_thickness 0.25)
			(keepout
				(tracks not_allowed)
				(vias allowed)
				(pads allowed)
				(copperpour not_allowed)
				(footprints allowed)
			)
			(placement
				(enabled no)
				(sheetname "")
			)
			(fill
				(thermal_gap 0.5)
				(thermal_bridge_width 0.5)
				(island_removal_mode 0)
			)
			(polygon
				(pts
					(xy 23.7236 35.7124) (xy 23.7236 35.6616) (xy 23.7744 35.6616) (xy 23.7744 35.7124)
				)
			)
		)
	)
	(footprint ""
		(layer "F.Cu")
		(at 49.53 48.26)
		(property "Reference" "R102"
			(at 0 0 0)
			(layer "F.SilkS")
			(hide yes)
			(effects
				(font
					(size 1.27 1.27)
				)
			)
		)
		(property "Value" "4.75K"
			(at -0.148158 1.3462 90)
			(unlocked yes)
			(layer "F.Fab")
			(hide yes)
			(effects
				(font
					(size 1.27 0.9652)
					(thickness 0.000001)
				)
				(justify left)
			)
		)
		(property "Device Type" "REST4024"
			(at -0.148158 1.3462 90)
			(unlocked yes)
			(layer "F.Fab")
			(hide yes)
			(effects
				(font
					(size 1.27 0.9652)
					(thickness 0.000001)
				)
				(justify left)
			)
		)
		(duplicate_pad_numbers_are_jumpers no)
		(fp_poly
			(pts
				(xy 0.635 1.0668) (xy 0.635 -1.0668) (xy -0.635 -1.0668) (xy -0.635 1.0668)
			)
			(stroke
				(width 0)
				(type default)
			)
			(fill no)
			(layer "F.CrtYd")
		)
		(fp_line
			(start -0.254 -0.508)
			(end 0.254 -0.508)
			(stroke
				(width 0.0254)
				(type default)
			)
			(layer "F.Fab")
		)
		(fp_line
			(start -0.254 0.508)
			(end -0.254 -0.508)
			(stroke
				(width 0.0254)
				(type default)
			)
			(layer "F.Fab")
		)
		(fp_line
			(start 0.254 -0.508)
			(end 0.254 0.508)
			(stroke
				(width 0.0254)
				(type default)
			)
			(layer "F.Fab")
		)
		(fp_line
			(start 0.254 0.508)
			(end -0.254 0.508)
			(stroke
				(width 0.0254)
				(type default)
			)
			(layer "F.Fab")
		)
		(pad "1" smd rect
			(at 0 -0.4191)
			(size 0.508 0.5334)
			(layers "F.Cu" "F.Mask" "F.Paste")
			(net "GND")
		)
		(pad "2" smd rect
			(at 0 0.4191)
			(size 0.508 0.5334)
			(layers "F.Cu" "F.Mask" "F.Paste")
			(net "EXT_3.3V_PGOOD")
		)
		(zone
			(layer "F.Cu")
			(hatch none 0.5)
			(connect_pads
				(clearance 0)
			)
			(min_thickness 0.25)
			(keepout
				(tracks not_allowed)
				(vias allowed)
				(pads allowed)
				(copperpour not_allowed)
				(footprints allowed)
			)
			(placement
				(enabled no)
				(sheetname "")
			)
			(fill
				(thermal_gap 0.5)
				(thermal_bridge_width 0.5)
				(island_removal_mode 0)
			)
			(polygon
				(pts
					(xy 49.5554 48.2346) (xy 49.5554 48.2854) (xy 49.5046 48.2854) (xy 49.5046 48.2346)
				)
			)
		)
	)
	(footprint ""
		(layer "F.Cu")
		(at 14.478 37.211 90)
		(property "Reference" "U9"
			(at 2.64033 -3.81 0)
			(unlocked yes)
			(layer "F.SilkS")
			(effects
				(font
					(size 0.7874 0.5842)
					(thickness 0.127)
				)
				(justify left)
			)
		)
		(property "Value" "VAL"
			(at 0 1.851914 90)
			(unlocked yes)
			(layer "F.Fab")
			(hide yes)
			(effects
				(font
					(size 1.27 0.9652)
					(thickness 0.1524)
				)
			)
		)
		(property "User Part Number" "PN"
			(at 0 -4.148328 90)
			(unlocked yes)
			(layer "Cmts.User")
			(hide yes)
			(effects
				(font
					(size 1.27 0.9652)
					(thickness 0.1524)
				)
			)
		)
		(property "Device Type" "DCDC0065"
			(at 0 -1.898142 90)
			(unlocked yes)
			(layer "F.Fab")
			(hide yes)
			(effects
				(font
					(size 1.27 0.9652)
					(thickness 0.1524)
				)
			)
		)
		(property "Tolerance" "TOL"
			(at 0 4.144518 90)
			(unlocked yes)
			(layer "Cmts.User")
			(hide yes)
			(effects
				(font
					(size 1.27 0.9652)
					(thickness 0.1524)
				)
			)
		)
		(duplicate_pad_numbers_are_jumpers no)
		(fp_line
			(start 2.355088 -2.355088)
			(end 2.355088 -1.905)
			(stroke
				(width 0.1524)
				(type default)
			)
			(layer "F.SilkS")
		)
		(fp_line
			(start 1.905 -2.355088)
			(end 2.355088 -2.355088)
			(stroke
				(width 0.1524)
				(type default)
			)
			(layer "F.SilkS")
		)
		(fp_line
			(start -1.955013 -2.355088)
			(end -1.905 -2.355088)
			(stroke
				(width 0.1524)
				(type default)
			)
			(layer "F.SilkS")
		)
		(fp_line
			(start -2.355088 -1.955013)
			(end -1.955013 -2.355088)
			(stroke
				(width 0.1524)
				(type default)
			)
			(layer "F.SilkS")
		)
		(fp_line
			(start -2.355088 -1.905)
			(end -2.355088 -1.955013)
			(stroke
				(width 0.1524)
				(type default)
			)
			(layer "F.SilkS")
		)
		(fp_line
			(start 2.355088 1.905)
			(end 2.355088 2.355088)
			(stroke
				(width 0.1524)
				(type default)
			)
			(layer "F.SilkS")
		)
		(fp_line
			(start 2.355088 2.355088)
			(end 1.905 2.355088)
			(stroke
				(width 0.1524)
				(type default)
			)
			(layer "F.SilkS")
		)
		(fp_line
			(start -1.905 2.355088)
			(end -2.355088 2.355088)
			(stroke
				(width 0.1524)
				(type default)
			)
			(layer "F.SilkS")
		)
		(fp_line
			(start -2.355088 2.355088)
			(end -2.355088 1.905)
			(stroke
				(width 0.1524)
				(type default)
			)
			(layer "F.SilkS")
		)
		(fp_arc
			(start -2.8956 -2.032)
			(mid -2.876496 -2.031281)
			(end -2.8575 -2.02913)
			(stroke
				(width 0.1524)
				(type default)
			)
			(layer "F.SilkS")
		)
		(fp_arc
			(start -2.921 -2.03073)
			(mid -2.908316 -2.031684)
			(end -2.8956 -2.032)
			(stroke
				(width 0.1524)
				(type default)
			)
			(layer "F.SilkS")
		)
		(fp_arc
			(start -2.8575 -1.52687)
			(mid -2.876496 -1.524717)
			(end -2.8956 -1.524)
			(stroke
				(width 0.1524)
				(type default)
			)
			(layer "F.SilkS")
		)
		(fp_arc
			(start -2.8956 -1.524)
			(mid -2.965173 -1.533714)
			(end -3.029433 -1.5621)
			(stroke
				(width 0.1524)
				(type default)
			)
			(layer "F.SilkS")
		)
		(fp_circle
			(center -2.8956 -1.778)
			(end -2.8956 -1.524)
			(stroke
				(width 0.1524)
				(type default)
			)
			(fill no)
			(layer "F.SilkS")
		)
		(fp_poly
			(pts
				(xy -3.048 3.048) (xy 3.048 3.048) (xy 3.048 -3.048) (xy -3.048 -3.048)
			)
			(stroke
				(width 0)
				(type default)
			)
			(fill no)
			(layer "F.CrtYd")
		)
		(fp_line
			(start 2.275103 -2.275103)
			(end 2.275103 2.275103)
			(stroke
				(width 0.0254)
				(type default)
			)
			(layer "F.Fab")
		)
		(fp_line
			(start -1.640103 -2.275103)
			(end 2.275103 -2.275103)
			(stroke
				(width 0.0254)
				(type default)
			)
			(layer "F.Fab")
		)
		(fp_line
			(start -2.275103 -1.640103)
			(end -1.640103 -2.275103)
			(stroke
				(width 0.0254)
				(type default)
			)
			(layer "F.Fab")
		)
		(fp_line
			(start 2.275103 2.275103)
			(end -2.275103 2.275103)
			(stroke
				(width 0.0254)
				(type default)
			)
			(layer "F.Fab")
		)
		(fp_line
			(start -2.275103 2.275103)
			(end -2.275103 -1.640103)
			(stroke
				(width 0.0254)
				(type default)
			)
			(layer "F.Fab")
		)
		(fp_circle
			(center -1.61511 -1.61511)
			(end -1.61511 -1.361212)
			(stroke
				(width 0.0254)
				(type default)
			)
			(fill no)
			(layer "F.Fab")
		)
		(pad "1" smd custom
			(at -2.1717 -1.599895)
			(size 0.0508 0.0508)
			(layers "F.Cu" "F.Mask" "F.Paste")
			(net "11N1968")
			(options
				(clearance outline)
				(anchor circle)
			)
			(primitives
				(gr_poly
					(pts
						(xy -0.1016 0.3556) (xy -0.1016 -0.254) (xy 0 -0.3556) (xy 0.1016 -0.3556) (xy 0.1016 0.3556)
					)
					(width 0)
					(fill yes)
				)
			)
		)
		(pad "2" smd rect
			(at -2.1717 -1.199896)
			(size 0.2032 0.7112)
			(layers "F.Cu" "F.Mask" "F.Paste")
			(net "VDD_5.0V")
		)
		(pad "3" smd rect
			(at -2.1717 -0.8001)
			(size 0.2032 0.7112)
			(layers "F.Cu" "F.Mask" "F.Paste")
			(net "VDD_1.5V")
		)
		(pad "4" smd rect
			(at -2.1717 -0.399999)
			(size 0.2032 0.7112)
			(layers "F.Cu" "F.Mask" "F.Paste")
			(net "VDD_5.0V")
		)
		(pad "5" smd rect
			(at -2.1717 0)
			(size 0.2032 0.7112)
			(layers "F.Cu" "F.Mask" "F.Paste")
			(net "11N1937")
		)
		(pad "6" smd rect
			(at -2.1717 0.399999)
			(size 0.2032 0.7112)
			(layers "F.Cu" "F.Mask" "F.Paste")
			(net "GND")
		)
		(pad "7" smd rect
			(at -2.1717 0.8001)
			(size 0.2032 0.7112)
			(layers "F.Cu" "F.Mask" "F.Paste")
			(net "VDD_1.8V")
		)
		(pad "8" smd rect
			(at -2.1717 1.199896)
			(size 0.2032 0.7112)
			(layers "F.Cu" "F.Mask" "F.Paste")
			(net "VDD_5.0V")
		)
		(pad "9" smd custom
			(at -2.1717 1.599895)
			(size 0.0508 0.0508)
			(layers "F.Cu" "F.Mask" "F.Paste")
			(net "11N1971")
			(options
				(clearance outline)
				(anchor circle)
			)
			(primitives
				(gr_poly
					(pts
						(xy 0.1016 0.3556) (xy 0.1016 -0.254) (xy 0 -0.3556) (xy -0.1016 -0.3556) (xy -0.1016 0.3556)
					)
					(width 0)
					(fill yes)
				)
			)
		)
		(pad "10" smd custom
			(at -1.599895 2.1717 90)
			(size 0.0508 0.0508)
			(layers "F.Cu" "F.Mask" "F.Paste")
			(net "GND")
			(options
				(clearance outline)
				(anchor circle)
			)
			(primitives
				(gr_poly
					(pts
						(xy -0.1016 0.3556) (xy -0.1016 -0.254) (xy 0 -0.3556) (xy 0.1016 -0.3556) (xy 0.1016 0.3556)
					)
					(width 0)
					(fill yes)
				)
			)
		)
		(pad "11" smd rect
			(at -1.199896 2.1717 90)
			(size 0.2032 0.7112)
			(layers "F.Cu" "F.Mask" "F.Paste")
			(net "DDR_1.8V")
		)
		(pad "12" smd rect
			(at -0.8001 2.1717 90)
			(size 0.2032 0.7112)
			(layers "F.Cu" "F.Mask" "F.Paste")
			(net "11N1979")
		)
		(pad "13" smd rect
			(at -0.399999 2.1717 90)
			(size 0.2032 0.7112)
			(layers "F.Cu" "F.Mask" "F.Paste")
			(net "PSU_I2C_SDA")
		)
		(pad "14" smd rect
			(at 0 2.1717 90)
			(size 0.2032 0.7112)
			(layers "F.Cu" "F.Mask" "F.Paste")
			(net "GND")
		)
		(pad "15" smd rect
			(at 0.399999 2.1717 90)
			(size 0.2032 0.7112)
			(layers "F.Cu" "F.Mask" "F.Paste")
			(net "PSU_I2C_SCL")
		)
		(pad "16" smd rect
			(at 0.8001 2.1717 90)
			(size 0.2032 0.7112)
			(layers "F.Cu" "F.Mask" "F.Paste")
			(net "11N1966")
		)
		(pad "17" smd rect
			(at 1.199896 2.1717 90)
			(size 0.2032 0.7112)
			(layers "F.Cu" "F.Mask" "F.Paste")
			(net "VDD_3.3V")
		)
		(pad "18" smd custom
			(at 1.599895 2.1717 90)
			(size 0.0508 0.0508)
			(layers "F.Cu" "F.Mask" "F.Paste")
			(net "GND")
			(options
				(clearance outline)
				(anchor circle)
			)
			(primitives
				(gr_poly
					(pts
						(xy 0.1016 0.3556) (xy 0.1016 -0.254) (xy 0 -0.3556) (xy -0.1016 -0.3556) (xy -0.1016 0.3556)
					)
					(width 0)
					(fill yes)
				)
			)
		)
		(pad "19" smd custom
			(at 2.1717 1.599895 180)
			(size 0.0508 0.0508)
			(layers "F.Cu" "F.Mask" "F.Paste")
			(net "11N2296")
			(options
				(clearance outline)
				(anchor circle)
			)
			(primitives
				(gr_poly
					(pts
						(xy -0.1016 0.3556) (xy -0.1016 -0.254) (xy 0 -0.3556) (xy 0.1016 -0.3556) (xy 0.1016 0.3556)
					)
					(width 0)
					(fill yes)
				)
			)
		)
		(pad "20" smd rect
			(at 2.1717 1.199896 180)
			(size 0.2032 0.7112)
			(layers "F.Cu" "F.Mask" "F.Paste")
			(net "VDD_5.0V")
		)
		(pad "21" smd rect
			(at 2.1717 0.8001 180)
			(size 0.2032 0.7112)
			(layers "F.Cu" "F.Mask" "F.Paste")
			(net "VDD_5.0V")
		)
		(pad "22" smd rect
			(at 2.1717 0.399999 180)
			(size 0.2032 0.7112)
			(layers "F.Cu" "F.Mask" "F.Paste")
			(net "GND")
		)
		(pad "23" smd rect
			(at 2.1717 0 180)
			(size 0.2032 0.7112)
			(layers "F.Cu" "F.Mask" "F.Paste")
			(net "GND")
		)
		(pad "24" smd rect
			(at 2.1717 -0.399999 180)
			(size 0.2032 0.7112)
			(layers "F.Cu" "F.Mask" "F.Paste")
			(net "VDD_5.0V")
		)
		(pad "25" smd rect
			(at 2.1717 -0.8001 180)
			(size 0.2032 0.7112)
			(layers "F.Cu" "F.Mask" "F.Paste")
			(net "VDD_5.0V")
		)
		(pad "26" smd rect
			(at 2.1717 -1.199896 180)
			(size 0.2032 0.7112)
			(layers "F.Cu" "F.Mask" "F.Paste")
			(net "VDD_5.0V")
		)
		(pad "27" smd custom
			(at 2.1717 -1.599895 180)
			(size 0.0508 0.0508)
			(layers "F.Cu" "F.Mask" "F.Paste")
			(net "11N1970")
			(options
				(clearance outline)
				(anchor circle)
			)
			(primitives
				(gr_poly
					(pts
						(xy 0.1016 0.3556) (xy 0.1016 -0.254) (xy 0 -0.3556) (xy -0.1016 -0.3556) (xy -0.1016 0.3556)
					)
					(width 0)
					(fill yes)
				)
			)
		)
		(pad "28" smd custom
			(at 1.599895 -2.1717 270)
			(size 0.0508 0.0508)
			(layers "F.Cu" "F.Mask" "F.Paste")
			(net "GND")
			(options
				(clearance outline)
				(anchor circle)
			)
			(primitives
				(gr_poly
					(pts
						(xy -0.1016 0.3556) (xy -0.1016 -0.254) (xy 0 -0.3556) (xy 0.1016 -0.3556) (xy 0.1016 0.3556)
					)
					(width 0)
					(fill yes)
				)
			)
		)
		(pad "29" smd rect
			(at 1.199896 -2.1717 270)
			(size 0.2032 0.7112)
			(layers "F.Cu" "F.Mask" "F.Paste")
			(net "VDD_1.2V")
		)
		(pad "30" smd rect
			(at 0.8001 -2.1717 270)
			(size 0.2032 0.7112)
			(layers "F.Cu" "F.Mask" "F.Paste")
			(net "VDD_7401_EN")
		)
		(pad "31" smd rect
			(at 0.399999 -2.1717 270)
			(size 0.2032 0.7112)
			(layers "F.Cu" "F.Mask" "F.Paste")
			(net "VDD_5.0V")
		)
		(pad "32" smd rect
			(at 0 -2.1717 270)
			(size 0.2032 0.7112)
			(layers "F.Cu" "F.Mask" "F.Paste")
			(net "GND")
		)
		(pad "33" smd rect
			(at -0.399999 -2.1717 270)
			(size 0.2032 0.7112)
			(layers "F.Cu" "F.Mask" "F.Paste")
			(net "_NC_MIC7401_NC1")
		)
		(pad "34" smd rect
			(at -0.8001 -2.1717 270)
			(size 0.2032 0.7112)
			(layers "F.Cu" "F.Mask" "F.Paste")
			(net "_NC_MIC7401_NC2")
		)
		(pad "35" smd rect
			(at -1.199896 -2.1717 270)
			(size 0.2032 0.7112)
			(layers "F.Cu" "F.Mask" "F.Paste")
			(net "VDD_7401_PGOOD")
		)
		(pad "36" smd custom
			(at -1.599895 -2.1717 270)
			(size 0.0508 0.0508)
			(layers "F.Cu" "F.Mask" "F.Paste")
			(net "GND")
			(options
				(clearance outline)
				(anchor circle)
			)
			(primitives
				(gr_poly
					(pts
						(xy 0.1016 0.3556) (xy 0.1016 -0.254) (xy 0 -0.3556) (xy -0.1016 -0.3556) (xy -0.1016 0.3556)
					)
					(width 0)
					(fill yes)
				)
			)
		)
		(pad "37" smd rect
			(at 0 0 90)
			(size 1.8034 1.8034)
			(layers "F.Cu" "F.Mask" "F.Paste")
			(net "GND")
		)
	)
	(footprint ""
		(layer "F.Cu")
		(at 53.086 49.5046 -90)
		(property "Reference" "C63"
			(at 1.32207 -0.127 0)
			(unlocked yes)
			(layer "F.SilkS")
			(effects
				(font
					(size 0.7874 0.5842)
					(thickness 0.127)
				)
				(justify left)
			)
		)
		(property "Value" "100UF"
			(at -0.78232 0.4826 0)
			(unlocked yes)
			(layer "F.Fab")
			(hide yes)
			(effects
				(font
					(size 1.27 0.9652)
					(thickness 0.000001)
				)
				(justify left)
			)
		)
		(property "Device Type" "CAPC0087"
			(at -0.78232 0.4826 0)
			(unlocked yes)
			(layer "F.Fab")
			(hide yes)
			(effects
				(font
					(size 1.27 0.9652)
					(thickness 0.000001)
				)
				(justify left)
			)
		)
		(duplicate_pad_numbers_are_jumpers no)
		(fp_circle
			(center 0 0)
			(end 0 -0.508)
			(stroke
				(width 0.2032)
				(type default)
			)
			(fill no)
			(layer "F.SilkS")
		)
		(fp_circle
			(center 0 0)
			(end 0 -0.508)
			(stroke
				(width 0.2032)
				(type default)
			)
			(fill no)
			(layer "F.SilkS")
		)
		(fp_poly
			(pts
				(xy -1.27 2.9464) (xy 1.27 2.9464) (xy 1.27 -2.9464) (xy -1.27 -2.9464)
			)
			(stroke
				(width 0)
				(type default)
			)
			(fill no)
			(layer "F.CrtYd")
		)
		(fp_line
			(start -1.016 2.794)
			(end -1.016 -2.794)
			(stroke
				(width 0.0254)
				(type default)
			)
			(layer "F.Fab")
		)
		(fp_line
			(start 1.016 2.794)
			(end -1.016 2.794)
			(stroke
				(width 0.0254)
				(type default)
			)
			(layer "F.Fab")
		)
		(fp_line
			(start -1.016 -2.794)
			(end 1.016 -2.794)
			(stroke
				(width 0.0254)
				(type default)
			)
			(layer "F.Fab")
		)
		(fp_line
			(start 1.016 -2.794)
			(end 1.016 2.794)
			(stroke
				(width 0.0254)
				(type default)
			)
			(layer "F.Fab")
		)
		(pad "1" smd rect
			(at 0 -1.6764 270)
			(size 1.524 1.524)
			(layers "F.Cu" "F.Mask" "F.Paste")
			(net "VDD_CORE")
		)
		(pad "2" smd rect
			(at 0 1.6764 270)
			(size 1.524 1.524)
			(layers "F.Cu" "F.Mask" "F.Paste")
			(net "GND")
		)
		(zone
			(layer "F.Cu")
			(hatch none 0.5)
			(connect_pads
				(clearance 0)
			)
			(min_thickness 0.25)
			(keepout
				(tracks allowed)
				(vias not_allowed)
				(pads allowed)
				(copperpour not_allowed)
				(footprints allowed)
			)
			(placement
				(enabled no)
				(sheetname "")
			)
			(fill
				(thermal_gap 0.5)
				(thermal_bridge_width 0.5)
				(island_removal_mode 0)
			)
			(polygon
				(pts
					(xy 51.4858 48.7172) (xy 51.4858 50.292) (xy 54.6862 50.292) (xy 54.6862 48.7172)
				)
			)
		)
		(zone
			(layer "F.Cu")
			(hatch none 0.5)
			(connect_pads
				(clearance 0)
			)
			(min_thickness 0.25)
			(keepout
				(tracks not_allowed)
				(vias allowed)
				(pads allowed)
				(copperpour not_allowed)
				(footprints allowed)
			)
			(placement
				(enabled no)
				(sheetname "")
			)
			(fill
				(thermal_gap 0.5)
				(thermal_bridge_width 0.5)
				(island_removal_mode 0)
			)
			(polygon
				(pts
					(xy 52.3494 48.7172) (xy 52.3494 50.292) (xy 52.197 50.292) (xy 52.197 48.7172)
				)
			)
		)
		(zone
			(layer "F.Cu")
			(hatch none 0.5)
			(connect_pads
				(clearance 0)
			)
			(min_thickness 0.25)
			(keepout
				(tracks not_allowed)
				(vias allowed)
				(pads allowed)
				(copperpour not_allowed)
				(footprints allowed)
			)
			(placement
				(enabled no)
				(sheetname "")
			)
			(fill
				(thermal_gap 0.5)
				(thermal_bridge_width 0.5)
				(island_removal_mode 0)
			)
			(polygon
				(pts
					(xy 53.975 48.7172) (xy 53.975 50.292) (xy 53.8226 50.292) (xy 53.8226 48.7172)
				)
			)
		)
	)
	(footprint ""
		(layer "F.Cu")
		(at 73.05101 7.498994)
		(property "Reference" "V_A-DQ10"
			(at 0 0 0)
			(layer "F.SilkS")
			(hide yes)
			(effects
				(font
					(size 1.27 1.27)
				)
			)
		)
		(property "Value" ""
			(at 0 0 0)
			(layer "F.Fab")
			(effects
				(font
					(size 1.27 1.27)
				)
			)
		)
		(duplicate_pad_numbers_are_jumpers no)
		(pad "1" thru_hole circle
			(at 0 0)
			(size 0.762 0.762)
			(drill 0.20574)
			(layers "*.Cu" "*.Mask")
			(remove_unused_layers no)
			(net "DDR0_32A_DQ10")
			(clearance 0.127)
			(thermal_gap 0.127)
			(padstack
				(mode front_inner_back)
				(layer "Inner"
					(shape circle)
					(size 0.4572 0.4572)
					(clearance 0.1143)
				)
				(layer "B.Cu"
					(shape circle)
					(size 0.4572 0.4572)
					(clearance 0.1143)
				)
			)
		)
	)
	(footprint ""
		(layer "F.Cu")
		(at 78.74 43.688)
		(property "Reference" "C138"
			(at -0.22733 -1.397 90)
			(unlocked yes)
			(layer "F.SilkS")
			(effects
				(font
					(size 0.7874 0.5842)
					(thickness 0.127)
				)
				(justify left)
			)
		)
		(property "Value" "10UF"
			(at -0.148158 1.7526 90)
			(unlocked yes)
			(layer "F.Fab")
			(hide yes)
			(effects
				(font
					(size 1.27 0.9652)
					(thickness 0.000001)
				)
				(justify left)
			)
		)
		(property "Device Type" "CAPC0058"
			(at -0.148158 1.7526 90)
			(unlocked yes)
			(layer "F.Fab")
			(hide yes)
			(effects
				(font
					(size 1.27 0.9652)
					(thickness 0.000001)
				)
				(justify left)
			)
		)
		(duplicate_pad_numbers_are_jumpers no)
		(fp_circle
			(center 0 0)
			(end 0.127 0)
			(stroke
				(width 0.2032)
				(type default)
			)
			(fill no)
			(layer "F.SilkS")
		)
		(fp_poly
			(pts
				(xy 0.7874 -1.6637) (xy -0.7874 -1.6637) (xy -0.7874 1.6637) (xy 0.7874 1.6637)
			)
			(stroke
				(width 0)
				(type default)
			)
			(fill no)
			(layer "F.CrtYd")
		)
		(fp_line
			(start -0.4064 -0.7874)
			(end 0.4064 -0.7874)
			(stroke
				(width 0.0254)
				(type default)
			)
			(layer "F.Fab")
		)
		(fp_line
			(start -0.4064 0.8128)
			(end -0.4064 -0.7874)
			(stroke
				(width 0.0254)
				(type default)
			)
			(layer "F.Fab")
		)
		(fp_line
			(start 0.4064 -0.7874)
			(end 0.4064 0.8128)
			(stroke
				(width 0.0254)
				(type default)
			)
			(layer "F.Fab")
		)
		(fp_line
			(start 0.4064 0.8128)
			(end -0.4064 0.8128)
			(stroke
				(width 0.0254)
				(type default)
			)
			(layer "F.Fab")
		)
		(pad "1" smd rect
			(at 0 -0.8001)
			(size 0.8636 0.9652)
			(layers "F.Cu" "F.Mask" "F.Paste")
			(net "DDR_VTT")
		)
		(pad "2" smd rect
			(at 0 0.8001)
			(size 0.8636 0.9652)
			(layers "F.Cu" "F.Mask" "F.Paste")
			(net "GND")
		)
	)
	(footprint ""
		(layer "F.Cu")
		(at 22.86 35.687 180)
		(property "Reference" "R61"
			(at 0 0 180)
			(layer "F.SilkS")
			(hide yes)
			(effects
				(font
					(size 1.27 1.27)
				)
			)
		)
		(property "Value" "4.75K"
			(at -0.148158 1.3462 270)
			(unlocked yes)
			(layer "F.Fab")
			(hide yes)
			(effects
				(font
					(size 1.27 0.9652)
					(thickness 0.000001)
				)
				(justify left)
			)
		)
		(property "Device Type" "REST4024"
			(at -0.148158 1.3462 270)
			(unlocked yes)
			(layer "F.Fab")
			(hide yes)
			(effects
				(font
					(size 1.27 0.9652)
					(thickness 0.000001)
				)
				(justify left)
			)
		)
		(duplicate_pad_numbers_are_jumpers no)
		(fp_poly
			(pts
				(xy 0.635 1.0668) (xy 0.635 -1.0668) (xy -0.635 -1.0668) (xy -0.635 1.0668)
			)
			(stroke
				(width 0)
				(type default)
			)
			(fill no)
			(layer "F.CrtYd")
		)
		(fp_line
			(start 0.254 0.508)
			(end -0.254 0.508)
			(stroke
				(width 0.0254)
				(type default)
			)
			(layer "F.Fab")
		)
		(fp_line
			(start 0.254 -0.508)
			(end 0.254 0.508)
			(stroke
				(width 0.0254)
				(type default)
			)
			(layer "F.Fab")
		)
		(fp_line
			(start -0.254 0.508)
			(end -0.254 -0.508)
			(stroke
				(width 0.0254)
				(type default)
			)
			(layer "F.Fab")
		)
		(fp_line
			(start -0.254 -0.508)
			(end 0.254 -0.508)
			(stroke
				(width 0.0254)
				(type default)
			)
			(layer "F.Fab")
		)
		(pad "1" smd rect
			(at 0 -0.4191 180)
			(size 0.508 0.5334)
			(layers "F.Cu" "F.Mask" "F.Paste")
			(net "EXT_3.3V")
		)
		(pad "2" smd rect
			(at 0 0.4191 180)
			(size 0.508 0.5334)
			(layers "F.Cu" "F.Mask" "F.Paste")
			(net "CPLD_PGRM_JTAG_TMS")
		)
		(zone
			(layer "F.Cu")
			(hatch none 0.5)
			(connect_pads
				(clearance 0)
			)
			(min_thickness 0.25)
			(keepout
				(tracks not_allowed)
				(vias allowed)
				(pads allowed)
				(copperpour not_allowed)
				(footprints allowed)
			)
			(placement
				(enabled no)
				(sheetname "")
			)
			(fill
				(thermal_gap 0.5)
				(thermal_bridge_width 0.5)
				(island_removal_mode 0)
			)
			(polygon
				(pts
					(xy 22.8346 35.7124) (xy 22.8346 35.6616) (xy 22.8854 35.6616) (xy 22.8854 35.7124)
				)
			)
		)
	)
	(footprint ""
		(layer "F.Cu")
		(at 75.819 4.318 -90)
		(property "Reference" "R288"
			(at -0.10033 4.064 0)
			(unlocked yes)
			(layer "F.SilkS")
			(effects
				(font
					(size 0.7874 0.5842)
					(thickness 0.127)
				)
				(justify left)
			)
		)
		(property "Value" "100"
			(at -0.148158 1.3462 0)
			(unlocked yes)
			(layer "F.Fab")
			(hide yes)
			(effects
				(font
					(size 1.27 0.9652)
					(thickness 0.000001)
				)
				(justify left)
			)
		)
		(property "Device Type" "REST4030"
			(at -0.148158 1.3462 0)
			(unlocked yes)
			(layer "F.Fab")
			(hide yes)
			(effects
				(font
					(size 1.27 0.9652)
					(thickness 0.000001)
				)
				(justify left)
			)
		)
		(duplicate_pad_numbers_are_jumpers no)
		(fp_poly
			(pts
				(xy 0.635 1.0668) (xy 0.635 -1.0668) (xy -0.635 -1.0668) (xy -0.635 1.0668)
			)
			(stroke
				(width 0)
				(type default)
			)
			(fill no)
			(layer "F.CrtYd")
		)
		(fp_line
			(start -0.254 0.508)
			(end -0.254 -0.508)
			(stroke
				(width 0.0254)
				(type default)
			)
			(layer "F.Fab")
		)
		(fp_line
			(start 0.254 0.508)
			(end -0.254 0.508)
			(stroke
				(width 0.0254)
				(type default)
			)
			(layer "F.Fab")
		)
		(fp_line
			(start -0.254 -0.508)
			(end 0.254 -0.508)
			(stroke
				(width 0.0254)
				(type default)
			)
			(layer "F.Fab")
		)
		(fp_line
			(start 0.254 -0.508)
			(end 0.254 0.508)
			(stroke
				(width 0.0254)
				(type default)
			)
			(layer "F.Fab")
		)
		(pad "1" smd rect
			(at 0 -0.4191 270)
			(size 0.508 0.5334)
			(layers "F.Cu" "F.Mask" "F.Paste")
			(net "DDR0_32A_VREF0B")
		)
		(pad "2" smd rect
			(at 0 0.4191 270)
			(size 0.508 0.5334)
			(layers "F.Cu" "F.Mask" "F.Paste")
			(net "DDR_VDDQ")
		)
		(zone
			(layer "F.Cu")
			(hatch none 0.5)
			(connect_pads
				(clearance 0)
			)
			(min_thickness 0.25)
			(keepout
				(tracks not_allowed)
				(vias allowed)
				(pads allowed)
				(copperpour not_allowed)
				(footprints allowed)
			)
			(placement
				(enabled no)
				(sheetname "")
			)
			(fill
				(thermal_gap 0.5)
				(thermal_bridge_width 0.5)
				(island_removal_mode 0)
			)
			(polygon
				(pts
					(xy 75.8444 4.3434) (xy 75.7936 4.3434) (xy 75.7936 4.2926) (xy 75.8444 4.2926)
				)
			)
		)
	)
	(footprint ""
		(layer "F.Cu")
		(at 49.403 46.482)
		(property "Reference" "TP63"
			(at -5.715 -0.10033 0)
			(unlocked yes)
			(layer "F.SilkS")
			(effects
				(font
					(size 0.7874 0.5842)
					(thickness 0.127)
				)
				(justify left)
			)
		)
		(property "Value" "*"
			(at -0.4826 -0.14732 0)
			(unlocked yes)
			(layer "F.Fab")
			(hide yes)
			(effects
				(font
					(size 1.27 0.9652)
					(thickness 0.000001)
				)
				(justify left)
			)
		)
		(property "Device Type" "TP_SMALL"
			(at -0.4826 -0.14732 0)
			(unlocked yes)
			(layer "F.Fab")
			(hide yes)
			(effects
				(font
					(size 1.27 0.9652)
					(thickness 0.000001)
				)
				(justify left)
			)
		)
		(duplicate_pad_numbers_are_jumpers no)
		(fp_line
			(start -0.8636 -0.8636)
			(end -0.8636 0.8636)
			(stroke
				(width 0.1524)
				(type default)
			)
			(layer "F.SilkS")
		)
		(fp_line
			(start -0.8636 0.8636)
			(end 0.8636 0.8636)
			(stroke
				(width 0.1524)
				(type default)
			)
			(layer "F.SilkS")
		)
		(fp_line
			(start 0.8636 -0.8636)
			(end -0.8636 -0.8636)
			(stroke
				(width 0.1524)
				(type default)
			)
			(layer "F.SilkS")
		)
		(fp_line
			(start 0.8636 0.8636)
			(end 0.8636 -0.8636)
			(stroke
				(width 0.1524)
				(type default)
			)
			(layer "F.SilkS")
		)
		(fp_poly
			(pts
				(xy -0.635 -0.635) (xy -0.635 0.635) (xy 0.635 0.635) (xy 0.635 -0.635)
			)
			(stroke
				(width 0)
				(type default)
			)
			(fill no)
			(layer "F.CrtYd")
		)
		(pad "1" smd rect
			(at 0 0)
			(size 1.27 1.27)
			(layers "F.Cu" "F.Mask" "F.Paste")
			(net "EXT_3.3V_PGOOD")
		)
	)
	(footprint ""
		(layer "F.Cu")
		(at 78.3082 22.987 180)
		(property "Reference" "R354"
			(at 0 0 180)
			(layer "F.SilkS")
			(hide yes)
			(effects
				(font
					(size 1.27 1.27)
				)
			)
		)
		(property "Value" "39.0"
			(at -0.148158 1.3462 270)
			(unlocked yes)
			(layer "F.Fab")
			(hide yes)
			(effects
				(font
					(size 1.27 0.9652)
					(thickness 0.000001)
				)
				(justify left)
			)
		)
		(property "Device Type" "REST0108"
			(at -0.148158 1.3462 270)
			(unlocked yes)
			(layer "F.Fab")
			(hide yes)
			(effects
				(font
					(size 1.27 0.9652)
					(thickness 0.000001)
				)
				(justify left)
			)
		)
		(duplicate_pad_numbers_are_jumpers no)
		(fp_poly
			(pts
				(xy 0.635 1.0668) (xy 0.635 -1.0668) (xy -0.635 -1.0668) (xy -0.635 1.0668)
			)
			(stroke
				(width 0)
				(type default)
			)
			(fill no)
			(layer "F.CrtYd")
		)
		(fp_line
			(start 0.254 0.508)
			(end -0.254 0.508)
			(stroke
				(width 0.0254)
				(type default)
			)
			(layer "F.Fab")
		)
		(fp_line
			(start 0.254 -0.508)
			(end 0.254 0.508)
			(stroke
				(width 0.0254)
				(type default)
			)
			(layer "F.Fab")
		)
		(fp_line
			(start -0.254 0.508)
			(end -0.254 -0.508)
			(stroke
				(width 0.0254)
				(type default)
			)
			(layer "F.Fab")
		)
		(fp_line
			(start -0.254 -0.508)
			(end 0.254 -0.508)
			(stroke
				(width 0.0254)
				(type default)
			)
			(layer "F.Fab")
		)
		(pad "1" smd rect
			(at 0 -0.4191 180)
			(size 0.508 0.5334)
			(layers "F.Cu" "F.Mask" "F.Paste")
			(net "DDR0_32A_ODT0")
		)
		(pad "2" smd rect
			(at 0 0.4191 180)
			(size 0.508 0.5334)
			(layers "F.Cu" "F.Mask" "F.Paste")
			(net "DDR_VTT")
		)
		(zone
			(layer "F.Cu")
			(hatch none 0.5)
			(connect_pads
				(clearance 0)
			)
			(min_thickness 0.25)
			(keepout
				(tracks not_allowed)
				(vias allowed)
				(pads allowed)
				(copperpour not_allowed)
				(footprints allowed)
			)
			(placement
				(enabled no)
				(sheetname "")
			)
			(fill
				(thermal_gap 0.5)
				(thermal_bridge_width 0.5)
				(island_removal_mode 0)
			)
			(polygon
				(pts
					(xy 78.2828 23.0124) (xy 78.2828 22.9616) (xy 78.3336 22.9616) (xy 78.3336 23.0124)
				)
			)
		)
	)
	(footprint ""
		(layer "F.Cu")
		(at 81.026 26.924)
		(property "Reference" "R222"
			(at 0 0 0)
			(layer "F.SilkS")
			(hide yes)
			(effects
				(font
					(size 1.27 1.27)
				)
			)
		)
		(property "Value" "39.0"
			(at -0.148158 1.3462 90)
			(unlocked yes)
			(layer "F.Fab")
			(hide yes)
			(effects
				(font
					(size 1.27 0.9652)
					(thickness 0.000001)
				)
				(justify left)
			)
		)
		(property "Device Type" "REST0108"
			(at -0.148158 1.3462 90)
			(unlocked yes)
			(layer "F.Fab")
			(hide yes)
			(effects
				(font
					(size 1.27 0.9652)
					(thickness 0.000001)
				)
				(justify left)
			)
		)
		(duplicate_pad_numbers_are_jumpers no)
		(fp_poly
			(pts
				(xy 0.635 1.0668) (xy 0.635 -1.0668) (xy -0.635 -1.0668) (xy -0.635 1.0668)
			)
			(stroke
				(width 0)
				(type default)
			)
			(fill no)
			(layer "F.CrtYd")
		)
		(fp_line
			(start -0.254 -0.508)
			(end 0.254 -0.508)
			(stroke
				(width 0.0254)
				(type default)
			)
			(layer "F.Fab")
		)
		(fp_line
			(start -0.254 0.508)
			(end -0.254 -0.508)
			(stroke
				(width 0.0254)
				(type default)
			)
			(layer "F.Fab")
		)
		(fp_line
			(start 0.254 -0.508)
			(end 0.254 0.508)
			(stroke
				(width 0.0254)
				(type default)
			)
			(layer "F.Fab")
		)
		(fp_line
			(start 0.254 0.508)
			(end -0.254 0.508)
			(stroke
				(width 0.0254)
				(type default)
			)
			(layer "F.Fab")
		)
		(pad "1" smd rect
			(at 0 -0.4191)
			(size 0.508 0.5334)
			(layers "F.Cu" "F.Mask" "F.Paste")
			(net "DDR0_32A_BA2")
		)
		(pad "2" smd rect
			(at 0 0.4191)
			(size 0.508 0.5334)
			(layers "F.Cu" "F.Mask" "F.Paste")
			(net "DDR_VTT")
		)
		(zone
			(layer "F.Cu")
			(hatch none 0.5)
			(connect_pads
				(clearance 0)
			)
			(min_thickness 0.25)
			(keepout
				(tracks not_allowed)
				(vias allowed)
				(pads allowed)
				(copperpour not_allowed)
				(footprints allowed)
			)
			(placement
				(enabled no)
				(sheetname "")
			)
			(fill
				(thermal_gap 0.5)
				(thermal_bridge_width 0.5)
				(island_removal_mode 0)
			)
			(polygon
				(pts
					(xy 81.0514 26.8986) (xy 81.0514 26.9494) (xy 81.0006 26.9494) (xy 81.0006 26.8986)
				)
			)
		)
	)
	(footprint ""
		(layer "F.Cu")
		(at 40.259 49.784)
		(property "Reference" "TP62"
			(at -1.524 -1.87833 0)
			(unlocked yes)
			(layer "F.SilkS")
			(effects
				(font
					(size 0.7874 0.5842)
					(thickness 0.127)
				)
				(justify left)
			)
		)
		(property "Value" "*"
			(at -0.4826 -0.14732 0)
			(unlocked yes)
			(layer "F.Fab")
			(hide yes)
			(effects
				(font
					(size 1.27 0.9652)
					(thickness 0.000001)
				)
				(justify left)
			)
		)
		(property "Device Type" "TP_SMALL"
			(at -0.4826 -0.14732 0)
			(unlocked yes)
			(layer "F.Fab")
			(hide yes)
			(effects
				(font
					(size 1.27 0.9652)
					(thickness 0.000001)
				)
				(justify left)
			)
		)
		(duplicate_pad_numbers_are_jumpers no)
		(fp_line
			(start -0.8636 -0.8636)
			(end -0.8636 0.8636)
			(stroke
				(width 0.1524)
				(type default)
			)
			(layer "F.SilkS")
		)
		(fp_line
			(start -0.8636 0.8636)
			(end 0.8636 0.8636)
			(stroke
				(width 0.1524)
				(type default)
			)
			(layer "F.SilkS")
		)
		(fp_line
			(start 0.8636 -0.8636)
			(end -0.8636 -0.8636)
			(stroke
				(width 0.1524)
				(type default)
			)
			(layer "F.SilkS")
		)
		(fp_line
			(start 0.8636 0.8636)
			(end 0.8636 -0.8636)
			(stroke
				(width 0.1524)
				(type default)
			)
			(layer "F.SilkS")
		)
		(fp_poly
			(pts
				(xy -0.635 -0.635) (xy -0.635 0.635) (xy 0.635 0.635) (xy 0.635 -0.635)
			)
			(stroke
				(width 0)
				(type default)
			)
			(fill no)
			(layer "F.CrtYd")
		)
		(pad "1" smd rect
			(at 0 0)
			(size 1.27 1.27)
			(layers "F.Cu" "F.Mask" "F.Paste")
			(net "EXT_12.0V_PGOOD")
		)
	)
	(footprint ""
		(layer "F.Cu")
		(at 63.6524 54.102)
		(property "Reference" "C183"
			(at -1.397 2.18567 0)
			(unlocked yes)
			(layer "F.SilkS")
			(effects
				(font
					(size 0.7874 0.5842)
					(thickness 0.127)
				)
				(justify left)
			)
		)
		(property "Value" ""
			(at 0 0 0)
			(layer "F.Fab")
			(effects
				(font
					(size 1.27 1.27)
				)
			)
		)
		(duplicate_pad_numbers_are_jumpers no)
		(fp_arc
			(start 0.379679 -0.337515)
			(mid 0.38034 -0.336767)
			(end 0.381 -0.336017)
			(stroke
				(width 0.2032)
				(type default)
			)
			(layer "F.SilkS")
		)
		(fp_arc
			(start 0.381 0.334264)
			(mid 0.380049 0.335357)
			(end 0.379095 0.336448)
			(stroke
				(width 0.2032)
				(type default)
			)
			(layer "F.SilkS")
		)
		(fp_circle
			(center 0 0)
			(end 0.508 0)
			(stroke
				(width 0.2032)
				(type default)
			)
			(fill no)
			(layer "F.SilkS")
		)
		(fp_poly
			(pts
				(xy -2.286 1.397) (xy -2.286 -1.778) (xy 2.286 -1.778) (xy 2.286 1.397)
			)
			(stroke
				(width 0)
				(type default)
			)
			(fill no)
			(layer "F.CrtYd")
		)
		(fp_line
			(start -1.524 -1.27)
			(end 1.524 -1.27)
			(stroke
				(width 0.0254)
				(type default)
			)
			(layer "F.Fab")
		)
		(fp_line
			(start -1.524 1.27)
			(end -1.524 -1.27)
			(stroke
				(width 0.0254)
				(type default)
			)
			(layer "F.Fab")
		)
		(fp_line
			(start 1.524 -1.27)
			(end 1.524 1.27)
			(stroke
				(width 0.0254)
				(type default)
			)
			(layer "F.Fab")
		)
		(fp_line
			(start 1.524 1.27)
			(end -1.524 1.27)
			(stroke
				(width 0.0254)
				(type default)
			)
			(layer "F.Fab")
		)
		(pad "1" smd rect
			(at -1.4224 0 90)
			(size 2.7432 1.3716)
			(layers "F.Cu" "F.Mask" "F.Paste")
			(net "EXT_12.0V")
		)
		(pad "2" smd rect
			(at 1.4224 0 90)
			(size 2.7432 1.3716)
			(layers "F.Cu" "F.Mask" "F.Paste")
			(net "GND")
		)
	)
	(footprint ""
		(layer "F.Cu")
		(at 25.908 38.608 90)
		(property "Reference" "C125"
			(at 0 0 90)
			(layer "F.SilkS")
			(hide yes)
			(effects
				(font
					(size 1.27 1.27)
				)
			)
		)
		(property "Value" "0.1UF"
			(at -0.091846 0.2921 180)
			(unlocked yes)
			(layer "F.Fab")
			(hide yes)
			(effects
				(font
					(size 0.7874 0.5842)
					(thickness 0.2032)
				)
				(justify left)
			)
		)
		(property "Device Type" "CAPC0073"
			(at -0.091846 0.2921 180)
			(unlocked yes)
			(layer "F.Fab")
			(hide yes)
			(effects
				(font
					(size 0.7874 0.5842)
					(thickness 0.2032)
				)
				(justify left)
			)
		)
		(duplicate_pad_numbers_are_jumpers no)
		(fp_poly
			(pts
				(xy 0.635 1.0668) (xy 0.635 -1.0668) (xy -0.635 -1.0668) (xy -0.635 1.0668)
			)
			(stroke
				(width 0)
				(type default)
			)
			(fill no)
			(layer "F.CrtYd")
		)
		(fp_line
			(start 0.254 -0.508)
			(end 0.254 0.508)
			(stroke
				(width 0.0254)
				(type default)
			)
			(layer "F.Fab")
		)
		(fp_line
			(start -0.254 -0.508)
			(end 0.254 -0.508)
			(stroke
				(width 0.0254)
				(type default)
			)
			(layer "F.Fab")
		)
		(fp_line
			(start 0.254 0.508)
			(end -0.254 0.508)
			(stroke
				(width 0.0254)
				(type default)
			)
			(layer "F.Fab")
		)
		(fp_line
			(start -0.254 0.508)
			(end -0.254 -0.508)
			(stroke
				(width 0.0254)
				(type default)
			)
			(layer "F.Fab")
		)
		(pad "1" smd rect
			(at 0 -0.4191 90)
			(size 0.508 0.5334)
			(layers "F.Cu" "F.Mask" "F.Paste")
			(net "NFP_VDD_CORE_SENSE_VSS")
		)
		(pad "2" smd rect
			(at 0 0.4191 90)
			(size 0.508 0.5334)
			(layers "F.Cu" "F.Mask" "F.Paste")
			(net "NFP_VDD_CORE_IMON")
		)
		(zone
			(layer "F.Cu")
			(hatch none 0.5)
			(connect_pads
				(clearance 0)
			)
			(min_thickness 0.25)
			(keepout
				(tracks not_allowed)
				(vias allowed)
				(pads allowed)
				(copperpour not_allowed)
				(footprints allowed)
			)
			(placement
				(enabled no)
				(sheetname "")
			)
			(fill
				(thermal_gap 0.5)
				(thermal_bridge_width 0.5)
				(island_removal_mode 0)
			)
			(polygon
				(pts
					(xy 25.8826 38.5826) (xy 25.9334 38.5826) (xy 25.9334 38.6334) (xy 25.8826 38.6334)
				)
			)
		)
	)
	(footprint ""
		(layer "F.Cu")
		(at 36.2712 40.767 90)
		(property "Reference" "R324"
			(at 0 0 90)
			(layer "F.SilkS")
			(hide yes)
			(effects
				(font
					(size 1.27 1.27)
				)
			)
		)
		(property "Value" "86.6K"
			(at -0.148158 1.3462 180)
			(unlocked yes)
			(layer "F.Fab")
			(hide yes)
			(effects
				(font
					(size 1.27 0.9652)
					(thickness 0.000001)
				)
				(justify left)
			)
		)
		(property "Device Type" "REST0029"
			(at -0.148158 1.3462 180)
			(unlocked yes)
			(layer "F.Fab")
			(hide yes)
			(effects
				(font
					(size 1.27 0.9652)
					(thickness 0.000001)
				)
				(justify left)
			)
		)
		(duplicate_pad_numbers_are_jumpers no)
		(fp_poly
			(pts
				(xy 0.635 1.0668) (xy 0.635 -1.0668) (xy -0.635 -1.0668) (xy -0.635 1.0668)
			)
			(stroke
				(width 0)
				(type default)
			)
			(fill no)
			(layer "F.CrtYd")
		)
		(fp_line
			(start 0.254 -0.508)
			(end 0.254 0.508)
			(stroke
				(width 0.0254)
				(type default)
			)
			(layer "F.Fab")
		)
		(fp_line
			(start -0.254 -0.508)
			(end 0.254 -0.508)
			(stroke
				(width 0.0254)
				(type default)
			)
			(layer "F.Fab")
		)
		(fp_line
			(start 0.254 0.508)
			(end -0.254 0.508)
			(stroke
				(width 0.0254)
				(type default)
			)
			(layer "F.Fab")
		)
		(fp_line
			(start -0.254 0.508)
			(end -0.254 -0.508)
			(stroke
				(width 0.0254)
				(type default)
			)
			(layer "F.Fab")
		)
		(pad "1" smd rect
			(at 0 -0.4191 90)
			(size 0.508 0.5334)
			(layers "F.Cu" "F.Mask" "F.Paste")
			(net "10N2528")
		)
		(pad "2" smd rect
			(at 0 0.4191 90)
			(size 0.508 0.5334)
			(layers "F.Cu" "F.Mask" "F.Paste")
			(net "NFP_VDD_CORE_ISEN2_P")
		)
		(zone
			(layer "F.Cu")
			(hatch none 0.5)
			(connect_pads
				(clearance 0)
			)
			(min_thickness 0.25)
			(keepout
				(tracks not_allowed)
				(vias allowed)
				(pads allowed)
				(copperpour not_allowed)
				(footprints allowed)
			)
			(placement
				(enabled no)
				(sheetname "")
			)
			(fill
				(thermal_gap 0.5)
				(thermal_bridge_width 0.5)
				(island_removal_mode 0)
			)
			(polygon
				(pts
					(xy 36.2458 40.7416) (xy 36.2966 40.7416) (xy 36.2966 40.7924) (xy 36.2458 40.7924)
				)
			)
		)
	)
	(footprint ""
		(layer "F.Cu")
		(at 44.196 51.816)
		(property "Reference" "R267"
			(at 0 0 0)
			(layer "F.SilkS")
			(hide yes)
			(effects
				(font
					(size 1.27 1.27)
				)
			)
		)
		(property "Value" "1.5K"
			(at -0.148158 1.3462 90)
			(unlocked yes)
			(layer "F.Fab")
			(hide yes)
			(effects
				(font
					(size 1.27 0.9652)
					(thickness 0.000001)
				)
				(justify left)
			)
		)
		(property "Device Type" "REST0055"
			(at -0.148158 1.3462 90)
			(unlocked yes)
			(layer "F.Fab")
			(hide yes)
			(effects
				(font
					(size 1.27 0.9652)
					(thickness 0.000001)
				)
				(justify left)
			)
		)
		(duplicate_pad_numbers_are_jumpers no)
		(fp_poly
			(pts
				(xy 0.635 1.0668) (xy 0.635 -1.0668) (xy -0.635 -1.0668) (xy -0.635 1.0668)
			)
			(stroke
				(width 0)
				(type default)
			)
			(fill no)
			(layer "F.CrtYd")
		)
		(fp_line
			(start -0.254 -0.508)
			(end 0.254 -0.508)
			(stroke
				(width 0.0254)
				(type default)
			)
			(layer "F.Fab")
		)
		(fp_line
			(start -0.254 0.508)
			(end -0.254 -0.508)
			(stroke
				(width 0.0254)
				(type default)
			)
			(layer "F.Fab")
		)
		(fp_line
			(start 0.254 -0.508)
			(end 0.254 0.508)
			(stroke
				(width 0.0254)
				(type default)
			)
			(layer "F.Fab")
		)
		(fp_line
			(start 0.254 0.508)
			(end -0.254 0.508)
			(stroke
				(width 0.0254)
				(type default)
			)
			(layer "F.Fab")
		)
		(pad "1" smd rect
			(at 0 -0.4191)
			(size 0.508 0.5334)
			(layers "F.Cu" "F.Mask" "F.Paste")
			(net "EXT_3.3V_THRESHOLD")
		)
		(pad "2" smd rect
			(at 0 0.4191)
			(size 0.508 0.5334)
			(layers "F.Cu" "F.Mask" "F.Paste")
			(net "EXT_3.3V")
		)
		(zone
			(layer "F.Cu")
			(hatch none 0.5)
			(connect_pads
				(clearance 0)
			)
			(min_thickness 0.25)
			(keepout
				(tracks not_allowed)
				(vias allowed)
				(pads allowed)
				(copperpour not_allowed)
				(footprints allowed)
			)
			(placement
				(enabled no)
				(sheetname "")
			)
			(fill
				(thermal_gap 0.5)
				(thermal_bridge_width 0.5)
				(island_removal_mode 0)
			)
			(polygon
				(pts
					(xy 44.2214 51.7906) (xy 44.2214 51.8414) (xy 44.1706 51.8414) (xy 44.1706 51.7906)
				)
			)
		)
	)
	(footprint ""
		(layer "F.Cu")
		(at 23.241 16.8529)
		(property "Reference" "R22"
			(at 0 0 0)
			(layer "F.SilkS")
			(hide yes)
			(effects
				(font
					(size 1.27 1.27)
				)
			)
		)
		(property "Value" "4.75K"
			(at -0.148158 1.3462 90)
			(unlocked yes)
			(layer "F.Fab")
			(hide yes)
			(effects
				(font
					(size 1.27 0.9652)
					(thickness 0.000001)
				)
				(justify left)
			)
		)
		(property "Device Type" "REST4024"
			(at -0.148158 1.3462 90)
			(unlocked yes)
			(layer "F.Fab")
			(hide yes)
			(effects
				(font
					(size 1.27 0.9652)
					(thickness 0.000001)
				)
				(justify left)
			)
		)
		(duplicate_pad_numbers_are_jumpers no)
		(fp_poly
			(pts
				(xy 0.635 1.0668) (xy 0.635 -1.0668) (xy -0.635 -1.0668) (xy -0.635 1.0668)
			)
			(stroke
				(width 0)
				(type default)
			)
			(fill no)
			(layer "F.CrtYd")
		)
		(fp_line
			(start -0.254 -0.508)
			(end 0.254 -0.508)
			(stroke
				(width 0.0254)
				(type default)
			)
			(layer "F.Fab")
		)
		(fp_line
			(start -0.254 0.508)
			(end -0.254 -0.508)
			(stroke
				(width 0.0254)
				(type default)
			)
			(layer "F.Fab")
		)
		(fp_line
			(start 0.254 -0.508)
			(end 0.254 0.508)
			(stroke
				(width 0.0254)
				(type default)
			)
			(layer "F.Fab")
		)
		(fp_line
			(start 0.254 0.508)
			(end -0.254 0.508)
			(stroke
				(width 0.0254)
				(type default)
			)
			(layer "F.Fab")
		)
		(pad "1" smd rect
			(at 0 -0.4191)
			(size 0.508 0.5334)
			(layers "F.Cu" "F.Mask" "F.Paste")
			(net "VDD_3.3V")
		)
		(pad "2" smd rect
			(at 0 0.4191)
			(size 0.508 0.5334)
			(layers "F.Cu" "F.Mask" "F.Paste")
			(net "NFP_ARM_SPI_FLASH_SCK")
		)
		(zone
			(layer "F.Cu")
			(hatch none 0.5)
			(connect_pads
				(clearance 0)
			)
			(min_thickness 0.25)
			(keepout
				(tracks not_allowed)
				(vias allowed)
				(pads allowed)
				(copperpour not_allowed)
				(footprints allowed)
			)
			(placement
				(enabled no)
				(sheetname "")
			)
			(fill
				(thermal_gap 0.5)
				(thermal_bridge_width 0.5)
				(island_removal_mode 0)
			)
			(polygon
				(pts
					(xy 23.2664 16.8275) (xy 23.2664 16.8783) (xy 23.2156 16.8783) (xy 23.2156 16.8275)
				)
			)
		)
	)
	(footprint ""
		(layer "F.Cu")
		(at 82.169 35.687 180)
		(property "Reference" "R337"
			(at 0 0 180)
			(layer "F.SilkS")
			(hide yes)
			(effects
				(font
					(size 1.27 1.27)
				)
			)
		)
		(property "Value" "0"
			(at -0.148158 1.3462 270)
			(unlocked yes)
			(layer "F.Fab")
			(hide yes)
			(effects
				(font
					(size 1.27 0.9652)
					(thickness 0.000001)
				)
				(justify left)
			)
		)
		(property "Device Type" "REST1111"
			(at -0.148158 1.3462 270)
			(unlocked yes)
			(layer "F.Fab")
			(hide yes)
			(effects
				(font
					(size 1.27 0.9652)
					(thickness 0.000001)
				)
				(justify left)
			)
		)
		(duplicate_pad_numbers_are_jumpers no)
		(fp_poly
			(pts
				(xy 0.635 1.0668) (xy 0.635 -1.0668) (xy -0.635 -1.0668) (xy -0.635 1.0668)
			)
			(stroke
				(width 0)
				(type default)
			)
			(fill no)
			(layer "F.CrtYd")
		)
		(fp_line
			(start 0.254 0.508)
			(end -0.254 0.508)
			(stroke
				(width 0.0254)
				(type default)
			)
			(layer "F.Fab")
		)
		(fp_line
			(start 0.254 -0.508)
			(end 0.254 0.508)
			(stroke
				(width 0.0254)
				(type default)
			)
			(layer "F.Fab")
		)
		(fp_line
			(start -0.254 0.508)
			(end -0.254 -0.508)
			(stroke
				(width 0.0254)
				(type default)
			)
			(layer "F.Fab")
		)
		(fp_line
			(start -0.254 -0.508)
			(end 0.254 -0.508)
			(stroke
				(width 0.0254)
				(type default)
			)
			(layer "F.Fab")
		)
		(pad "1" smd rect
			(at 0 -0.4191 180)
			(size 0.508 0.5334)
			(layers "F.Cu" "F.Mask" "F.Paste")
			(net "11N2199")
		)
		(pad "2" smd rect
			(at 0 0.4191 180)
			(size 0.508 0.5334)
			(layers "F.Cu" "F.Mask" "F.Paste")
			(net "DDR_VTT")
		)
		(zone
			(layer "F.Cu")
			(hatch none 0.5)
			(connect_pads
				(clearance 0)
			)
			(min_thickness 0.25)
			(keepout
				(tracks not_allowed)
				(vias allowed)
				(pads allowed)
				(copperpour not_allowed)
				(footprints allowed)
			)
			(placement
				(enabled no)
				(sheetname "")
			)
			(fill
				(thermal_gap 0.5)
				(thermal_bridge_width 0.5)
				(island_removal_mode 0)
			)
			(polygon
				(pts
					(xy 82.1436 35.7124) (xy 82.1436 35.6616) (xy 82.1944 35.6616) (xy 82.1944 35.7124)
				)
			)
		)
	)
	(footprint ""
		(layer "F.Cu")
		(at 79.248 26.924)
		(property "Reference" "R226"
			(at 0 0 0)
			(layer "F.SilkS")
			(hide yes)
			(effects
				(font
					(size 1.27 1.27)
				)
			)
		)
		(property "Value" "39.0"
			(at -0.148158 1.3462 90)
			(unlocked yes)
			(layer "F.Fab")
			(hide yes)
			(effects
				(font
					(size 1.27 0.9652)
					(thickness 0.000001)
				)
				(justify left)
			)
		)
		(property "Device Type" "REST0108"
			(at -0.148158 1.3462 90)
			(unlocked yes)
			(layer "F.Fab")
			(hide yes)
			(effects
				(font
					(size 1.27 0.9652)
					(thickness 0.000001)
				)
				(justify left)
			)
		)
		(duplicate_pad_numbers_are_jumpers no)
		(fp_poly
			(pts
				(xy 0.635 1.0668) (xy 0.635 -1.0668) (xy -0.635 -1.0668) (xy -0.635 1.0668)
			)
			(stroke
				(width 0)
				(type default)
			)
			(fill no)
			(layer "F.CrtYd")
		)
		(fp_line
			(start -0.254 -0.508)
			(end 0.254 -0.508)
			(stroke
				(width 0.0254)
				(type default)
			)
			(layer "F.Fab")
		)
		(fp_line
			(start -0.254 0.508)
			(end -0.254 -0.508)
			(stroke
				(width 0.0254)
				(type default)
			)
			(layer "F.Fab")
		)
		(fp_line
			(start 0.254 -0.508)
			(end 0.254 0.508)
			(stroke
				(width 0.0254)
				(type default)
			)
			(layer "F.Fab")
		)
		(fp_line
			(start 0.254 0.508)
			(end -0.254 0.508)
			(stroke
				(width 0.0254)
				(type default)
			)
			(layer "F.Fab")
		)
		(pad "1" smd rect
			(at 0 -0.4191)
			(size 0.508 0.5334)
			(layers "F.Cu" "F.Mask" "F.Paste")
			(net "DDR0_32A_CAS_L")
		)
		(pad "2" smd rect
			(at 0 0.4191)
			(size 0.508 0.5334)
			(layers "F.Cu" "F.Mask" "F.Paste")
			(net "DDR_VTT")
		)
		(zone
			(layer "F.Cu")
			(hatch none 0.5)
			(connect_pads
				(clearance 0)
			)
			(min_thickness 0.25)
			(keepout
				(tracks not_allowed)
				(vias allowed)
				(pads allowed)
				(copperpour not_allowed)
				(footprints allowed)
			)
			(placement
				(enabled no)
				(sheetname "")
			)
			(fill
				(thermal_gap 0.5)
				(thermal_bridge_width 0.5)
				(island_removal_mode 0)
			)
			(polygon
				(pts
					(xy 79.2734 26.8986) (xy 79.2734 26.9494) (xy 79.2226 26.9494) (xy 79.2226 26.8986)
				)
			)
		)
	)
	(footprint ""
		(layer "F.Cu")
		(at 24.638 35.687 180)
		(property "Reference" "R69"
			(at 0 0 180)
			(layer "F.SilkS")
			(hide yes)
			(effects
				(font
					(size 1.27 1.27)
				)
			)
		)
		(property "Value" "4.75K"
			(at -0.148158 1.3462 270)
			(unlocked yes)
			(layer "F.Fab")
			(hide yes)
			(effects
				(font
					(size 1.27 0.9652)
					(thickness 0.000001)
				)
				(justify left)
			)
		)
		(property "Device Type" "REST4024"
			(at -0.148158 1.3462 270)
			(unlocked yes)
			(layer "F.Fab")
			(hide yes)
			(effects
				(font
					(size 1.27 0.9652)
					(thickness 0.000001)
				)
				(justify left)
			)
		)
		(duplicate_pad_numbers_are_jumpers no)
		(fp_poly
			(pts
				(xy 0.635 1.0668) (xy 0.635 -1.0668) (xy -0.635 -1.0668) (xy -0.635 1.0668)
			)
			(stroke
				(width 0)
				(type default)
			)
			(fill no)
			(layer "F.CrtYd")
		)
		(fp_line
			(start 0.254 0.508)
			(end -0.254 0.508)
			(stroke
				(width 0.0254)
				(type default)
			)
			(layer "F.Fab")
		)
		(fp_line
			(start 0.254 -0.508)
			(end 0.254 0.508)
			(stroke
				(width 0.0254)
				(type default)
			)
			(layer "F.Fab")
		)
		(fp_line
			(start -0.254 0.508)
			(end -0.254 -0.508)
			(stroke
				(width 0.0254)
				(type default)
			)
			(layer "F.Fab")
		)
		(fp_line
			(start -0.254 -0.508)
			(end 0.254 -0.508)
			(stroke
				(width 0.0254)
				(type default)
			)
			(layer "F.Fab")
		)
		(pad "1" smd rect
			(at 0 -0.4191 180)
			(size 0.508 0.5334)
			(layers "F.Cu" "F.Mask" "F.Paste")
			(net "EXT_3.3V")
		)
		(pad "2" smd rect
			(at 0 0.4191 180)
			(size 0.508 0.5334)
			(layers "F.Cu" "F.Mask" "F.Paste")
			(net "DEBUG_CPLD_PGRM_JTAG_TMS")
		)
		(zone
			(layer "F.Cu")
			(hatch none 0.5)
			(connect_pads
				(clearance 0)
			)
			(min_thickness 0.25)
			(keepout
				(tracks not_allowed)
				(vias allowed)
				(pads allowed)
				(copperpour not_allowed)
				(footprints allowed)
			)
			(placement
				(enabled no)
				(sheetname "")
			)
			(fill
				(thermal_gap 0.5)
				(thermal_bridge_width 0.5)
				(island_removal_mode 0)
			)
			(polygon
				(pts
					(xy 24.6126 35.7124) (xy 24.6126 35.6616) (xy 24.6634 35.6616) (xy 24.6634 35.7124)
				)
			)
		)
	)
	(footprint ""
		(layer "F.Cu")
		(at 84.582 32.576414)
		(property "Reference" "R214"
			(at 1.04267 1.586586 90)
			(unlocked yes)
			(layer "F.SilkS")
			(effects
				(font
					(size 0.7874 0.5842)
					(thickness 0.127)
				)
				(justify left)
			)
		)
		(property "Value" "39.0"
			(at -0.148158 1.3462 90)
			(unlocked yes)
			(layer "F.Fab")
			(hide yes)
			(effects
				(font
					(size 1.27 0.9652)
					(thickness 0.000001)
				)
				(justify left)
			)
		)
		(property "Device Type" "REST0108"
			(at -0.148158 1.3462 90)
			(unlocked yes)
			(layer "F.Fab")
			(hide yes)
			(effects
				(font
					(size 1.27 0.9652)
					(thickness 0.000001)
				)
				(justify left)
			)
		)
		(duplicate_pad_numbers_are_jumpers no)
		(fp_poly
			(pts
				(xy 0.635 1.0668) (xy 0.635 -1.0668) (xy -0.635 -1.0668) (xy -0.635 1.0668)
			)
			(stroke
				(width 0)
				(type default)
			)
			(fill no)
			(layer "F.CrtYd")
		)
		(fp_line
			(start -0.254 -0.508)
			(end 0.254 -0.508)
			(stroke
				(width 0.0254)
				(type default)
			)
			(layer "F.Fab")
		)
		(fp_line
			(start -0.254 0.508)
			(end -0.254 -0.508)
			(stroke
				(width 0.0254)
				(type default)
			)
			(layer "F.Fab")
		)
		(fp_line
			(start 0.254 -0.508)
			(end 0.254 0.508)
			(stroke
				(width 0.0254)
				(type default)
			)
			(layer "F.Fab")
		)
		(fp_line
			(start 0.254 0.508)
			(end -0.254 0.508)
			(stroke
				(width 0.0254)
				(type default)
			)
			(layer "F.Fab")
		)
		(pad "1" smd rect
			(at 0 -0.4191)
			(size 0.508 0.5334)
			(layers "F.Cu" "F.Mask" "F.Paste")
			(net "DDR0_32A_A8")
		)
		(pad "2" smd rect
			(at 0 0.4191)
			(size 0.508 0.5334)
			(layers "F.Cu" "F.Mask" "F.Paste")
			(net "DDR_VTT")
		)
		(zone
			(layer "F.Cu")
			(hatch none 0.5)
			(connect_pads
				(clearance 0)
			)
			(min_thickness 0.25)
			(keepout
				(tracks not_allowed)
				(vias allowed)
				(pads allowed)
				(copperpour not_allowed)
				(footprints allowed)
			)
			(placement
				(enabled no)
				(sheetname "")
			)
			(fill
				(thermal_gap 0.5)
				(thermal_bridge_width 0.5)
				(island_removal_mode 0)
			)
			(polygon
				(pts
					(xy 84.6074 32.551014) (xy 84.6074 32.601814) (xy 84.5566 32.601814) (xy 84.5566 32.551014)
				)
			)
		)
	)
	(footprint ""
		(layer "F.Cu")
		(at 0.254 36.83)
		(property "Reference" "TP14"
			(at -2.00533 1.016 90)
			(unlocked yes)
			(layer "F.SilkS")
			(effects
				(font
					(size 0.7874 0.5842)
					(thickness 0.127)
				)
				(justify left)
			)
		)
		(property "Value" "*"
			(at -0.4826 -0.14732 0)
			(unlocked yes)
			(layer "F.Fab")
			(hide yes)
			(effects
				(font
					(size 1.27 0.9652)
					(thickness 0.000001)
				)
				(justify left)
			)
		)
		(property "Device Type" "TP_SMALL"
			(at -0.4826 -0.14732 0)
			(unlocked yes)
			(layer "F.Fab")
			(hide yes)
			(effects
				(font
					(size 1.27 0.9652)
					(thickness 0.000001)
				)
				(justify left)
			)
		)
		(duplicate_pad_numbers_are_jumpers no)
		(fp_line
			(start -0.8636 -0.8636)
			(end -0.8636 0.8636)
			(stroke
				(width 0.1524)
				(type default)
			)
			(layer "F.SilkS")
		)
		(fp_line
			(start -0.8636 0.8636)
			(end 0.8636 0.8636)
			(stroke
				(width 0.1524)
				(type default)
			)
			(layer "F.SilkS")
		)
		(fp_line
			(start 0.8636 -0.8636)
			(end -0.8636 -0.8636)
			(stroke
				(width 0.1524)
				(type default)
			)
			(layer "F.SilkS")
		)
		(fp_line
			(start 0.8636 0.8636)
			(end 0.8636 -0.8636)
			(stroke
				(width 0.1524)
				(type default)
			)
			(layer "F.SilkS")
		)
		(fp_poly
			(pts
				(xy -0.635 -0.635) (xy -0.635 0.635) (xy 0.635 0.635) (xy 0.635 -0.635)
			)
			(stroke
				(width 0)
				(type default)
			)
			(fill no)
			(layer "F.CrtYd")
		)
		(pad "1" smd rect
			(at 0 0)
			(size 1.27 1.27)
			(layers "F.Cu" "F.Mask" "F.Paste")
			(net "PWR_GOOD_LED_L")
		)
	)
	(footprint ""
		(layer "F.Cu")
		(at 23.2537 41.021 90)
		(property "Reference" "C144"
			(at -3.83667 0.4953 0)
			(unlocked yes)
			(layer "F.SilkS")
			(effects
				(font
					(size 0.7874 0.5842)
					(thickness 0.127)
				)
				(justify left)
			)
		)
		(property "Value" ""
			(at 0 0 90)
			(layer "F.Fab")
			(effects
				(font
					(size 1.27 1.27)
				)
			)
		)
		(duplicate_pad_numbers_are_jumpers no)
		(fp_arc
			(start 0 -0.508)
			(mid 0.209 -0.463015)
			(end 0.381 -0.336042)
			(stroke
				(width 0.2032)
				(type default)
			)
			(layer "F.SilkS")
		)
		(fp_arc
			(start -0.381 -0.335991)
			(mid -0.209012 -0.462996)
			(end 0 -0.508)
			(stroke
				(width 0.2032)
				(type default)
			)
			(layer "F.SilkS")
		)
		(fp_arc
			(start 0.381 0.336017)
			(mid 0.20901 0.463015)
			(end 0 0.508)
			(stroke
				(width 0.2032)
				(type default)
			)
			(layer "F.SilkS")
		)
		(fp_arc
			(start 0 0.508)
			(mid -0.209017 0.463007)
			(end -0.381 0.335991)
			(stroke
				(width 0.2032)
				(type default)
			)
			(layer "F.SilkS")
		)
		(fp_circle
			(center 0 0)
			(end 0 0.508)
			(stroke
				(width 0.2032)
				(type default)
			)
			(fill no)
			(layer "F.SilkS")
		)
		(fp_poly
			(pts
				(xy -2.286 1.778) (xy -2.286 -1.778) (xy 2.286 -1.778) (xy 2.286 1.778)
			)
			(stroke
				(width 0)
				(type default)
			)
			(fill no)
			(layer "F.CrtYd")
		)
		(fp_line
			(start 1.524 -1.27)
			(end 1.524 1.27)
			(stroke
				(width 0.0254)
				(type default)
			)
			(layer "F.Fab")
		)
		(fp_line
			(start -1.524 -1.27)
			(end 1.524 -1.27)
			(stroke
				(width 0.0254)
				(type default)
			)
			(layer "F.Fab")
		)
		(fp_line
			(start 1.524 1.27)
			(end -1.524 1.27)
			(stroke
				(width 0.0254)
				(type default)
			)
			(layer "F.Fab")
		)
		(fp_line
			(start -1.524 1.27)
			(end -1.524 -1.27)
			(stroke
				(width 0.0254)
				(type default)
			)
			(layer "F.Fab")
		)
		(pad "1" smd rect
			(at -1.4224 0 180)
			(size 2.7432 1.3716)
			(layers "F.Cu" "F.Mask" "F.Paste")
			(net "10N2407")
		)
		(pad "2" smd rect
			(at 1.4224 0 180)
			(size 2.7432 1.3716)
			(layers "F.Cu" "F.Mask" "F.Paste")
			(net "GND")
		)
	)
	(footprint ""
		(layer "F.Cu")
		(at 25.2857 40.894)
		(property "Reference" "C82"
			(at 0 0 0)
			(layer "F.SilkS")
			(hide yes)
			(effects
				(font
					(size 1.27 1.27)
				)
			)
		)
		(property "Value" "1500PF"
			(at -0.091846 0.2921 90)
			(unlocked yes)
			(layer "F.Fab")
			(hide yes)
			(effects
				(font
					(size 0.7874 0.5842)
					(thickness 0.2032)
				)
				(justify left)
			)
		)
		(property "Device Type" "CAPC0088"
			(at -0.091846 0.2921 90)
			(unlocked yes)
			(layer "F.Fab")
			(hide yes)
			(effects
				(font
					(size 0.7874 0.5842)
					(thickness 0.2032)
				)
				(justify left)
			)
		)
		(duplicate_pad_numbers_are_jumpers no)
		(fp_poly
			(pts
				(xy 0.635 1.0668) (xy 0.635 -1.0668) (xy -0.635 -1.0668) (xy -0.635 1.0668)
			)
			(stroke
				(width 0)
				(type default)
			)
			(fill no)
			(layer "F.CrtYd")
		)
		(fp_line
			(start -0.254 -0.508)
			(end 0.254 -0.508)
			(stroke
				(width 0.0254)
				(type default)
			)
			(layer "F.Fab")
		)
		(fp_line
			(start -0.254 0.508)
			(end -0.254 -0.508)
			(stroke
				(width 0.0254)
				(type default)
			)
			(layer "F.Fab")
		)
		(fp_line
			(start 0.254 -0.508)
			(end 0.254 0.508)
			(stroke
				(width 0.0254)
				(type default)
			)
			(layer "F.Fab")
		)
		(fp_line
			(start 0.254 0.508)
			(end -0.254 0.508)
			(stroke
				(width 0.0254)
				(type default)
			)
			(layer "F.Fab")
		)
		(pad "1" smd rect
			(at 0 -0.4191)
			(size 0.508 0.5334)
			(layers "F.Cu" "F.Mask" "F.Paste")
			(net "NFP_VDD_CORE_SENSE_VSS")
		)
		(pad "2" smd rect
			(at 0 0.4191)
			(size 0.508 0.5334)
			(layers "F.Cu" "F.Mask" "F.Paste")
			(net "GND")
		)
		(zone
			(layer "F.Cu")
			(hatch none 0.5)
			(connect_pads
				(clearance 0)
			)
			(min_thickness 0.25)
			(keepout
				(tracks not_allowed)
				(vias allowed)
				(pads allowed)
				(copperpour not_allowed)
				(footprints allowed)
			)
			(placement
				(enabled no)
				(sheetname "")
			)
			(fill
				(thermal_gap 0.5)
				(thermal_bridge_width 0.5)
				(island_removal_mode 0)
			)
			(polygon
				(pts
					(xy 25.3111 40.8686) (xy 25.3111 40.9194) (xy 25.2603 40.9194) (xy 25.2603 40.8686)
				)
			)
		)
	)
	(footprint ""
		(layer "F.Cu")
		(at 83.185 47.625 90)
		(property "Reference" "Q1"
			(at 1.62433 2.159 0)
			(unlocked yes)
			(layer "F.SilkS")
			(effects
				(font
					(size 0.7874 0.5842)
					(thickness 0.127)
				)
				(justify left)
			)
		)
		(property "Value" "*"
			(at -0.4826 -0.148107 90)
			(unlocked yes)
			(layer "F.Fab")
			(hide yes)
			(effects
				(font
					(size 1.27 0.9652)
					(thickness 0.000001)
				)
				(justify left)
			)
		)
		(property "Device Type" "TRAN0028"
			(at -0.4826 -0.148107 90)
			(unlocked yes)
			(layer "F.Fab")
			(hide yes)
			(effects
				(font
					(size 1.27 0.9652)
					(thickness 0.000001)
				)
				(justify left)
			)
		)
		(duplicate_pad_numbers_are_jumpers no)
		(fp_line
			(start 1.905 -1.905)
			(end -1.905 -1.905)
			(stroke
				(width 0.1524)
				(type default)
			)
			(layer "F.SilkS")
		)
		(fp_line
			(start -0.7112 -1.905)
			(end -1.905 -1.905)
			(stroke
				(width 0.1524)
				(type default)
			)
			(layer "F.SilkS")
		)
		(fp_line
			(start -1.905 -1.905)
			(end -1.905 -1.524)
			(stroke
				(width 0.1524)
				(type default)
			)
			(layer "F.SilkS")
		)
		(fp_line
			(start 1.905 -1.524)
			(end 1.905 -1.905)
			(stroke
				(width 0.1524)
				(type default)
			)
			(layer "F.SilkS")
		)
		(fp_line
			(start -1.905 1.524)
			(end -1.905 1.905)
			(stroke
				(width 0.1524)
				(type default)
			)
			(layer "F.SilkS")
		)
		(fp_line
			(start 1.905 1.905)
			(end 1.905 1.524)
			(stroke
				(width 0.1524)
				(type default)
			)
			(layer "F.SilkS")
		)
		(fp_line
			(start -1.378915 1.905)
			(end 1.905 1.905)
			(stroke
				(width 0.1524)
				(type default)
			)
			(layer "F.SilkS")
		)
		(fp_line
			(start -1.905 1.905)
			(end 1.905 1.905)
			(stroke
				(width 0.1524)
				(type default)
			)
			(layer "F.SilkS")
		)
		(fp_arc
			(start -2.7178 -1.1684)
			(mid -2.717421 -1.182162)
			(end -2.716301 -1.195883)
			(stroke
				(width 0.1524)
				(type default)
			)
			(layer "F.SilkS")
		)
		(fp_arc
			(start -2.70571 -1.090905)
			(mid -2.714762 -1.129183)
			(end -2.7178 -1.1684)
			(stroke
				(width 0.1524)
				(type default)
			)
			(layer "F.SilkS")
		)
		(fp_circle
			(center -2.4638 -1.1684)
			(end -2.4638 -0.9144)
			(stroke
				(width 0.1524)
				(type default)
			)
			(fill no)
			(layer "F.SilkS")
		)
		(fp_poly
			(pts
				(xy -2.0066 -1.17856) (xy -2.0066 -0.77216) (xy -1.1938 -0.77216) (xy -1.1938 -1.17856)
			)
			(stroke
				(width 0)
				(type default)
			)
			(fill yes)
			(layer "F.Paste")
		)
		(fp_poly
			(pts
				(xy 0.1524 -0.635) (xy 0.762 -0.635) (xy 0.762 -1.2446) (xy 0.1524 -1.2446)
			)
			(stroke
				(width 0)
				(type default)
			)
			(fill yes)
			(layer "F.Paste")
		)
		(fp_poly
			(pts
				(xy -0.1524 -0.635) (xy -0.762 -0.635) (xy -0.762 -1.2446) (xy -0.1524 -1.2446)
			)
			(stroke
				(width 0)
				(type default)
			)
			(fill yes)
			(layer "F.Paste")
		)
		(fp_poly
			(pts
				(xy -2.0066 -0.52832) (xy -2.0066 -0.12192) (xy -1.1938 -0.12192) (xy -1.1938 -0.52832)
			)
			(stroke
				(width 0)
				(type default)
			)
			(fill yes)
			(layer "F.Paste")
		)
		(fp_poly
			(pts
				(xy 0.1524 0.3302) (xy 0.762 0.3302) (xy 0.762 -0.3302) (xy 0.1524 -0.3302)
			)
			(stroke
				(width 0)
				(type default)
			)
			(fill yes)
			(layer "F.Paste")
		)
		(fp_poly
			(pts
				(xy -0.1524 0.3302) (xy -0.762 0.3302) (xy -0.762 -0.3302) (xy -0.1524 -0.3302)
			)
			(stroke
				(width 0)
				(type default)
			)
			(fill yes)
			(layer "F.Paste")
		)
		(fp_poly
			(pts
				(xy 0.1524 0.635) (xy 0.762 0.635) (xy 0.762 1.2446) (xy 0.1524 1.2446)
			)
			(stroke
				(width 0)
				(type default)
			)
			(fill yes)
			(layer "F.Paste")
		)
		(fp_poly
			(pts
				(xy -0.1524 0.635) (xy -0.762 0.635) (xy -0.762 1.2446) (xy -0.1524 1.2446)
			)
			(stroke
				(width 0)
				(type default)
			)
			(fill yes)
			(layer "F.Paste")
		)
		(fp_poly
			(pts
				(xy -2.54 1.752194) (xy 2.54 1.752194) (xy 2.54 -2.286) (xy -2.54 -2.286)
			)
			(stroke
				(width 0)
				(type default)
			)
			(fill no)
			(layer "F.CrtYd")
		)
		(fp_line
			(start 1.7018 -1.7018)
			(end -1.7018 -1.7018)
			(stroke
				(width 0.1524)
				(type default)
			)
			(layer "F.Fab")
		)
		(fp_line
			(start -1.7018 -1.7018)
			(end -1.7018 1.7018)
			(stroke
				(width 0.1524)
				(type default)
			)
			(layer "F.Fab")
		)
		(fp_line
			(start 1.7018 1.7018)
			(end 1.7018 -1.7018)
			(stroke
				(width 0.1524)
				(type default)
			)
			(layer "F.Fab")
		)
		(fp_line
			(start -1.7018 1.7018)
			(end 1.7018 1.7018)
			(stroke
				(width 0.1524)
				(type default)
			)
			(layer "F.Fab")
		)
		(fp_circle
			(center -1.27 -1.27)
			(end -1.27 -1.016)
			(stroke
				(width 0.1524)
				(type default)
			)
			(fill no)
			(layer "F.Fab")
		)
		(pad "1" smd custom
			(at -1.6002 -0.97536 90)
			(size 0.2032 0.2032)
			(layers "F.Cu" "F.Mask" "F.Paste")
			(net "EXT_12.0V")
			(options
				(clearance outline)
				(anchor circle)
			)
			(primitives
				(gr_poly
					(pts
						(xy -0.4064 0.52832) (xy 0.4064 0.52832) (xy 0.4064 -0.52832) (xy -0.4064 -0.52832) (xy -0.4064 -0.12192)
						(xy 0.1778 -0.12192) (xy 0.1778 0.12192) (xy -0.4064 0.12192)
					)
					(width 0)
					(fill yes)
				)
			)
		)
		(pad "2" smd circle
			(at -1.524 -0.381 90)
			(size 0 0)
			(layers "F.Cu" "F.Mask" "F.Paste")
			(net "EXT_12.0V")
			(padstack
				(mode custom)
				(layer "In1.Cu"
					(shape circle)
					(size 0 0)
					(zone_connect -1)
				)
				(layer "In2.Cu"
					(shape circle)
					(size 0 0)
					(zone_connect -1)
				)
				(layer "In3.Cu"
					(shape circle)
					(size 0 0)
					(zone_connect -1)
				)
				(layer "In4.Cu"
					(shape circle)
					(size 0 0)
					(zone_connect -1)
				)
				(layer "In5.Cu"
					(shape circle)
					(size 0 0)
					(zone_connect -1)
				)
				(layer "In6.Cu"
					(shape circle)
					(size 0 0)
					(zone_connect -1)
				)
				(layer "In7.Cu"
					(shape circle)
					(size 0 0)
					(zone_connect -1)
				)
				(layer "In8.Cu"
					(shape circle)
					(size 0 0)
					(zone_connect -1)
				)
				(layer "B.Cu"
					(shape circle)
					(size 0 0)
					(zone_connect -1)
				)
			)
		)
		(pad "3" smd rect
			(at -1.6002 0.32512 90)
			(size 0.8128 0.4064)
			(layers "F.Cu" "F.Mask" "F.Paste")
			(net "11N2173")
		)
		(pad "4" smd rect
			(at -1.6002 0.97536 90)
			(size 0.8128 0.4064)
			(layers "F.Cu" "F.Mask" "F.Paste")
			(net "11N2175")
		)
		(pad "5" smd rect
			(at 1.6002 0.97536 270)
			(size 0.8128 0.4064)
			(layers "F.Cu" "F.Mask" "F.Paste")
			(net "11N2177")
		)
		(pad "6" smd rect
			(at 1.6002 0.32512 270)
			(size 0.8128 0.4064)
			(layers "F.Cu" "F.Mask" "F.Paste")
			(net "11N2253")
		)
		(pad "7" smd rect
			(at 1.6002 -0.32512 270)
			(size 0.8128 0.4064)
			(layers "F.Cu" "F.Mask" "F.Paste")
			(net "11N2253")
		)
		(pad "8" smd rect
			(at 1.6002 -0.97536 270)
			(size 0.8128 0.4064)
			(layers "F.Cu" "F.Mask" "F.Paste")
			(net "11N2253")
		)
		(pad "9" smd rect
			(at 0 0 90)
			(size 1.778 2.7432)
			(layers "F.Cu" "F.Mask" "F.Paste")
			(net "GND")
		)
		(zone
			(layer "F.Cu")
			(hatch none 0.5)
			(connect_pads
				(clearance 0)
			)
			(min_thickness 0.25)
			(keepout
				(tracks allowed)
				(vias not_allowed)
				(pads allowed)
				(copperpour not_allowed)
				(footprints allowed)
			)
			(placement
				(enabled no)
				(sheetname "")
			)
			(fill
				(thermal_gap 0.5)
				(thermal_bridge_width 0.5)
				(island_removal_mode 0)
			)
			(polygon
				(pts
					(xy 81.28 46.736) (xy 81.28 48.514) (xy 81.661 48.514) (xy 81.661 46.736)
				)
			)
		)
		(zone
			(layer "F.Cu")
			(hatch none 0.5)
			(connect_pads
				(clearance 0)
			)
			(min_thickness 0.25)
			(keepout
				(tracks allowed)
				(vias not_allowed)
				(pads allowed)
				(copperpour not_allowed)
				(footprints allowed)
			)
			(placement
				(enabled no)
				(sheetname "")
			)
			(fill
				(thermal_gap 0.5)
				(thermal_bridge_width 0.5)
				(island_removal_mode 0)
			)
			(polygon
				(pts
					(xy 85.09 48.514) (xy 85.09 46.736) (xy 84.709 46.736) (xy 84.709 48.514)
				)
			)
		)
		(zone
			(layer "F.Cu")
			(hatch none 0.5)
			(connect_pads
				(clearance 0)
			)
			(min_thickness 0.25)
			(keepout
				(tracks allowed)
				(vias not_allowed)
				(pads allowed)
				(copperpour not_allowed)
				(footprints allowed)
			)
			(placement
				(enabled no)
				(sheetname "")
			)
			(fill
				(thermal_gap 0.5)
				(thermal_bridge_width 0.5)
				(island_removal_mode 0)
			)
			(polygon
				(pts
					(arc
						(start 82.3468 50.0888)
						(mid 81.6864 50.0888)
						(end 82.3468 50.0888)
					)
				)
			)
		)
	)
	(footprint ""
		(layer "F.Cu")
		(at 27.178 11.557 -90)
		(property "Reference" "R138"
			(at 0 0 270)
			(layer "F.SilkS")
			(hide yes)
			(effects
				(font
					(size 1.27 1.27)
				)
			)
		)
		(property "Value" "0"
			(at -0.148158 1.3462 0)
			(unlocked yes)
			(layer "F.Fab")
			(hide yes)
			(effects
				(font
					(size 1.27 0.9652)
					(thickness 0.000001)
				)
				(justify left)
			)
		)
		(property "Device Type" "REST1111"
			(at -0.148158 1.3462 0)
			(unlocked yes)
			(layer "F.Fab")
			(hide yes)
			(effects
				(font
					(size 1.27 0.9652)
					(thickness 0.000001)
				)
				(justify left)
			)
		)
		(duplicate_pad_numbers_are_jumpers no)
		(fp_poly
			(pts
				(xy 0.635 1.0668) (xy 0.635 -1.0668) (xy -0.635 -1.0668) (xy -0.635 1.0668)
			)
			(stroke
				(width 0)
				(type default)
			)
			(fill no)
			(layer "F.CrtYd")
		)
		(fp_line
			(start -0.254 0.508)
			(end -0.254 -0.508)
			(stroke
				(width 0.0254)
				(type default)
			)
			(layer "F.Fab")
		)
		(fp_line
			(start 0.254 0.508)
			(end -0.254 0.508)
			(stroke
				(width 0.0254)
				(type default)
			)
			(layer "F.Fab")
		)
		(fp_line
			(start -0.254 -0.508)
			(end 0.254 -0.508)
			(stroke
				(width 0.0254)
				(type default)
			)
			(layer "F.Fab")
		)
		(fp_line
			(start 0.254 -0.508)
			(end 0.254 0.508)
			(stroke
				(width 0.0254)
				(type default)
			)
			(layer "F.Fab")
		)
		(pad "1" smd rect
			(at 0 -0.4191 270)
			(size 0.508 0.5334)
			(layers "F.Cu" "F.Mask" "F.Paste")
			(net "_PSU_I2C_SCL")
		)
		(pad "2" smd rect
			(at 0 0.4191 270)
			(size 0.508 0.5334)
			(layers "F.Cu" "F.Mask" "F.Paste")
			(net "PSU_I2C_SCL")
		)
		(zone
			(layer "F.Cu")
			(hatch none 0.5)
			(connect_pads
				(clearance 0)
			)
			(min_thickness 0.25)
			(keepout
				(tracks not_allowed)
				(vias allowed)
				(pads allowed)
				(copperpour not_allowed)
				(footprints allowed)
			)
			(placement
				(enabled no)
				(sheetname "")
			)
			(fill
				(thermal_gap 0.5)
				(thermal_bridge_width 0.5)
				(island_removal_mode 0)
			)
			(polygon
				(pts
					(xy 27.2034 11.5824) (xy 27.1526 11.5824) (xy 27.1526 11.5316) (xy 27.2034 11.5316)
				)
			)
		)
	)
	(footprint ""
		(layer "F.Cu")
		(at 22.352 3.937)
		(property "Reference" "U20"
			(at 2.921 1.42367 0)
			(unlocked yes)
			(layer "F.SilkS")
			(effects
				(font
					(size 0.7874 0.5842)
					(thickness 0.127)
				)
				(justify left)
			)
		)
		(property "Value" "*"
			(at -0.4826 -0.148107 0)
			(unlocked yes)
			(layer "F.Fab")
			(hide yes)
			(effects
				(font
					(size 1.27 0.9652)
					(thickness 0.000001)
				)
				(justify left)
			)
		)
		(property "Device Type" "ICSO0128"
			(at -0.4826 -0.148107 0)
			(unlocked yes)
			(layer "F.Fab")
			(hide yes)
			(effects
				(font
					(size 1.27 0.9652)
					(thickness 0.000001)
				)
				(justify left)
			)
		)
		(duplicate_pad_numbers_are_jumpers no)
		(fp_line
			(start -2.159 -1.651)
			(end -2.159 -0.762)
			(stroke
				(width 0.1524)
				(type default)
			)
			(layer "F.SilkS")
		)
		(fp_line
			(start -2.159 -1.651)
			(end -2.159 -0.762)
			(stroke
				(width 0.1524)
				(type default)
			)
			(layer "F.SilkS")
		)
		(fp_line
			(start -2.159 1.651)
			(end -2.159 0.762)
			(stroke
				(width 0.1524)
				(type default)
			)
			(layer "F.SilkS")
		)
		(fp_line
			(start -1.778 -1.651)
			(end -2.159 -1.651)
			(stroke
				(width 0.1524)
				(type default)
			)
			(layer "F.SilkS")
		)
		(fp_line
			(start -1.778 1.651)
			(end -2.159 1.143)
			(stroke
				(width 0.1524)
				(type default)
			)
			(layer "F.SilkS")
		)
		(fp_line
			(start -1.778 1.651)
			(end -2.159 1.651)
			(stroke
				(width 0.1524)
				(type default)
			)
			(layer "F.SilkS")
		)
		(fp_line
			(start 1.778 -1.651)
			(end 2.159 -1.651)
			(stroke
				(width 0.1524)
				(type default)
			)
			(layer "F.SilkS")
		)
		(fp_line
			(start 1.778 1.651)
			(end 2.159 1.651)
			(stroke
				(width 0.1524)
				(type default)
			)
			(layer "F.SilkS")
		)
		(fp_line
			(start 2.159 -1.651)
			(end 2.159 -0.762)
			(stroke
				(width 0.1524)
				(type default)
			)
			(layer "F.SilkS")
		)
		(fp_line
			(start 2.159 -1.651)
			(end 2.159 -0.762)
			(stroke
				(width 0.1524)
				(type default)
			)
			(layer "F.SilkS")
		)
		(fp_line
			(start 2.159 1.651)
			(end 2.159 0.762)
			(stroke
				(width 0.1524)
				(type default)
			)
			(layer "F.SilkS")
		)
		(fp_arc
			(start -2.0828 1.910131)
			(mid -2.057529 1.906285)
			(end -2.032 1.905)
			(stroke
				(width 0.1524)
				(type default)
			)
			(layer "F.SilkS")
		)
		(fp_arc
			(start -2.032 1.905)
			(mid -1.927492 1.927496)
			(end -1.8415 1.991004)
			(stroke
				(width 0.1524)
				(type default)
			)
			(layer "F.SilkS")
		)
		(fp_arc
			(start -2.032 2.413)
			(mid -2.05753 2.411703)
			(end -2.0828 2.407844)
			(stroke
				(width 0.1524)
				(type default)
			)
			(layer "F.SilkS")
		)
		(fp_arc
			(start -1.8415 2.327148)
			(mid -1.927511 2.390579)
			(end -2.032 2.413)
			(stroke
				(width 0.1524)
				(type default)
			)
			(layer "F.SilkS")
		)
		(fp_circle
			(center -2.032 2.159)
			(end -1.778 2.159)
			(stroke
				(width 0.1524)
				(type default)
			)
			(fill no)
			(layer "F.SilkS")
		)
		(fp_poly
			(pts
				(xy -2.667 2.159) (xy 2.667 2.159) (xy 2.667 -2.159) (xy -2.667 -2.159)
			)
			(stroke
				(width 0)
				(type default)
			)
			(fill no)
			(layer "F.CrtYd")
		)
		(fp_line
			(start -1.8034 -1.2954)
			(end -1.8034 1.2954)
			(stroke
				(width 0.1524)
				(type default)
			)
			(layer "F.Fab")
		)
		(fp_line
			(start -1.8034 1.2954)
			(end 1.8034 1.2954)
			(stroke
				(width 0.1524)
				(type default)
			)
			(layer "F.Fab")
		)
		(fp_line
			(start 1.8034 -1.2954)
			(end -1.8034 -1.2954)
			(stroke
				(width 0.1524)
				(type default)
			)
			(layer "F.Fab")
		)
		(fp_line
			(start 1.8034 1.2954)
			(end 1.8034 -1.2954)
			(stroke
				(width 0.1524)
				(type default)
			)
			(layer "F.Fab")
		)
		(fp_circle
			(center -1.27 0.762)
			(end -0.986003 0.762)
			(stroke
				(width 0.1524)
				(type default)
			)
			(fill no)
			(layer "F.Fab")
		)
		(fp_text user "1"
			(at -4.318 0.66167 0)
			(unlocked yes)
			(layer "F.SilkS")
			(effects
				(font
					(size 0.7874 0.5842)
					(thickness 0.127)
				)
				(justify left)
			)
		)
		(fp_text user "16"
			(at -3.65633 0 90)
			(unlocked yes)
			(layer "F.SilkS")
			(effects
				(font
					(size 0.7874 0.5842)
					(thickness 0.127)
				)
				(justify left)
			)
		)
		(fp_text user "15"
			(at -1.87833 -1.778 90)
			(unlocked yes)
			(layer "F.SilkS")
			(effects
				(font
					(size 0.7874 0.5842)
					(thickness 0.127)
				)
				(justify left)
			)
		)
		(fp_text user "2"
			(at -1.24333 3.429 90)
			(unlocked yes)
			(layer "F.SilkS")
			(effects
				(font
					(size 0.7874 0.5842)
					(thickness 0.127)
				)
				(justify left)
			)
		)
		(fp_text user "7"
			(at 1.29667 3.302 90)
			(unlocked yes)
			(layer "F.SilkS")
			(effects
				(font
					(size 0.7874 0.5842)
					(thickness 0.127)
				)
				(justify left)
			)
		)
		(fp_text user "10"
			(at 2.159 -1.87833 0)
			(unlocked yes)
			(layer "F.SilkS")
			(effects
				(font
					(size 0.7874 0.5842)
					(thickness 0.127)
				)
				(justify left)
			)
		)
		(fp_text user "9"
			(at 2.3749 -0.472872 0)
			(unlocked yes)
			(layer "F.SilkS")
			(effects
				(font
					(size 0.7874 0.5842)
					(thickness 0.127)
				)
				(justify left)
			)
		)
		(fp_text user "8"
			(at 2.3749 0.670154 0)
			(unlocked yes)
			(layer "F.SilkS")
			(effects
				(font
					(size 0.7874 0.5842)
					(thickness 0.127)
				)
				(justify left)
			)
		)
		(pad "1" smd custom
			(at -1.7018 0.250012 270)
			(size 0.06985 0.06985)
			(layers "F.Cu" "F.Mask" "F.Paste")
			(net "13N4321")
			(options
				(clearance outline)
				(anchor circle)
			)
			(primitives
				(gr_poly
					(pts
						(xy 0.1397 0.4064)
						(arc
							(start 0.1397 -0.2667)
							(mid 0 -0.4064)
							(end -0.1397 -0.2667)
						)
						(xy -0.1397 0.4064)
					)
					(width 0)
					(fill yes)
				)
			)
		)
		(pad "2" smd custom
			(at -1.25001 1.1938)
			(size 0.06985 0.06985)
			(layers "F.Cu" "F.Mask" "F.Paste")
			(net "_NC_U20_74CBTLV_1B1")
			(options
				(clearance outline)
				(anchor circle)
			)
			(primitives
				(gr_poly
					(pts
						(xy 0.1397 0.4064)
						(arc
							(start 0.1397 -0.2667)
							(mid 0 -0.4064)
							(end -0.1397 -0.2667)
						)
						(xy -0.1397 0.4064)
					)
					(width 0)
					(fill yes)
				)
			)
		)
		(pad "3" smd custom
			(at -0.750011 1.1938)
			(size 0.06985 0.06985)
			(layers "F.Cu" "F.Mask" "F.Paste")
			(net "MUX_NFP_SMBUS_ALERT_L")
			(options
				(clearance outline)
				(anchor circle)
			)
			(primitives
				(gr_poly
					(pts
						(xy 0.1397 0.4064)
						(arc
							(start 0.1397 -0.2667)
							(mid 0 -0.4064)
							(end -0.1397 -0.2667)
						)
						(xy -0.1397 0.4064)
					)
					(width 0)
					(fill yes)
				)
			)
		)
		(pad "4" smd custom
			(at -0.250012 1.1938)
			(size 0.06985 0.06985)
			(layers "F.Cu" "F.Mask" "F.Paste")
			(net "NFP_SMBUS_ALERT_L")
			(options
				(clearance outline)
				(anchor circle)
			)
			(primitives
				(gr_poly
					(pts
						(xy 0.1397 0.4064)
						(arc
							(start 0.1397 -0.2667)
							(mid 0 -0.4064)
							(end -0.1397 -0.2667)
						)
						(xy -0.1397 0.4064)
					)
					(width 0)
					(fill yes)
				)
			)
		)
		(pad "5" smd custom
			(at 0.250012 1.1938)
			(size 0.06985 0.06985)
			(layers "F.Cu" "F.Mask" "F.Paste")
			(net "_NC_U20_74CBTLV_2B1")
			(options
				(clearance outline)
				(anchor circle)
			)
			(primitives
				(gr_poly
					(pts
						(xy 0.1397 0.4064)
						(arc
							(start 0.1397 -0.2667)
							(mid 0 -0.4064)
							(end -0.1397 -0.2667)
						)
						(xy -0.1397 0.4064)
					)
					(width 0)
					(fill yes)
				)
			)
		)
		(pad "6" smd custom
			(at 0.750011 1.1938)
			(size 0.06985 0.06985)
			(layers "F.Cu" "F.Mask" "F.Paste")
			(net "MUX_NFP_SMBUS_SDA")
			(options
				(clearance outline)
				(anchor circle)
			)
			(primitives
				(gr_poly
					(pts
						(xy 0.1397 0.4064)
						(arc
							(start 0.1397 -0.2667)
							(mid 0 -0.4064)
							(end -0.1397 -0.2667)
						)
						(xy -0.1397 0.4064)
					)
					(width 0)
					(fill yes)
				)
			)
		)
		(pad "7" smd custom
			(at 1.25001 1.1938)
			(size 0.06985 0.06985)
			(layers "F.Cu" "F.Mask" "F.Paste")
			(net "NFP_SMBUS_SDA")
			(options
				(clearance outline)
				(anchor circle)
			)
			(primitives
				(gr_poly
					(pts
						(xy 0.1397 0.4064)
						(arc
							(start 0.1397 -0.2667)
							(mid 0 -0.4064)
							(end -0.1397 -0.2667)
						)
						(xy -0.1397 0.4064)
					)
					(width 0)
					(fill yes)
				)
			)
		)
		(pad "8" smd custom
			(at 1.7018 0.250012 90)
			(size 0.06985 0.06985)
			(layers "F.Cu" "F.Mask" "F.Paste")
			(net "GND")
			(options
				(clearance outline)
				(anchor circle)
			)
			(primitives
				(gr_poly
					(pts
						(xy 0.1397 0.4064)
						(arc
							(start 0.1397 -0.2667)
							(mid 0 -0.4064)
							(end -0.1397 -0.2667)
						)
						(xy -0.1397 0.4064)
					)
					(width 0)
					(fill yes)
				)
			)
		)
		(pad "9" smd custom
			(at 1.7018 -0.250012 90)
			(size 0.06985 0.06985)
			(layers "F.Cu" "F.Mask" "F.Paste")
			(net "NFP_SMBUS_SCL")
			(options
				(clearance outline)
				(anchor circle)
			)
			(primitives
				(gr_poly
					(pts
						(xy 0.1397 0.4064)
						(arc
							(start 0.1397 -0.2667)
							(mid 0 -0.4064)
							(end -0.1397 -0.2667)
						)
						(xy -0.1397 0.4064)
					)
					(width 0)
					(fill yes)
				)
			)
		)
		(pad "10" smd custom
			(at 1.25001 -1.1938 180)
			(size 0.06985 0.06985)
			(layers "F.Cu" "F.Mask" "F.Paste")
			(net "MUX_NFP_SMBUS_SCL")
			(options
				(clearance outline)
				(anchor circle)
			)
			(primitives
				(gr_poly
					(pts
						(xy 0.1397 0.4064)
						(arc
							(start 0.1397 -0.2667)
							(mid 0 -0.4064)
							(end -0.1397 -0.2667)
						)
						(xy -0.1397 0.4064)
					)
					(width 0)
					(fill yes)
				)
			)
		)
		(pad "11" smd custom
			(at 0.750011 -1.1938 180)
			(size 0.06985 0.06985)
			(layers "F.Cu" "F.Mask" "F.Paste")
			(net "_NC_U20_74CBTLV_3B1")
			(options
				(clearance outline)
				(anchor circle)
			)
			(primitives
				(gr_poly
					(pts
						(xy 0.1397 0.4064)
						(arc
							(start 0.1397 -0.2667)
							(mid 0 -0.4064)
							(end -0.1397 -0.2667)
						)
						(xy -0.1397 0.4064)
					)
					(width 0)
					(fill yes)
				)
			)
		)
		(pad "12" smd custom
			(at 0.250012 -1.1938 180)
			(size 0.06985 0.06985)
			(layers "F.Cu" "F.Mask" "F.Paste")
			(net "NFP_PCIE0_WAKE_L")
			(options
				(clearance outline)
				(anchor circle)
			)
			(primitives
				(gr_poly
					(pts
						(xy 0.1397 0.4064)
						(arc
							(start 0.1397 -0.2667)
							(mid 0 -0.4064)
							(end -0.1397 -0.2667)
						)
						(xy -0.1397 0.4064)
					)
					(width 0)
					(fill yes)
				)
			)
		)
		(pad "13" smd custom
			(at -0.250012 -1.1938 180)
			(size 0.06985 0.06985)
			(layers "F.Cu" "F.Mask" "F.Paste")
			(net "MUX_NFP_PCIE0_WAKE_L")
			(options
				(clearance outline)
				(anchor circle)
			)
			(primitives
				(gr_poly
					(pts
						(xy 0.1397 0.4064)
						(arc
							(start 0.1397 -0.2667)
							(mid 0 -0.4064)
							(end -0.1397 -0.2667)
						)
						(xy -0.1397 0.4064)
					)
					(width 0)
					(fill yes)
				)
			)
		)
		(pad "14" smd custom
			(at -0.750011 -1.1938 180)
			(size 0.06985 0.06985)
			(layers "F.Cu" "F.Mask" "F.Paste")
			(net "_NC_U20_74CBTLV_4B1")
			(options
				(clearance outline)
				(anchor circle)
			)
			(primitives
				(gr_poly
					(pts
						(xy 0.1397 0.4064)
						(arc
							(start 0.1397 -0.2667)
							(mid 0 -0.4064)
							(end -0.1397 -0.2667)
						)
						(xy -0.1397 0.4064)
					)
					(width 0)
					(fill yes)
				)
			)
		)
		(pad "15" smd custom
			(at -1.25001 -1.1938 180)
			(size 0.06985 0.06985)
			(layers "F.Cu" "F.Mask" "F.Paste")
			(net "13N4315")
			(options
				(clearance outline)
				(anchor circle)
			)
			(primitives
				(gr_poly
					(pts
						(xy 0.1397 0.4064)
						(arc
							(start 0.1397 -0.2667)
							(mid 0 -0.4064)
							(end -0.1397 -0.2667)
						)
						(xy -0.1397 0.4064)
					)
					(width 0)
					(fill yes)
				)
			)
		)
		(pad "16" smd custom
			(at -1.7018 -0.250012 270)
			(size 0.06985 0.06985)
			(layers "F.Cu" "F.Mask" "F.Paste")
			(net "EXT_3.3V")
			(options
				(clearance outline)
				(anchor circle)
			)
			(primitives
				(gr_poly
					(pts
						(xy 0.1397 0.4064)
						(arc
							(start 0.1397 -0.2667)
							(mid 0 -0.4064)
							(end -0.1397 -0.2667)
						)
						(xy -0.1397 0.4064)
					)
					(width 0)
					(fill yes)
				)
			)
		)
		(pad "17" smd rect
			(at 0 0)
			(size 1.9812 0.9652)
			(layers "F.Cu" "F.Mask" "F.Paste")
			(net "GND")
		)
		(zone
			(layer "F.Cu")
			(hatch none 0.5)
			(connect_pads
				(clearance 0)
			)
			(min_thickness 0.25)
			(keepout
				(tracks allowed)
				(vias not_allowed)
				(pads allowed)
				(copperpour not_allowed)
				(footprints allowed)
			)
			(placement
				(enabled no)
				(sheetname "")
			)
			(fill
				(thermal_gap 0.5)
				(thermal_bridge_width 0.5)
				(island_removal_mode 0)
			)
			(polygon
				(pts
					(arc
						(start 20.6502 6.096)
						(mid 19.9898 6.096)
						(end 20.6502 6.096)
					)
				)
			)
		)
	)
	(footprint ""
		(layer "F.Cu")
		(at 65.659 47.117 180)
		(property "Reference" "R112"
			(at 0 0 180)
			(layer "F.SilkS")
			(hide yes)
			(effects
				(font
					(size 1.27 1.27)
				)
			)
		)
		(property "Value" "3.32K"
			(at -0.148158 1.3462 270)
			(unlocked yes)
			(layer "F.Fab")
			(hide yes)
			(effects
				(font
					(size 1.27 0.9652)
					(thickness 0.000001)
				)
				(justify left)
			)
		)
		(property "Device Type" "REST0061"
			(at -0.148158 1.3462 270)
			(unlocked yes)
			(layer "F.Fab")
			(hide yes)
			(effects
				(font
					(size 1.27 0.9652)
					(thickness 0.000001)
				)
				(justify left)
			)
		)
		(duplicate_pad_numbers_are_jumpers no)
		(fp_poly
			(pts
				(xy 0.635 1.0668) (xy 0.635 -1.0668) (xy -0.635 -1.0668) (xy -0.635 1.0668)
			)
			(stroke
				(width 0)
				(type default)
			)
			(fill no)
			(layer "F.CrtYd")
		)
		(fp_line
			(start 0.254 0.508)
			(end -0.254 0.508)
			(stroke
				(width 0.0254)
				(type default)
			)
			(layer "F.Fab")
		)
		(fp_line
			(start 0.254 -0.508)
			(end 0.254 0.508)
			(stroke
				(width 0.0254)
				(type default)
			)
			(layer "F.Fab")
		)
		(fp_line
			(start -0.254 0.508)
			(end -0.254 -0.508)
			(stroke
				(width 0.0254)
				(type default)
			)
			(layer "F.Fab")
		)
		(fp_line
			(start -0.254 -0.508)
			(end 0.254 -0.508)
			(stroke
				(width 0.0254)
				(type default)
			)
			(layer "F.Fab")
		)
		(pad "1" smd rect
			(at 0 -0.4191 180)
			(size 0.508 0.5334)
			(layers "F.Cu" "F.Mask" "F.Paste")
			(net "11N1953")
		)
		(pad "2" smd rect
			(at 0 0.4191 180)
			(size 0.508 0.5334)
			(layers "F.Cu" "F.Mask" "F.Paste")
			(net "VDD_5.0V")
		)
		(zone
			(layer "F.Cu")
			(hatch none 0.5)
			(connect_pads
				(clearance 0)
			)
			(min_thickness 0.25)
			(keepout
				(tracks not_allowed)
				(vias allowed)
				(pads allowed)
				(copperpour not_allowed)
				(footprints allowed)
			)
			(placement
				(enabled no)
				(sheetname "")
			)
			(fill
				(thermal_gap 0.5)
				(thermal_bridge_width 0.5)
				(island_removal_mode 0)
			)
			(polygon
				(pts
					(xy 65.6336 47.1424) (xy 65.6336 47.0916) (xy 65.6844 47.0916) (xy 65.6844 47.1424)
				)
			)
		)
	)
	(footprint ""
		(layer "F.Cu")
		(at 82.65099 30.612994)
		(property "Reference" "V3_A-A04"
			(at 0 0 0)
			(layer "F.SilkS")
			(hide yes)
			(effects
				(font
					(size 1.27 1.27)
				)
			)
		)
		(property "Value" ""
			(at 0 0 0)
			(layer "F.Fab")
			(effects
				(font
					(size 1.27 1.27)
				)
			)
		)
		(duplicate_pad_numbers_are_jumpers no)
		(pad "1" thru_hole circle
			(at 0 0)
			(size 0.762 0.762)
			(drill 0.20574)
			(layers "*.Cu" "*.Mask")
			(remove_unused_layers no)
			(net "DDR0_32A_A4")
			(clearance 0.127)
			(thermal_gap 0.127)
			(padstack
				(mode front_inner_back)
				(layer "Inner"
					(shape circle)
					(size 0.4572 0.4572)
					(clearance 0.1143)
				)
				(layer "B.Cu"
					(shape circle)
					(size 0.4572 0.4572)
					(clearance 0.1143)
				)
			)
		)
	)
	(footprint ""
		(layer "F.Cu")
		(at 5.08 34.163 180)
		(property "Reference" "R104"
			(at 0 0 180)
			(layer "F.SilkS")
			(hide yes)
			(effects
				(font
					(size 1.27 1.27)
				)
			)
		)
		(property "Value" "4.75K"
			(at -0.148158 1.3462 270)
			(unlocked yes)
			(layer "F.Fab")
			(hide yes)
			(effects
				(font
					(size 1.27 0.9652)
					(thickness 0.000001)
				)
				(justify left)
			)
		)
		(property "Device Type" "REST4024"
			(at -0.148158 1.3462 270)
			(unlocked yes)
			(layer "F.Fab")
			(hide yes)
			(effects
				(font
					(size 1.27 0.9652)
					(thickness 0.000001)
				)
				(justify left)
			)
		)
		(duplicate_pad_numbers_are_jumpers no)
		(fp_poly
			(pts
				(xy 0.635 1.0668) (xy 0.635 -1.0668) (xy -0.635 -1.0668) (xy -0.635 1.0668)
			)
			(stroke
				(width 0)
				(type default)
			)
			(fill no)
			(layer "F.CrtYd")
		)
		(fp_line
			(start 0.254 0.508)
			(end -0.254 0.508)
			(stroke
				(width 0.0254)
				(type default)
			)
			(layer "F.Fab")
		)
		(fp_line
			(start 0.254 -0.508)
			(end 0.254 0.508)
			(stroke
				(width 0.0254)
				(type default)
			)
			(layer "F.Fab")
		)
		(fp_line
			(start -0.254 0.508)
			(end -0.254 -0.508)
			(stroke
				(width 0.0254)
				(type default)
			)
			(layer "F.Fab")
		)
		(fp_line
			(start -0.254 -0.508)
			(end 0.254 -0.508)
			(stroke
				(width 0.0254)
				(type default)
			)
			(layer "F.Fab")
		)
		(pad "1" smd rect
			(at 0 -0.4191 180)
			(size 0.508 0.5334)
			(layers "F.Cu" "F.Mask" "F.Paste")
			(net "11N1966")
		)
		(pad "2" smd rect
			(at 0 0.4191 180)
			(size 0.508 0.5334)
			(layers "F.Cu" "F.Mask" "F.Paste")
			(net "VDD_5.0V")
		)
		(zone
			(layer "F.Cu")
			(hatch none 0.5)
			(connect_pads
				(clearance 0)
			)
			(min_thickness 0.25)
			(keepout
				(tracks not_allowed)
				(vias allowed)
				(pads allowed)
				(copperpour not_allowed)
				(footprints allowed)
			)
			(placement
				(enabled no)
				(sheetname "")
			)
			(fill
				(thermal_gap 0.5)
				(thermal_bridge_width 0.5)
				(island_removal_mode 0)
			)
			(polygon
				(pts
					(xy 5.0546 34.1884) (xy 5.0546 34.1376) (xy 5.1054 34.1376) (xy 5.1054 34.1884)
				)
			)
		)
	)
	(footprint ""
		(layer "F.Cu")
		(at 84.201 37.973)
		(property "Reference" "R105"
			(at 0.381 -0.10033 0)
			(unlocked yes)
			(layer "F.SilkS")
			(effects
				(font
					(size 0.7874 0.5842)
					(thickness 0.127)
				)
				(justify left)
			)
		)
		(property "Value" "4.75K"
			(at -0.148158 1.3462 90)
			(unlocked yes)
			(layer "F.Fab")
			(hide yes)
			(effects
				(font
					(size 1.27 0.9652)
					(thickness 0.000001)
				)
				(justify left)
			)
		)
		(property "Device Type" "REST4024"
			(at -0.148158 1.3462 90)
			(unlocked yes)
			(layer "F.Fab")
			(hide yes)
			(effects
				(font
					(size 1.27 0.9652)
					(thickness 0.000001)
				)
				(justify left)
			)
		)
		(duplicate_pad_numbers_are_jumpers no)
		(fp_poly
			(pts
				(xy 0.635 1.0668) (xy 0.635 -1.0668) (xy -0.635 -1.0668) (xy -0.635 1.0668)
			)
			(stroke
				(width 0)
				(type default)
			)
			(fill no)
			(layer "F.CrtYd")
		)
		(fp_line
			(start -0.254 -0.508)
			(end 0.254 -0.508)
			(stroke
				(width 0.0254)
				(type default)
			)
			(layer "F.Fab")
		)
		(fp_line
			(start -0.254 0.508)
			(end -0.254 -0.508)
			(stroke
				(width 0.0254)
				(type default)
			)
			(layer "F.Fab")
		)
		(fp_line
			(start 0.254 -0.508)
			(end 0.254 0.508)
			(stroke
				(width 0.0254)
				(type default)
			)
			(layer "F.Fab")
		)
		(fp_line
			(start 0.254 0.508)
			(end -0.254 0.508)
			(stroke
				(width 0.0254)
				(type default)
			)
			(layer "F.Fab")
		)
		(pad "1" smd rect
			(at 0 -0.4191)
			(size 0.508 0.5334)
			(layers "F.Cu" "F.Mask" "F.Paste")
			(net "GND")
		)
		(pad "2" smd rect
			(at 0 0.4191)
			(size 0.508 0.5334)
			(layers "F.Cu" "F.Mask" "F.Paste")
			(net "VDDQ_VTT_EN")
		)
		(zone
			(layer "F.Cu")
			(hatch none 0.5)
			(connect_pads
				(clearance 0)
			)
			(min_thickness 0.25)
			(keepout
				(tracks not_allowed)
				(vias allowed)
				(pads allowed)
				(copperpour not_allowed)
				(footprints allowed)
			)
			(placement
				(enabled no)
				(sheetname "")
			)
			(fill
				(thermal_gap 0.5)
				(thermal_bridge_width 0.5)
				(island_removal_mode 0)
			)
			(polygon
				(pts
					(xy 84.2264 37.9476) (xy 84.2264 37.9984) (xy 84.1756 37.9984) (xy 84.1756 37.9476)
				)
			)
		)
	)
	(footprint ""
		(layer "F.Cu")
		(at 21.5265 1.397 -90)
		(property "Reference" "R384"
			(at -0.381 -0.09017 90)
			(unlocked yes)
			(layer "F.SilkS")
			(effects
				(font
					(size 0.7874 0.5842)
					(thickness 0.127)
				)
				(justify left)
			)
		)
		(property "Value" "0"
			(at -0.148158 1.3462 0)
			(unlocked yes)
			(layer "F.Fab")
			(hide yes)
			(effects
				(font
					(size 1.27 0.9652)
					(thickness 0.000001)
				)
				(justify left)
			)
		)
		(property "Device Type" "REST1111"
			(at -0.148158 1.3462 0)
			(unlocked yes)
			(layer "F.Fab")
			(hide yes)
			(effects
				(font
					(size 1.27 0.9652)
					(thickness 0.000001)
				)
				(justify left)
			)
		)
		(duplicate_pad_numbers_are_jumpers no)
		(fp_poly
			(pts
				(xy 0.635 1.0668) (xy 0.635 -1.0668) (xy -0.635 -1.0668) (xy -0.635 1.0668)
			)
			(stroke
				(width 0)
				(type default)
			)
			(fill no)
			(layer "F.CrtYd")
		)
		(fp_line
			(start -0.254 0.508)
			(end -0.254 -0.508)
			(stroke
				(width 0.0254)
				(type default)
			)
			(layer "F.Fab")
		)
		(fp_line
			(start 0.254 0.508)
			(end -0.254 0.508)
			(stroke
				(width 0.0254)
				(type default)
			)
			(layer "F.Fab")
		)
		(fp_line
			(start -0.254 -0.508)
			(end 0.254 -0.508)
			(stroke
				(width 0.0254)
				(type default)
			)
			(layer "F.Fab")
		)
		(fp_line
			(start 0.254 -0.508)
			(end 0.254 0.508)
			(stroke
				(width 0.0254)
				(type default)
			)
			(layer "F.Fab")
		)
		(pad "1" smd rect
			(at 0 -0.4191 270)
			(size 0.508 0.5334)
			(layers "F.Cu" "F.Mask" "F.Paste")
			(net "NFP_PCIE0_WAKE_L")
		)
		(pad "2" smd rect
			(at 0 0.4191 270)
			(size 0.508 0.5334)
			(layers "F.Cu" "F.Mask" "F.Paste")
			(net "MUX_NFP_PCIE0_WAKE_L")
		)
		(zone
			(layer "F.Cu")
			(hatch none 0.5)
			(connect_pads
				(clearance 0)
			)
			(min_thickness 0.25)
			(keepout
				(tracks not_allowed)
				(vias allowed)
				(pads allowed)
				(copperpour not_allowed)
				(footprints allowed)
			)
			(placement
				(enabled no)
				(sheetname "")
			)
			(fill
				(thermal_gap 0.5)
				(thermal_bridge_width 0.5)
				(island_removal_mode 0)
			)
			(polygon
				(pts
					(xy 21.5519 1.4224) (xy 21.5011 1.4224) (xy 21.5011 1.3716) (xy 21.5519 1.3716)
				)
			)
		)
	)
	(footprint ""
		(layer "F.Cu")
		(at 74.3712 43.942 -90)
		(property "Reference" "TP54"
			(at 0.889 1.75133 90)
			(unlocked yes)
			(layer "F.SilkS")
			(effects
				(font
					(size 0.7874 0.5842)
					(thickness 0.127)
				)
				(justify left)
			)
		)
		(property "Value" "*"
			(at -0.4826 -0.14732 270)
			(unlocked yes)
			(layer "F.Fab")
			(hide yes)
			(effects
				(font
					(size 1.27 0.9652)
					(thickness 0.000001)
				)
				(justify left)
			)
		)
		(property "Device Type" "TP_SMALL"
			(at -0.4826 -0.14732 270)
			(unlocked yes)
			(layer "F.Fab")
			(hide yes)
			(effects
				(font
					(size 1.27 0.9652)
					(thickness 0.000001)
				)
				(justify left)
			)
		)
		(duplicate_pad_numbers_are_jumpers no)
		(fp_line
			(start -0.8636 0.8636)
			(end 0.8636 0.8636)
			(stroke
				(width 0.1524)
				(type default)
			)
			(layer "F.SilkS")
		)
		(fp_line
			(start 0.8636 0.8636)
			(end 0.8636 -0.8636)
			(stroke
				(width 0.1524)
				(type default)
			)
			(layer "F.SilkS")
		)
		(fp_line
			(start -0.8636 -0.8636)
			(end -0.8636 0.8636)
			(stroke
				(width 0.1524)
				(type default)
			)
			(layer "F.SilkS")
		)
		(fp_line
			(start 0.8636 -0.8636)
			(end -0.8636 -0.8636)
			(stroke
				(width 0.1524)
				(type default)
			)
			(layer "F.SilkS")
		)
		(fp_poly
			(pts
				(xy -0.635 -0.635) (xy -0.635 0.635) (xy 0.635 0.635) (xy 0.635 -0.635)
			)
			(stroke
				(width 0)
				(type default)
			)
			(fill no)
			(layer "F.CrtYd")
		)
		(pad "1" smd rect
			(at 0 0 270)
			(size 1.27 1.27)
			(layers "F.Cu" "F.Mask" "F.Paste")
			(net "DDR_VDDQ")
		)
	)
	(footprint ""
		(layer "F.Cu")
		(at 26.162 17.272)
		(property "Reference" "TP58"
			(at -2.032 -1.49733 0)
			(unlocked yes)
			(layer "F.SilkS")
			(effects
				(font
					(size 0.7874 0.5842)
					(thickness 0.127)
				)
				(justify left)
			)
		)
		(property "Value" "*"
			(at -0.4826 -0.14732 0)
			(unlocked yes)
			(layer "F.Fab")
			(hide yes)
			(effects
				(font
					(size 1.27 0.9652)
					(thickness 0.000001)
				)
				(justify left)
			)
		)
		(property "Device Type" "TP_SMALL"
			(at -0.4826 -0.14732 0)
			(unlocked yes)
			(layer "F.Fab")
			(hide yes)
			(effects
				(font
					(size 1.27 0.9652)
					(thickness 0.000001)
				)
				(justify left)
			)
		)
		(duplicate_pad_numbers_are_jumpers no)
		(fp_line
			(start -0.8636 -0.8636)
			(end -0.8636 0.8636)
			(stroke
				(width 0.1524)
				(type default)
			)
			(layer "F.SilkS")
		)
		(fp_line
			(start -0.8636 0.8636)
			(end 0.8636 0.8636)
			(stroke
				(width 0.1524)
				(type default)
			)
			(layer "F.SilkS")
		)
		(fp_line
			(start 0.8636 -0.8636)
			(end -0.8636 -0.8636)
			(stroke
				(width 0.1524)
				(type default)
			)
			(layer "F.SilkS")
		)
		(fp_line
			(start 0.8636 0.8636)
			(end 0.8636 -0.8636)
			(stroke
				(width 0.1524)
				(type default)
			)
			(layer "F.SilkS")
		)
		(fp_poly
			(pts
				(xy -0.635 -0.635) (xy -0.635 0.635) (xy 0.635 0.635) (xy 0.635 -0.635)
			)
			(stroke
				(width 0)
				(type default)
			)
			(fill no)
			(layer "F.CrtYd")
		)
		(pad "1" smd rect
			(at 0 0)
			(size 1.27 1.27)
			(layers "F.Cu" "F.Mask" "F.Paste")
			(net "VDD_CORE_EN")
		)
	)
	(footprint ""
		(layer "F.Cu")
		(at 36.2712 41.656 90)
		(property "Reference" "R315"
			(at 0 0 90)
			(layer "F.SilkS")
			(hide yes)
			(effects
				(font
					(size 1.27 1.27)
				)
			)
		)
		(property "Value" "1.0K"
			(at -0.148158 1.3462 180)
			(unlocked yes)
			(layer "F.Fab")
			(hide yes)
			(effects
				(font
					(size 1.27 0.9652)
					(thickness 0.000001)
				)
				(justify left)
			)
		)
		(property "Device Type" "REST0025"
			(at -0.148158 1.3462 180)
			(unlocked yes)
			(layer "F.Fab")
			(hide yes)
			(effects
				(font
					(size 1.27 0.9652)
					(thickness 0.000001)
				)
				(justify left)
			)
		)
		(duplicate_pad_numbers_are_jumpers no)
		(fp_poly
			(pts
				(xy 0.635 1.0668) (xy 0.635 -1.0668) (xy -0.635 -1.0668) (xy -0.635 1.0668)
			)
			(stroke
				(width 0)
				(type default)
			)
			(fill no)
			(layer "F.CrtYd")
		)
		(fp_line
			(start 0.254 -0.508)
			(end 0.254 0.508)
			(stroke
				(width 0.0254)
				(type default)
			)
			(layer "F.Fab")
		)
		(fp_line
			(start -0.254 -0.508)
			(end 0.254 -0.508)
			(stroke
				(width 0.0254)
				(type default)
			)
			(layer "F.Fab")
		)
		(fp_line
			(start 0.254 0.508)
			(end -0.254 0.508)
			(stroke
				(width 0.0254)
				(type default)
			)
			(layer "F.Fab")
		)
		(fp_line
			(start -0.254 0.508)
			(end -0.254 -0.508)
			(stroke
				(width 0.0254)
				(type default)
			)
			(layer "F.Fab")
		)
		(pad "1" smd rect
			(at 0 -0.4191 90)
			(size 0.508 0.5334)
			(layers "F.Cu" "F.Mask" "F.Paste")
			(net "_SW2")
		)
		(pad "2" smd rect
			(at 0 0.4191 90)
			(size 0.508 0.5334)
			(layers "F.Cu" "F.Mask" "F.Paste")
			(net "NFP_VDD_CORE_ISEN2_P")
		)
		(zone
			(layer "F.Cu")
			(hatch none 0.5)
			(connect_pads
				(clearance 0)
			)
			(min_thickness 0.25)
			(keepout
				(tracks not_allowed)
				(vias allowed)
				(pads allowed)
				(copperpour not_allowed)
				(footprints allowed)
			)
			(placement
				(enabled no)
				(sheetname "")
			)
			(fill
				(thermal_gap 0.5)
				(thermal_bridge_width 0.5)
				(island_removal_mode 0)
			)
			(polygon
				(pts
					(xy 36.2458 41.6306) (xy 36.2966 41.6306) (xy 36.2966 41.6814) (xy 36.2458 41.6814)
				)
			)
		)
	)
	(footprint ""
		(layer "F.Cu")
		(at 76.251003 22.174073)
		(property "Reference" "R363"
			(at 0.991667 1.447927 90)
			(unlocked yes)
			(layer "F.SilkS")
			(effects
				(font
					(size 0.7874 0.5842)
					(thickness 0.127)
				)
				(justify left)
			)
		)
		(property "Value" "100"
			(at -0.148158 1.3462 90)
			(unlocked yes)
			(layer "F.Fab")
			(hide yes)
			(effects
				(font
					(size 1.27 0.9652)
					(thickness 0.000001)
				)
				(justify left)
			)
		)
		(property "Device Type" "REST4030"
			(at -0.148158 1.3462 90)
			(unlocked yes)
			(layer "F.Fab")
			(hide yes)
			(effects
				(font
					(size 1.27 0.9652)
					(thickness 0.000001)
				)
				(justify left)
			)
		)
		(duplicate_pad_numbers_are_jumpers no)
		(fp_poly
			(pts
				(xy 0.635 1.0668) (xy 0.635 -1.0668) (xy -0.635 -1.0668) (xy -0.635 1.0668)
			)
			(stroke
				(width 0)
				(type default)
			)
			(fill no)
			(layer "F.CrtYd")
		)
		(fp_line
			(start -0.254 -0.508)
			(end 0.254 -0.508)
			(stroke
				(width 0.0254)
				(type default)
			)
			(layer "F.Fab")
		)
		(fp_line
			(start -0.254 0.508)
			(end -0.254 -0.508)
			(stroke
				(width 0.0254)
				(type default)
			)
			(layer "F.Fab")
		)
		(fp_line
			(start 0.254 -0.508)
			(end 0.254 0.508)
			(stroke
				(width 0.0254)
				(type default)
			)
			(layer "F.Fab")
		)
		(fp_line
			(start 0.254 0.508)
			(end -0.254 0.508)
			(stroke
				(width 0.0254)
				(type default)
			)
			(layer "F.Fab")
		)
		(pad "1" smd rect
			(at 0 -0.4191)
			(size 0.508 0.5334)
			(layers "F.Cu" "F.Mask" "F.Paste")
			(net "GND")
		)
		(pad "2" smd rect
			(at 0 0.4191)
			(size 0.508 0.5334)
			(layers "F.Cu" "F.Mask" "F.Paste")
			(net "DDR0_32A_VREF1B")
		)
		(zone
			(layer "F.Cu")
			(hatch none 0.5)
			(connect_pads
				(clearance 0)
			)
			(min_thickness 0.25)
			(keepout
				(tracks not_allowed)
				(vias allowed)
				(pads allowed)
				(copperpour not_allowed)
				(footprints allowed)
			)
			(placement
				(enabled no)
				(sheetname "")
			)
			(fill
				(thermal_gap 0.5)
				(thermal_bridge_width 0.5)
				(island_removal_mode 0)
			)
			(polygon
				(pts
					(xy 76.276403 22.148673) (xy 76.276403 22.199473) (xy 76.225603 22.199473) (xy 76.225603 22.148673)
				)
			)
		)
	)
	(footprint ""
		(layer "F.Cu")
		(at 82.423 37.973)
		(property "Reference" "R318"
			(at 0 0 0)
			(layer "F.SilkS")
			(hide yes)
			(effects
				(font
					(size 1.27 1.27)
				)
			)
		)
		(property "Value" "1.0K"
			(at -0.148158 1.3462 90)
			(unlocked yes)
			(layer "F.Fab")
			(hide yes)
			(effects
				(font
					(size 1.27 0.9652)
					(thickness 0.000001)
				)
				(justify left)
			)
		)
		(property "Device Type" "REST0025"
			(at -0.148158 1.3462 90)
			(unlocked yes)
			(layer "F.Fab")
			(hide yes)
			(effects
				(font
					(size 1.27 0.9652)
					(thickness 0.000001)
				)
				(justify left)
			)
		)
		(duplicate_pad_numbers_are_jumpers no)
		(fp_poly
			(pts
				(xy 0.635 1.0668) (xy 0.635 -1.0668) (xy -0.635 -1.0668) (xy -0.635 1.0668)
			)
			(stroke
				(width 0)
				(type default)
			)
			(fill no)
			(layer "F.CrtYd")
		)
		(fp_line
			(start -0.254 -0.508)
			(end 0.254 -0.508)
			(stroke
				(width 0.0254)
				(type default)
			)
			(layer "F.Fab")
		)
		(fp_line
			(start -0.254 0.508)
			(end -0.254 -0.508)
			(stroke
				(width 0.0254)
				(type default)
			)
			(layer "F.Fab")
		)
		(fp_line
			(start 0.254 -0.508)
			(end 0.254 0.508)
			(stroke
				(width 0.0254)
				(type default)
			)
			(layer "F.Fab")
		)
		(fp_line
			(start 0.254 0.508)
			(end -0.254 0.508)
			(stroke
				(width 0.0254)
				(type default)
			)
			(layer "F.Fab")
		)
		(pad "1" smd rect
			(at 0 -0.4191)
			(size 0.508 0.5334)
			(layers "F.Cu" "F.Mask" "F.Paste")
			(net "GND")
		)
		(pad "2" smd rect
			(at 0 0.4191)
			(size 0.508 0.5334)
			(layers "F.Cu" "F.Mask" "F.Paste")
			(net "11N2138")
		)
		(zone
			(layer "F.Cu")
			(hatch none 0.5)
			(connect_pads
				(clearance 0)
			)
			(min_thickness 0.25)
			(keepout
				(tracks not_allowed)
				(vias allowed)
				(pads allowed)
				(copperpour not_allowed)
				(footprints allowed)
			)
			(placement
				(enabled no)
				(sheetname "")
			)
			(fill
				(thermal_gap 0.5)
				(thermal_bridge_width 0.5)
				(island_removal_mode 0)
			)
			(polygon
				(pts
					(xy 82.4484 37.9476) (xy 82.4484 37.9984) (xy 82.3976 37.9984) (xy 82.3976 37.9476)
				)
			)
		)
	)
	(footprint ""
		(layer "F.Cu")
		(at 78.994 5.715 90)
		(property "Reference" "C71"
			(at -0.28067 0.635 0)
			(unlocked yes)
			(layer "F.SilkS")
			(effects
				(font
					(size 0.7874 0.5842)
					(thickness 0.127)
				)
				(justify left)
			)
		)
		(property "Value" "8.2PF"
			(at -0.091846 0.2921 180)
			(unlocked yes)
			(layer "F.Fab")
			(hide yes)
			(effects
				(font
					(size 0.7874 0.5842)
					(thickness 0.2032)
				)
				(justify left)
			)
		)
		(property "Device Type" "CAPC0004"
			(at -0.091846 0.2921 180)
			(unlocked yes)
			(layer "F.Fab")
			(hide yes)
			(effects
				(font
					(size 0.7874 0.5842)
					(thickness 0.2032)
				)
				(justify left)
			)
		)
		(duplicate_pad_numbers_are_jumpers no)
		(fp_poly
			(pts
				(xy 0.635 1.0668) (xy 0.635 -1.0668) (xy -0.635 -1.0668) (xy -0.635 1.0668)
			)
			(stroke
				(width 0)
				(type default)
			)
			(fill no)
			(layer "F.CrtYd")
		)
		(fp_line
			(start 0.254 -0.508)
			(end 0.254 0.508)
			(stroke
				(width 0.0254)
				(type default)
			)
			(layer "F.Fab")
		)
		(fp_line
			(start -0.254 -0.508)
			(end 0.254 -0.508)
			(stroke
				(width 0.0254)
				(type default)
			)
			(layer "F.Fab")
		)
		(fp_line
			(start 0.254 0.508)
			(end -0.254 0.508)
			(stroke
				(width 0.0254)
				(type default)
			)
			(layer "F.Fab")
		)
		(fp_line
			(start -0.254 0.508)
			(end -0.254 -0.508)
			(stroke
				(width 0.0254)
				(type default)
			)
			(layer "F.Fab")
		)
		(pad "1" smd rect
			(at 0 -0.4191 90)
			(size 0.508 0.5334)
			(layers "F.Cu" "F.Mask" "F.Paste")
			(net "DDR0_32A_CK0_P")
		)
		(pad "2" smd rect
			(at 0 0.4191 90)
			(size 0.508 0.5334)
			(layers "F.Cu" "F.Mask" "F.Paste")
			(net "DDR0_32A_CK0_N")
		)
		(zone
			(layer "F.Cu")
			(hatch none 0.5)
			(connect_pads
				(clearance 0)
			)
			(min_thickness 0.25)
			(keepout
				(tracks not_allowed)
				(vias allowed)
				(pads allowed)
				(copperpour not_allowed)
				(footprints allowed)
			)
			(placement
				(enabled no)
				(sheetname "")
			)
			(fill
				(thermal_gap 0.5)
				(thermal_bridge_width 0.5)
				(island_removal_mode 0)
			)
			(polygon
				(pts
					(xy 78.9686 5.6896) (xy 79.0194 5.6896) (xy 79.0194 5.7404) (xy 78.9686 5.7404)
				)
			)
		)
	)
	(footprint ""
		(layer "F.Cu")
		(at 7.366 46.228)
		(property "Reference" "TP46"
			(at 1.397 1.42367 0)
			(unlocked yes)
			(layer "F.SilkS")
			(effects
				(font
					(size 0.7874 0.5842)
					(thickness 0.127)
				)
				(justify left)
			)
		)
		(property "Value" "*"
			(at -0.4826 -0.14732 0)
			(unlocked yes)
			(layer "F.Fab")
			(hide yes)
			(effects
				(font
					(size 1.27 0.9652)
					(thickness 0.000001)
				)
				(justify left)
			)
		)
		(property "Device Type" "TP_SMALL"
			(at -0.4826 -0.14732 0)
			(unlocked yes)
			(layer "F.Fab")
			(hide yes)
			(effects
				(font
					(size 1.27 0.9652)
					(thickness 0.000001)
				)
				(justify left)
			)
		)
		(duplicate_pad_numbers_are_jumpers no)
		(fp_line
			(start -0.8636 -0.8636)
			(end -0.8636 0.8636)
			(stroke
				(width 0.1524)
				(type default)
			)
			(layer "F.SilkS")
		)
		(fp_line
			(start -0.8636 0.8636)
			(end 0.8636 0.8636)
			(stroke
				(width 0.1524)
				(type default)
			)
			(layer "F.SilkS")
		)
		(fp_line
			(start 0.8636 -0.8636)
			(end -0.8636 -0.8636)
			(stroke
				(width 0.1524)
				(type default)
			)
			(layer "F.SilkS")
		)
		(fp_line
			(start 0.8636 0.8636)
			(end 0.8636 -0.8636)
			(stroke
				(width 0.1524)
				(type default)
			)
			(layer "F.SilkS")
		)
		(fp_poly
			(pts
				(xy -0.635 -0.635) (xy -0.635 0.635) (xy 0.635 0.635) (xy 0.635 -0.635)
			)
			(stroke
				(width 0)
				(type default)
			)
			(fill no)
			(layer "F.CrtYd")
		)
		(pad "1" smd rect
			(at 0 0)
			(size 1.27 1.27)
			(layers "F.Cu" "F.Mask" "F.Paste")
			(net "VDD_1.5V")
		)
	)
	(footprint ""
		(layer "F.Cu")
		(at 74.651006 25.813004)
		(property "Reference" "V_A-CB2"
			(at 0 0 0)
			(layer "F.SilkS")
			(hide yes)
			(effects
				(font
					(size 1.27 1.27)
				)
			)
		)
		(property "Value" ""
			(at 0 0 0)
			(layer "F.Fab")
			(effects
				(font
					(size 1.27 1.27)
				)
			)
		)
		(duplicate_pad_numbers_are_jumpers no)
		(pad "1" thru_hole circle
			(at 0 0)
			(size 0.762 0.762)
			(drill 0.20574)
			(layers "*.Cu" "*.Mask")
			(remove_unused_layers no)
			(net "DDR0_32A_CB2")
			(clearance 0.127)
			(thermal_gap 0.127)
			(padstack
				(mode front_inner_back)
				(layer "Inner"
					(shape circle)
					(size 0.4572 0.4572)
					(clearance 0.1143)
				)
				(layer "B.Cu"
					(shape circle)
					(size 0.4572 0.4572)
					(clearance 0.1143)
				)
			)
		)
	)
	(footprint ""
		(layer "F.Cu")
		(at 16.129 47.498 -90)
		(property "Reference" "TP49"
			(at 0.02667 4.191 0)
			(unlocked yes)
			(layer "F.SilkS")
			(effects
				(font
					(size 0.7874 0.5842)
					(thickness 0.127)
				)
				(justify left)
			)
		)
		(property "Value" "*"
			(at -0.4826 -0.14732 270)
			(unlocked yes)
			(layer "F.Fab")
			(hide yes)
			(effects
				(font
					(size 1.27 0.9652)
					(thickness 0.000001)
				)
				(justify left)
			)
		)
		(property "Device Type" "TP_SMALL"
			(at -0.4826 -0.14732 270)
			(unlocked yes)
			(layer "F.Fab")
			(hide yes)
			(effects
				(font
					(size 1.27 0.9652)
					(thickness 0.000001)
				)
				(justify left)
			)
		)
		(duplicate_pad_numbers_are_jumpers no)
		(fp_line
			(start -0.8636 0.8636)
			(end 0.8636 0.8636)
			(stroke
				(width 0.1524)
				(type default)
			)
			(layer "F.SilkS")
		)
		(fp_line
			(start 0.8636 0.8636)
			(end 0.8636 -0.8636)
			(stroke
				(width 0.1524)
				(type default)
			)
			(layer "F.SilkS")
		)
		(fp_line
			(start -0.8636 -0.8636)
			(end -0.8636 0.8636)
			(stroke
				(width 0.1524)
				(type default)
			)
			(layer "F.SilkS")
		)
		(fp_line
			(start 0.8636 -0.8636)
			(end -0.8636 -0.8636)
			(stroke
				(width 0.1524)
				(type default)
			)
			(layer "F.SilkS")
		)
		(fp_poly
			(pts
				(xy -0.635 -0.635) (xy -0.635 0.635) (xy 0.635 0.635) (xy 0.635 -0.635)
			)
			(stroke
				(width 0)
				(type default)
			)
			(fill no)
			(layer "F.CrtYd")
		)
		(pad "1" smd rect
			(at 0 0 270)
			(size 1.27 1.27)
			(layers "F.Cu" "F.Mask" "F.Paste")
			(net "GND")
		)
	)
	(footprint ""
		(layer "F.Cu")
		(at 31.496 25.2984 180)
		(property "Reference" "U2"
			(at 3.81 5.84073 0)
			(unlocked yes)
			(layer "F.SilkS")
			(effects
				(font
					(size 0.7874 0.5842)
					(thickness 0.127)
				)
				(justify left)
			)
		)
		(property "Value" "*"
			(at -0.4826 -0.148209 180)
			(unlocked yes)
			(layer "F.Fab")
			(hide yes)
			(effects
				(font
					(size 1.27 0.9652)
					(thickness 0.000001)
				)
				(justify left)
			)
		)
		(property "Device Type" "PROG0057"
			(at -0.4826 -0.148209 180)
			(unlocked yes)
			(layer "F.Fab")
			(hide yes)
			(effects
				(font
					(size 1.27 0.9652)
					(thickness 0.000001)
				)
				(justify left)
			)
		)
		(duplicate_pad_numbers_are_jumpers no)
		(fp_line
			(start 4.445 4.445)
			(end -4.445 4.445)
			(stroke
				(width 0.2032)
				(type default)
			)
			(layer "F.SilkS")
		)
		(fp_line
			(start 4.445 4.445)
			(end -4.445 4.445)
			(stroke
				(width 0.2032)
				(type default)
			)
			(layer "F.SilkS")
		)
		(fp_line
			(start 4.445 -2.55397)
			(end 4.445 4.445)
			(stroke
				(width 0.2032)
				(type default)
			)
			(layer "F.SilkS")
		)
		(fp_line
			(start 4.445 -4.445)
			(end 4.445 4.445)
			(stroke
				(width 0.2032)
				(type default)
			)
			(layer "F.SilkS")
		)
		(fp_line
			(start 4.445 -4.445)
			(end 4.445 -3.69443)
			(stroke
				(width 0.2032)
				(type default)
			)
			(layer "F.SilkS")
		)
		(fp_line
			(start -0.6096 -4.445)
			(end 4.445 -4.445)
			(stroke
				(width 0.2032)
				(type default)
			)
			(layer "F.SilkS")
		)
		(fp_line
			(start -4.403776 -4.445)
			(end -1.778 -4.445)
			(stroke
				(width 0.2032)
				(type default)
			)
			(layer "F.SilkS")
		)
		(fp_line
			(start -4.445 4.445)
			(end -4.445 -4.368089)
			(stroke
				(width 0.2032)
				(type default)
			)
			(layer "F.SilkS")
		)
		(fp_line
			(start -4.445 4.445)
			(end -4.445 -4.445)
			(stroke
				(width 0.2032)
				(type default)
			)
			(layer "F.SilkS")
		)
		(fp_line
			(start -4.445 -4.445)
			(end 4.445 -4.445)
			(stroke
				(width 0.2032)
				(type default)
			)
			(layer "F.SilkS")
		)
		(fp_circle
			(center -4.953 -4.953)
			(end -5.236997 -4.953)
			(stroke
				(width 0.2032)
				(type default)
			)
			(fill no)
			(layer "F.SilkS")
		)
		(fp_poly
			(pts
				(xy -7.860005 7.860005) (xy -5.827979 7.860005) (xy -3.646526 5.678551) (xy 0.362763 5.678551) (xy 2.353462 7.669251)
				(xy 2.353462 7.852359) (xy 2.361108 7.860005) (xy 7.860005 7.860005) (xy 7.860005 -7.860005) (xy -7.860005 -7.860005)
			)
			(stroke
				(width 0)
				(type default)
			)
			(fill no)
			(layer "F.CrtYd")
		)
		(fp_line
			(start 4.050005 4.050005)
			(end 4.050005 -4.050005)
			(stroke
				(width 0.2032)
				(type default)
			)
			(layer "F.Fab")
		)
		(fp_line
			(start 4.050005 -4.050005)
			(end -4.050005 -4.050005)
			(stroke
				(width 0.2032)
				(type default)
			)
			(layer "F.Fab")
		)
		(fp_line
			(start -4.050005 4.050005)
			(end 4.050005 4.050005)
			(stroke
				(width 0.2032)
				(type default)
			)
			(layer "F.Fab")
		)
		(fp_line
			(start -4.050005 -4.050005)
			(end -4.050005 4.050005)
			(stroke
				(width 0.2032)
				(type default)
			)
			(layer "F.Fab")
		)
		(fp_circle
			(center -3.302 -3.302)
			(end -3.585997 -3.302)
			(stroke
				(width 0.2032)
				(type default)
			)
			(fill no)
			(layer "F.Fab")
		)
		(fp_text user "14"
			(at 4.318 -5.20827 0)
			(unlocked yes)
			(layer "F.SilkS")
			(effects
				(font
					(size 0.7874 0.5842)
					(thickness 0.127)
				)
				(justify left)
			)
		)
		(fp_text user "1"
			(at -3.048 -5.08127 0)
			(unlocked yes)
			(layer "F.SilkS")
			(effects
				(font
					(size 0.7874 0.5842)
					(thickness 0.127)
				)
				(justify left)
			)
		)
		(fp_text user "A"
			(at -4.699 -3.17627 0)
			(unlocked yes)
			(layer "F.SilkS")
			(effects
				(font
					(size 0.7874 0.5842)
					(thickness 0.127)
				)
				(justify left)
			)
		)
		(fp_text user "P"
			(at -4.826 4.18973 0)
			(unlocked yes)
			(layer "F.SilkS")
			(effects
				(font
					(size 0.7874 0.5842)
					(thickness 0.127)
				)
				(justify left)
			)
		)
		(fp_text user "14"
			(at 3.937 -4.70027 0)
			(unlocked yes)
			(layer "F.Fab")
			(effects
				(font
					(size 0.7874 0.5842)
					(thickness 0.127)
				)
				(justify left)
			)
		)
		(fp_text user "1"
			(at -3.048 -4.70027 0)
			(unlocked yes)
			(layer "F.Fab")
			(effects
				(font
					(size 0.7874 0.5842)
					(thickness 0.127)
				)
				(justify left)
			)
		)
		(fp_text user "P"
			(at -4.40309 3.427832 0)
			(unlocked yes)
			(layer "F.Fab")
			(effects
				(font
					(size 0.7874 0.5842)
					(thickness 0.127)
				)
				(justify left)
			)
		)
		(fp_text user "A"
			(at -4.40309 -3.57218 0)
			(unlocked yes)
			(layer "F.Fab")
			(effects
				(font
					(size 0.7874 0.5842)
					(thickness 0.127)
				)
				(justify left)
			)
		)
		(pad "" smd circle
			(at -5.207 -4.826 180)
			(size 1.0668 1.0668)
			(layers "F.Cu" "F.Mask" "F.Paste")
		)
		(pad "" smd circle
			(at 4.826 5.588 180)
			(size 1.0668 1.0668)
			(layers "F.Cu" "F.Mask" "F.Paste")
		)
		(pad "A1" smd circle
			(at -3.250006 -3.250006 180)
			(size 0.254 0.254)
			(layers "F.Cu" "F.Mask" "F.Paste")
			(net "EXT_3.3V")
		)
		(pad "A2" smd circle
			(at -2.750007 -3.250006 180)
			(size 0.254 0.254)
			(layers "F.Cu" "F.Mask" "F.Paste")
			(net "_NC_NWK0_LED_LINK_Y_L")
		)
		(pad "A3" smd circle
			(at -2.250008 -3.250006 180)
			(size 0.254 0.254)
			(layers "F.Cu" "F.Mask" "F.Paste")
			(net "_NC_NWK0_LED_ACT_Y_L")
		)
		(pad "A4" smd circle
			(at -1.750009 -3.250006 180)
			(size 0.254 0.254)
			(layers "F.Cu" "F.Mask" "F.Paste")
			(net "9N1879")
		)
		(pad "A5" smd circle
			(at -1.25001 -3.250006 180)
			(size 0.254 0.254)
			(layers "F.Cu" "F.Mask" "F.Paste")
			(net "GND")
		)
		(pad "A6" smd circle
			(at -0.750011 -3.250006 180)
			(size 0.254 0.254)
			(layers "F.Cu" "F.Mask" "F.Paste")
			(net "CPLD_PGRM_JTAG_TMS")
		)
		(pad "A7" smd circle
			(at -0.250012 -3.250006 180)
			(size 0.254 0.254)
			(layers "F.Cu" "F.Mask" "F.Paste")
			(net "_NC_NWK0_MOD_INT_L")
		)
		(pad "A8" smd circle
			(at 0.250012 -3.250006 180)
			(size 0.254 0.254)
			(layers "F.Cu" "F.Mask" "F.Paste")
			(net "_NC_CPLD_28")
		)
		(pad "A9" smd circle
			(at 0.750011 -3.250006 180)
			(size 0.254 0.254)
			(layers "F.Cu" "F.Mask" "F.Paste")
			(net "_NC_NWK0_MOD_RESET_L")
		)
		(pad "A10" smd circle
			(at 1.25001 -3.250006 180)
			(size 0.254 0.254)
			(layers "F.Cu" "F.Mask" "F.Paste")
			(net "_NC_CPLD_27")
		)
		(pad "A11" smd circle
			(at 1.750009 -3.250006 180)
			(size 0.254 0.254)
			(layers "F.Cu" "F.Mask" "F.Paste")
			(net "_NC_NWK1_LED_LINK_Y_L")
		)
		(pad "A12" smd circle
			(at 2.250008 -3.250006 180)
			(size 0.254 0.254)
			(layers "F.Cu" "F.Mask" "F.Paste")
			(net "_NC_CPLD_24")
		)
		(pad "A13" smd circle
			(at 2.750007 -3.250006 180)
			(size 0.254 0.254)
			(layers "F.Cu" "F.Mask" "F.Paste")
			(net "NWK1_LED_ACT_G_L")
		)
		(pad "A14" smd circle
			(at 3.250006 -3.250006 180)
			(size 0.254 0.254)
			(layers "F.Cu" "F.Mask" "F.Paste")
			(net "_NC_CPLD_21")
		)
		(pad "B1" smd circle
			(at -3.250006 -2.750007 180)
			(size 0.254 0.254)
			(layers "F.Cu" "F.Mask" "F.Paste")
			(net "_NC_CPLD_0")
		)
		(pad "B2" smd circle
			(at -2.750007 -2.750007 180)
			(size 0.254 0.254)
			(layers "F.Cu" "F.Mask" "F.Paste")
			(net "_NC_CPLD_1")
		)
		(pad "B3" thru_hole circle
			(at -2.250008 -2.750007 180)
			(size 0.3048 0.3048)
			(drill 0.127)
			(layers "*.Cu" "*.Mask")
			(remove_unused_layers no)
			(net "NWK0_LED_LINK_G_L")
			(clearance 0.1143)
			(thermal_gap 0.1143)
			(padstack
				(mode front_inner_back)
				(layer "Inner"
					(shape circle)
					(size 0 0)
				)
				(layer "B.Cu"
					(shape circle)
					(size 0.3556 0.3556)
					(clearance 0.0889)
				)
			)
		)
		(pad "B4" thru_hole circle
			(at -1.750009 -2.750007 180)
			(size 0.3048 0.3048)
			(drill 0.127)
			(layers "*.Cu" "*.Mask")
			(remove_unused_layers no)
			(net "CPLD_PGRM_JTAG_TDI")
			(clearance 0.1143)
			(thermal_gap 0.1143)
			(padstack
				(mode front_inner_back)
				(layer "Inner"
					(shape circle)
					(size 0 0)
				)
				(layer "B.Cu"
					(shape circle)
					(size 0.3556 0.3556)
					(clearance 0.0889)
				)
			)
		)
		(pad "B5" smd circle
			(at -1.25001 -2.750007 180)
			(size 0.254 0.254)
			(layers "F.Cu" "F.Mask" "F.Paste")
			(net "_NC_CPLD_30")
		)
		(pad "B6" thru_hole circle
			(at -0.750011 -2.750007 180)
			(size 0.3048 0.3048)
			(drill 0.127)
			(layers "*.Cu" "*.Mask")
			(remove_unused_layers no)
			(net "CPLD_PGRM_JTAG_TCK")
			(clearance 0.1143)
			(thermal_gap 0.1143)
			(padstack
				(mode front_inner_back)
				(layer "Inner"
					(shape circle)
					(size 0 0)
				)
				(layer "B.Cu"
					(shape circle)
					(size 0.3556 0.3556)
					(clearance 0.0889)
				)
			)
		)
		(pad "B7" thru_hole circle
			(at -0.250012 -2.750007 180)
			(size 0.3048 0.3048)
			(drill 0.127)
			(layers "*.Cu" "*.Mask")
			(remove_unused_layers no)
			(net "NWK0_MOD_PRES_L")
			(clearance 0.1143)
			(thermal_gap 0.1143)
			(padstack
				(mode front_inner_back)
				(layer "Inner"
					(shape circle)
					(size 0 0)
				)
				(layer "B.Cu"
					(shape circle)
					(size 0.3556 0.3556)
					(clearance 0.0889)
				)
			)
		)
		(pad "B8" thru_hole circle
			(at 0.250012 -2.750007 180)
			(size 0.3048 0.3048)
			(drill 0.127)
			(layers "*.Cu" "*.Mask")
			(remove_unused_layers no)
			(net "PSU_I2C_SDA")
			(clearance 0.1143)
			(thermal_gap 0.1143)
			(padstack
				(mode front_inner_back)
				(layer "Inner"
					(shape circle)
					(size 0 0)
				)
				(layer "B.Cu"
					(shape circle)
					(size 0.3556 0.3556)
					(clearance 0.0889)
				)
			)
		)
		(pad "B9" smd circle
			(at 0.750011 -2.750007 180)
			(size 0.254 0.254)
			(layers "F.Cu" "F.Mask" "F.Paste")
			(net "_NC_NWK0_MOD_SEL_L")
		)
		(pad "B10" thru_hole circle
			(at 1.25001 -2.750007 180)
			(size 0.3048 0.3048)
			(drill 0.127)
			(layers "*.Cu" "*.Mask")
			(remove_unused_layers no)
			(net "EXT_3.3V")
			(clearance 0.1143)
			(thermal_gap 0.1143)
			(padstack
				(mode front_inner_back)
				(layer "Inner"
					(shape circle)
					(size 0 0)
				)
				(layer "B.Cu"
					(shape circle)
					(size 0.3556 0.3556)
					(clearance 0.0889)
				)
			)
		)
		(pad "B11" thru_hole circle
			(at 1.750009 -2.750007 180)
			(size 0.3048 0.3048)
			(drill 0.127)
			(layers "*.Cu" "*.Mask")
			(remove_unused_layers no)
			(net "GND")
			(clearance 0.1143)
			(thermal_gap 0.1143)
			(padstack
				(mode front_inner_back)
				(layer "Inner"
					(shape circle)
					(size 0 0)
				)
				(layer "B.Cu"
					(shape circle)
					(size 0.3556 0.3556)
					(clearance 0.0889)
				)
			)
		)
		(pad "B12" smd circle
			(at 2.250008 -2.750007 180)
			(size 0.254 0.254)
			(layers "F.Cu" "F.Mask" "F.Paste")
			(net "_NC_CPLD_GPIO8")
		)
		(pad "B13" smd circle
			(at 2.750007 -2.750007 180)
			(size 0.254 0.254)
			(layers "F.Cu" "F.Mask" "F.Paste")
			(net "_NC_NWK1_LED_ACT_Y_L")
		)
		(pad "B14" smd circle
			(at 3.250006 -2.750007 180)
			(size 0.254 0.254)
			(layers "F.Cu" "F.Mask" "F.Paste")
			(net "_NC_NWK1_MOD_INT_L")
		)
		(pad "C1" smd circle
			(at -3.250006 -2.250008 180)
			(size 0.254 0.254)
			(layers "F.Cu" "F.Mask" "F.Paste")
			(net "EXT_12.0V_PGOOD")
		)
		(pad "C2" thru_hole circle
			(at -2.750007 -2.250008 180)
			(size 0.3048 0.3048)
			(drill 0.127)
			(layers "*.Cu" "*.Mask")
			(remove_unused_layers no)
			(net "VDD_5.0V_PGOOD")
			(clearance 0.1143)
			(thermal_gap 0.1143)
			(padstack
				(mode front_inner_back)
				(layer "Inner"
					(shape circle)
					(size 0 0)
				)
				(layer "B.Cu"
					(shape circle)
					(size 0.3556 0.3556)
					(clearance 0.0889)
				)
			)
		)
		(pad "C3" smd circle
			(at -2.250008 -2.250008 180)
			(size 0.254 0.254)
			(layers "F.Cu" "F.Mask" "F.Paste")
			(net "EXT_3.3V_PGOOD")
		)
		(pad "C4" smd circle
			(at -1.750009 -2.250008 180)
			(size 0.254 0.254)
			(layers "F.Cu" "F.Mask" "F.Paste")
			(net "NWK0_LED_ACT_G_L")
		)
		(pad "C5" smd circle
			(at -1.25001 -2.250008 180)
			(size 0.254 0.254)
			(layers "F.Cu" "F.Mask" "F.Paste")
			(net "EXT_3.3V")
		)
		(pad "C6" smd circle
			(at -0.750011 -2.250008 180)
			(size 0.254 0.254)
			(layers "F.Cu" "F.Mask" "F.Paste")
			(net "_NC_CPLD_29")
		)
		(pad "C7" smd circle
			(at -0.250012 -2.250008 180)
			(size 0.254 0.254)
			(layers "F.Cu" "F.Mask" "F.Paste")
			(net "_NC_CPLD_31")
		)
		(pad "C8" smd circle
			(at 0.250012 -2.250008 180)
			(size 0.254 0.254)
			(layers "F.Cu" "F.Mask" "F.Paste")
			(net "PSU_I2C_SCL")
		)
		(pad "C9" smd circle
			(at 0.750011 -2.250008 180)
			(size 0.254 0.254)
			(layers "F.Cu" "F.Mask" "F.Paste")
			(net "_NC_NWK0_MOD_LP_MODE")
		)
		(pad "C10" smd circle
			(at 1.25001 -2.250008 180)
			(size 0.254 0.254)
			(layers "F.Cu" "F.Mask" "F.Paste")
			(net "_NC_NWK0_MOD_RS_1")
		)
		(pad "C11" smd circle
			(at 1.750009 -2.250008 180)
			(size 0.254 0.254)
			(layers "F.Cu" "F.Mask" "F.Paste")
			(net "_NC_CPLD_26")
		)
		(pad "C12" smd circle
			(at 2.250008 -2.250008 180)
			(size 0.254 0.254)
			(layers "F.Cu" "F.Mask" "F.Paste")
			(net "_NC_CPLD_25")
		)
		(pad "C13" thru_hole circle
			(at 2.750007 -2.250008 180)
			(size 0.3048 0.3048)
			(drill 0.127)
			(layers "*.Cu" "*.Mask")
			(remove_unused_layers no)
			(net "NWK1_MOD_PRES_L")
			(clearance 0.1143)
			(thermal_gap 0.1143)
			(padstack
				(mode front_inner_back)
				(layer "Inner"
					(shape circle)
					(size 0 0)
				)
				(layer "B.Cu"
					(shape circle)
					(size 0.3556 0.3556)
					(clearance 0.0889)
				)
			)
		)
		(pad "C14" smd circle
			(at 3.250006 -2.250008 180)
			(size 0.254 0.254)
			(layers "F.Cu" "F.Mask" "F.Paste")
			(net "_NC_CPLD_23")
		)
		(pad "D1" smd circle
			(at -3.250006 -1.750009 180)
			(size 0.254 0.254)
			(layers "F.Cu" "F.Mask" "F.Paste")
			(net "VDD_7401_PGOOD")
		)
		(pad "D2" thru_hole circle
			(at -2.750007 -1.750009 180)
			(size 0.3048 0.3048)
			(drill 0.127)
			(layers "*.Cu" "*.Mask")
			(remove_unused_layers no)
			(net "GND")
			(clearance 0.1143)
			(thermal_gap 0.1143)
			(padstack
				(mode front_inner_back)
				(layer "Inner"
					(shape circle)
					(size 0 0)
				)
				(layer "B.Cu"
					(shape circle)
					(size 0.3556 0.3556)
					(clearance 0.0889)
				)
			)
		)
		(pad "D3" smd circle
			(at -2.250008 -1.750009 180)
			(size 0.254 0.254)
			(layers "F.Cu" "F.Mask" "F.Paste")
			(net "EXT_3.3V")
		)
		(pad "D12" smd circle
			(at 2.250008 -1.750009 180)
			(size 0.254 0.254)
			(layers "F.Cu" "F.Mask" "F.Paste")
			(net "_NC_CPLD_22")
		)
		(pad "D13" thru_hole circle
			(at 2.750007 -1.750009 180)
			(size 0.3048 0.3048)
			(drill 0.127)
			(layers "*.Cu" "*.Mask")
			(remove_unused_layers no)
			(net "GND")
			(clearance 0.1143)
			(thermal_gap 0.1143)
			(padstack
				(mode front_inner_back)
				(layer "Inner"
					(shape circle)
					(size 0 0)
				)
				(layer "B.Cu"
					(shape circle)
					(size 0.3556 0.3556)
					(clearance 0.0889)
				)
			)
		)
		(pad "D14" smd circle
			(at 3.250006 -1.750009 180)
			(size 0.254 0.254)
			(layers "F.Cu" "F.Mask" "F.Paste")
			(net "EXT_3.3V")
		)
		(pad "E1" smd circle
			(at -3.250006 -1.25001 180)
			(size 0.254 0.254)
			(layers "F.Cu" "F.Mask" "F.Paste")
			(net "VDDQ_VTT_PGOOD")
		)
		(pad "E2" thru_hole circle
			(at -2.750007 -1.25001 180)
			(size 0.3048 0.3048)
			(drill 0.127)
			(layers "*.Cu" "*.Mask")
			(remove_unused_layers no)
			(net "VDD_CORE_PGOOD")
			(clearance 0.1143)
			(thermal_gap 0.1143)
			(padstack
				(mode front_inner_back)
				(layer "Inner"
					(shape circle)
					(size 0 0)
				)
				(layer "B.Cu"
					(shape circle)
					(size 0.3556 0.3556)
					(clearance 0.0889)
				)
			)
		)
		(pad "E3" smd circle
			(at -2.250008 -1.25001 180)
			(size 0.254 0.254)
			(layers "F.Cu" "F.Mask" "F.Paste")
			(net "CORE_FB_FAULT_L")
		)
		(pad "E12" smd circle
			(at 2.250008 -1.25001 180)
			(size 0.254 0.254)
			(layers "F.Cu" "F.Mask" "F.Paste")
			(net "_NC_NWK1_MOD_LP_MODE")
		)
		(pad "E13" smd circle
			(at 2.750007 -1.25001 180)
			(size 0.254 0.254)
			(layers "F.Cu" "F.Mask" "F.Paste")
			(net "_NC_NWK1_MOD_SEL_L")
		)
		(pad "E14" smd circle
			(at 3.250006 -1.25001 180)
			(size 0.254 0.254)
			(layers "F.Cu" "F.Mask" "F.Paste")
			(net "_NC_NWK1_MOD_RESET_L")
		)
		(pad "F1" smd circle
			(at -3.250006 -0.750011 180)
			(size 0.254 0.254)
			(layers "F.Cu" "F.Mask" "F.Paste")
			(net "_NC_CPLD_2")
		)
		(pad "F2" thru_hole circle
			(at -2.750007 -0.750011 180)
			(size 0.3048 0.3048)
			(drill 0.127)
			(layers "*.Cu" "*.Mask")
			(remove_unused_layers no)
			(net "CORE_FB_ALERT_L")
			(clearance 0.1143)
			(thermal_gap 0.1143)
			(padstack
				(mode front_inner_back)
				(layer "Inner"
					(shape circle)
					(size 0 0)
				)
				(layer "B.Cu"
					(shape circle)
					(size 0.3556 0.3556)
					(clearance 0.0889)
				)
			)
		)
		(pad "F3" smd circle
			(at -2.250008 -0.750011 180)
			(size 0.254 0.254)
			(layers "F.Cu" "F.Mask" "F.Paste")
			(net "_NC_CPLD_3")
		)
		(pad "F12" smd circle
			(at 2.250008 -0.750011 180)
			(size 0.254 0.254)
			(layers "F.Cu" "F.Mask" "F.Paste")
			(net "_NC_NWK1_MOD_RS_1")
		)
		(pad "F13" thru_hole circle
			(at 2.750007 -0.750011 180)
			(size 0.3048 0.3048)
			(drill 0.127)
			(layers "*.Cu" "*.Mask")
			(remove_unused_layers no)
			(net "CPLD_NFP_RST_LED_L")
			(clearance 0.1143)
			(thermal_gap 0.1143)
			(padstack
				(mode front_inner_back)
				(layer "Inner"
					(shape circle)
					(size 0 0)
				)
				(layer "B.Cu"
					(shape circle)
					(size 0.3556 0.3556)
					(clearance 0.0889)
				)
			)
		)
		(pad "F14" smd circle
			(at 3.250006 -0.750011 180)
			(size 0.254 0.254)
			(layers "F.Cu" "F.Mask" "F.Paste")
			(net "PWR_GOOD_LED_L")
		)
		(pad "G1" smd circle
			(at -3.250006 -0.250012 180)
			(size 0.254 0.254)
			(layers "F.Cu" "F.Mask" "F.Paste")
			(net "_NC_CPLD_4")
		)
		(pad "G2" thru_hole circle
			(at -2.750007 -0.250012 180)
			(size 0.3048 0.3048)
			(drill 0.127)
			(layers "*.Cu" "*.Mask")
			(remove_unused_layers no)
			(net "GND")
			(clearance 0.1143)
			(thermal_gap 0.1143)
			(padstack
				(mode front_inner_back)
				(layer "Inner"
					(shape circle)
					(size 0 0)
				)
				(layer "B.Cu"
					(shape circle)
					(size 0.3556 0.3556)
					(clearance 0.0889)
				)
			)
		)
		(pad "G3" smd circle
			(at -2.250008 -0.250012 180)
			(size 0.254 0.254)
			(layers "F.Cu" "F.Mask" "F.Paste")
			(net "CORE_FB_PH1_THERM_L")
		)
		(pad "G12" smd circle
			(at 2.250008 -0.250012 180)
			(size 0.254 0.254)
			(layers "F.Cu" "F.Mask" "F.Paste")
			(net "CPLD_CORE_PSI_L")
		)
		(pad "G13" thru_hole circle
			(at 2.750007 -0.250012 180)
			(size 0.3048 0.3048)
			(drill 0.127)
			(layers "*.Cu" "*.Mask")
			(remove_unused_layers no)
			(net "VDD_CORE_EN")
			(clearance 0.1143)
			(thermal_gap 0.1143)
			(padstack
				(mode front_inner_back)
				(layer "Inner"
					(shape circle)
					(size 0 0)
				)
				(layer "B.Cu"
					(shape circle)
					(size 0.3556 0.3556)
					(clearance 0.0889)
				)
			)
		)
		(pad "G14" smd circle
			(at 3.250006 -0.250012 180)
			(size 0.254 0.254)
			(layers "F.Cu" "F.Mask" "F.Paste")
			(net "VDD_7401_EN")
		)
		(pad "H1" smd circle
			(at -3.250006 0.250012 180)
			(size 0.254 0.254)
			(layers "F.Cu" "F.Mask" "F.Paste")
			(net "HOST_RESET_REQ_L")
		)
		(pad "H2" thru_hole circle
			(at -2.750007 0.250012 180)
			(size 0.3048 0.3048)
			(drill 0.127)
			(layers "*.Cu" "*.Mask")
			(remove_unused_layers no)
			(net "CORE_FB_PH2_THERM_L")
			(clearance 0.1143)
			(thermal_gap 0.1143)
			(padstack
				(mode front_inner_back)
				(layer "Inner"
					(shape circle)
					(size 0 0)
				)
				(layer "B.Cu"
					(shape circle)
					(size 0.3556 0.3556)
					(clearance 0.0889)
				)
			)
		)
		(pad "H3" smd circle
			(at -2.250008 0.250012 180)
			(size 0.254 0.254)
			(layers "F.Cu" "F.Mask" "F.Paste")
			(net "CPLD_NIC_MEZZ_ID1")
		)
		(pad "H12" smd circle
			(at 2.250008 0.250012 180)
			(size 0.254 0.254)
			(layers "F.Cu" "F.Mask" "F.Paste")
			(net "VDDQ_VTT_EN")
		)
		(pad "H13" thru_hole circle
			(at 2.750007 0.250012 180)
			(size 0.3048 0.3048)
			(drill 0.127)
			(layers "*.Cu" "*.Mask")
			(remove_unused_layers no)
			(net "GND")
			(clearance 0.1143)
			(thermal_gap 0.1143)
			(padstack
				(mode front_inner_back)
				(layer "Inner"
					(shape circle)
					(size 0 0)
				)
				(layer "B.Cu"
					(shape circle)
					(size 0.3556 0.3556)
					(clearance 0.0889)
				)
			)
		)
		(pad "H14" smd circle
			(at 3.250006 0.250012 180)
			(size 0.254 0.254)
			(layers "F.Cu" "F.Mask" "F.Paste")
			(net "_NC_CPLD_20")
		)
		(pad "J1" smd circle
			(at -3.250006 0.750011 180)
			(size 0.254 0.254)
			(layers "F.Cu" "F.Mask" "F.Paste")
			(net "NFP_CLK_NRESET_OUT_L")
		)
		(pad "J2" thru_hole circle
			(at -2.750007 0.750011 180)
			(size 0.3048 0.3048)
			(drill 0.127)
			(layers "*.Cu" "*.Mask")
			(remove_unused_layers no)
			(net "CNTRL_SPI_SCK")
			(clearance 0.1143)
			(thermal_gap 0.1143)
			(padstack
				(mode front_inner_back)
				(layer "Inner"
					(shape circle)
					(size 0 0)
				)
				(layer "B.Cu"
					(shape circle)
					(size 0.3556 0.3556)
					(clearance 0.0889)
				)
			)
		)
		(pad "J3" smd circle
			(at -2.250008 0.750011 180)
			(size 0.254 0.254)
			(layers "F.Cu" "F.Mask" "F.Paste")
			(net "CNTRL_SPI_MISO")
		)
		(pad "J12" smd circle
			(at 2.250008 0.750011 180)
			(size 0.254 0.254)
			(layers "F.Cu" "F.Mask" "F.Paste")
			(net "_NC_CPLD_19")
		)
		(pad "J13" thru_hole circle
			(at 2.750007 0.750011 180)
			(size 0.3048 0.3048)
			(drill 0.127)
			(layers "*.Cu" "*.Mask")
			(remove_unused_layers no)
			(net "VDD_5.0V_EN")
			(clearance 0.1143)
			(thermal_gap 0.1143)
			(padstack
				(mode front_inner_back)
				(layer "Inner"
					(shape circle)
					(size 0 0)
				)
				(layer "B.Cu"
					(shape circle)
					(size 0.3556 0.3556)
					(clearance 0.0889)
				)
			)
		)
		(pad "J14" smd circle
			(at 3.250006 0.750011 180)
			(size 0.254 0.254)
			(layers "F.Cu" "F.Mask" "F.Paste")
			(net "_NC_CPLD_18")
		)
		(pad "K1" smd circle
			(at -3.250006 1.25001 180)
			(size 0.254 0.254)
			(layers "F.Cu" "F.Mask" "F.Paste")
			(net "CNTRL_SPI_MOSI")
		)
		(pad "K2" thru_hole circle
			(at -2.750007 1.25001 180)
			(size 0.3048 0.3048)
			(drill 0.127)
			(layers "*.Cu" "*.Mask")
			(remove_unused_layers no)
			(net "CNTRL_SPI_CS")
			(clearance 0.1143)
			(thermal_gap 0.1143)
			(padstack
				(mode front_inner_back)
				(layer "Inner"
					(shape circle)
					(size 0 0)
				)
				(layer "B.Cu"
					(shape circle)
					(size 0.3556 0.3556)
					(clearance 0.0889)
				)
			)
		)
		(pad "K3" smd circle
			(at -2.250008 1.25001 180)
			(size 0.254 0.254)
			(layers "F.Cu" "F.Mask" "F.Paste")
			(net "NFP_REF_CLK_100M_EN")
		)
		(pad "K12" smd circle
			(at 2.250008 1.25001 180)
			(size 0.254 0.254)
			(layers "F.Cu" "F.Mask" "F.Paste")
			(net "NFP_CFG_SPI_FLASH_HOLD_L")
		)
		(pad "K13" thru_hole circle
			(at 2.750007 1.25001 180)
			(size 0.3048 0.3048)
			(drill 0.127)
			(layers "*.Cu" "*.Mask")
			(remove_unused_layers no)
			(net "CPLD_SMBUS_ALERT_L")
			(clearance 0.1143)
			(thermal_gap 0.1143)
			(padstack
				(mode front_inner_back)
				(layer "Inner"
					(shape circle)
					(size 0 0)
				)
				(layer "B.Cu"
					(shape circle)
					(size 0.3556 0.3556)
					(clearance 0.0889)
				)
			)
		)
		(pad "K14" smd circle
			(at 3.250006 1.25001 180)
			(size 0.254 0.254)
			(layers "F.Cu" "F.Mask" "F.Paste")
			(net "NFP_CFG_SPI_FLASH_WP_L")
		)
		(pad "L1" smd circle
			(at -3.250006 1.750009 180)
			(size 0.254 0.254)
			(layers "F.Cu" "F.Mask" "F.Paste")
			(net "EXT_3.3V")
		)
		(pad "L2" thru_hole circle
			(at -2.750007 1.750009 180)
			(size 0.3048 0.3048)
			(drill 0.127)
			(layers "*.Cu" "*.Mask")
			(remove_unused_layers no)
			(net "GND")
			(clearance 0.1143)
			(thermal_gap 0.1143)
			(padstack
				(mode front_inner_back)
				(layer "Inner"
					(shape circle)
					(size 0 0)
				)
				(layer "B.Cu"
					(shape circle)
					(size 0.3556 0.3556)
					(clearance 0.0889)
				)
			)
		)
		(pad "L3" smd circle
			(at -2.250008 1.750009 180)
			(size 0.254 0.254)
			(layers "F.Cu" "F.Mask" "F.Paste")
			(net "_NC_CPLD_6")
		)
		(pad "L12" smd circle
			(at 2.250008 1.750009 180)
			(size 0.254 0.254)
			(layers "F.Cu" "F.Mask" "F.Paste")
			(net "EXT_3.3V")
		)
		(pad "L13" thru_hole circle
			(at 2.750007 1.750009 180)
			(size 0.3048 0.3048)
			(drill 0.127)
			(layers "*.Cu" "*.Mask")
			(remove_unused_layers no)
			(net "GND")
			(clearance 0.1143)
			(thermal_gap 0.1143)
			(padstack
				(mode front_inner_back)
				(layer "Inner"
					(shape circle)
					(size 0 0)
				)
				(layer "B.Cu"
					(shape circle)
					(size 0.3556 0.3556)
					(clearance 0.0889)
				)
			)
		)
		(pad "L14" smd circle
			(at 3.250006 1.750009 180)
			(size 0.254 0.254)
			(layers "F.Cu" "F.Mask" "F.Paste")
			(net "NFP_CPLD_INT_L")
		)
		(pad "M1" smd circle
			(at -3.250006 2.250008 180)
			(size 0.254 0.254)
			(layers "F.Cu" "F.Mask" "F.Paste")
			(net "NFP_REF_CLK_156M_EN")
		)
		(pad "M2" thru_hole circle
			(at -2.750007 2.250008 180)
			(size 0.3048 0.3048)
			(drill 0.127)
			(layers "*.Cu" "*.Mask")
			(remove_unused_layers no)
			(net "PCIE0_RST_L")
			(clearance 0.1143)
			(thermal_gap 0.1143)
			(padstack
				(mode front_inner_back)
				(layer "Inner"
					(shape circle)
					(size 0 0)
				)
				(layer "B.Cu"
					(shape circle)
					(size 0.3556 0.3556)
					(clearance 0.0889)
				)
			)
		)
		(pad "M3" smd circle
			(at -2.250008 2.250008 180)
			(size 0.254 0.254)
			(layers "F.Cu" "F.Mask" "F.Paste")
			(net "CPLD_GPIO_3")
		)
		(pad "M4" smd circle
			(at -1.750009 2.250008 180)
			(size 0.254 0.254)
			(layers "F.Cu" "F.Mask" "F.Paste")
			(net "NFP_SPI2_SCK")
		)
		(pad "M5" smd circle
			(at -1.25001 2.250008 180)
			(size 0.254 0.254)
			(layers "F.Cu" "F.Mask" "F.Paste")
			(net "_NC_CPLD_10")
		)
		(pad "M6" smd circle
			(at -0.750011 2.250008 180)
			(size 0.254 0.254)
			(layers "F.Cu" "F.Mask" "F.Paste")
			(net "_NC_CPLD_11")
		)
		(pad "M7" smd circle
			(at -0.250012 2.250008 180)
			(size 0.254 0.254)
			(layers "F.Cu" "F.Mask" "F.Paste")
			(net "_NC_FAN_PWM")
		)
		(pad "M8" smd circle
			(at 0.250012 2.250008 180)
			(size 0.254 0.254)
			(layers "F.Cu" "F.Mask" "F.Paste")
			(net "CPLD_GPIO_1")
		)
		(pad "M9" smd circle
			(at 0.750011 2.250008 180)
			(size 0.254 0.254)
			(layers "F.Cu" "F.Mask" "F.Paste")
			(net "CPLD_VERSION_1")
		)
		(pad "M10" smd circle
			(at 1.25001 2.250008 180)
			(size 0.254 0.254)
			(layers "F.Cu" "F.Mask" "F.Paste")
			(net "NFP_FAIL_SAFE_BOOT_L")
		)
		(pad "M11" smd circle
			(at 1.750009 2.250008 180)
			(size 0.254 0.254)
			(layers "F.Cu" "F.Mask" "F.Paste")
			(net "_NC_CPLD_14")
		)
		(pad "M12" smd circle
			(at 2.250008 2.250008 180)
			(size 0.254 0.254)
			(layers "F.Cu" "F.Mask" "F.Paste")
			(net "_NC_CPLD_17")
		)
		(pad "M13" thru_hole circle
			(at 2.750007 2.250008 180)
			(size 0.3048 0.3048)
			(drill 0.127)
			(layers "*.Cu" "*.Mask")
			(remove_unused_layers no)
			(net "_NFP_CLK_NRESET_L")
			(clearance 0.1143)
			(thermal_gap 0.1143)
			(padstack
				(mode front_inner_back)
				(layer "Inner"
					(shape circle)
					(size 0 0)
				)
				(layer "B.Cu"
					(shape circle)
					(size 0.3556 0.3556)
					(clearance 0.0889)
				)
			)
		)
		(pad "M14" smd circle
			(at 3.250006 2.250008 180)
			(size 0.254 0.254)
			(layers "F.Cu" "F.Mask" "F.Paste")
			(net "_NC_CPLD_16")
		)
		(pad "N1" smd circle
			(at -3.250006 2.750007 180)
			(size 0.254 0.254)
			(layers "F.Cu" "F.Mask" "F.Paste")
			(net "_NC_CPLD_5")
		)
		(pad "N2" smd circle
			(at -2.750007 2.750007 180)
			(size 0.254 0.254)
			(layers "F.Cu" "F.Mask" "F.Paste")
			(net "_NC_CPLD_8")
		)
		(pad "N3" thru_hole circle
			(at -2.250008 2.750007 180)
			(size 0.3048 0.3048)
			(drill 0.127)
			(layers "*.Cu" "*.Mask")
			(remove_unused_layers no)
			(net "NWK1_LED_LINK_G_L")
			(clearance 0.1143)
			(thermal_gap 0.1143)
			(padstack
				(mode front_inner_back)
				(layer "Inner"
					(shape circle)
					(size 0 0)
				)
				(layer "B.Cu"
					(shape circle)
					(size 0.3556 0.3556)
					(clearance 0.0889)
				)
			)
		)
		(pad "N4" thru_hole circle
			(at -1.750009 2.750007 180)
			(size 0.3048 0.3048)
			(drill 0.127)
			(layers "*.Cu" "*.Mask")
			(remove_unused_layers no)
			(net "NFP_SPI2_MISO")
			(clearance 0.1143)
			(thermal_gap 0.1143)
			(padstack
				(mode front_inner_back)
				(layer "Inner"
					(shape circle)
					(size 0 0)
				)
				(layer "B.Cu"
					(shape circle)
					(size 0.3556 0.3556)
					(clearance 0.0889)
				)
			)
		)
		(pad "N5" smd circle
			(at -1.25001 2.750007 180)
			(size 0.254 0.254)
			(layers "F.Cu" "F.Mask" "F.Paste")
			(net "_NC_CPLD_9")
		)
		(pad "N6" thru_hole circle
			(at -0.750011 2.750007 180)
			(size 0.3048 0.3048)
			(drill 0.127)
			(layers "*.Cu" "*.Mask")
			(remove_unused_layers no)
			(net "CPLD_SMBUS_SDA")
			(clearance 0.1143)
			(thermal_gap 0.1143)
			(padstack
				(mode front_inner_back)
				(layer "Inner"
					(shape circle)
					(size 0 0)
				)
				(layer "B.Cu"
					(shape circle)
					(size 0.3556 0.3556)
					(clearance 0.0889)
				)
			)
		)
		(pad "N7" smd circle
			(at -0.250012 2.750007 180)
			(size 0.254 0.254)
			(layers "F.Cu" "F.Mask" "F.Paste")
			(net "_NC_FAN_TACH")
		)
		(pad "N8" thru_hole circle
			(at 0.250012 2.750007 180)
			(size 0.3048 0.3048)
			(drill 0.127)
			(layers "*.Cu" "*.Mask")
			(remove_unused_layers no)
			(net "CPLD_VERSION_0")
			(clearance 0.1143)
			(thermal_gap 0.1143)
			(padstack
				(mode front_inner_back)
				(layer "Inner"
					(shape circle)
					(size 0 0)
				)
				(layer "B.Cu"
					(shape circle)
					(size 0.3556 0.3556)
					(clearance 0.0889)
				)
			)
		)
		(pad "N9" smd circle
			(at 0.750011 2.750007 180)
			(size 0.254 0.254)
			(layers "F.Cu" "F.Mask" "F.Paste")
			(net "_NC_CPLD_13")
		)
		(pad "N10" thru_hole circle
			(at 1.25001 2.750007 180)
			(size 0.3048 0.3048)
			(drill 0.127)
			(layers "*.Cu" "*.Mask")
			(remove_unused_layers no)
			(net "CPLD_VERSION_2")
			(clearance 0.1143)
			(thermal_gap 0.1143)
			(padstack
				(mode front_inner_back)
				(layer "Inner"
					(shape circle)
					(size 0 0)
				)
				(layer "B.Cu"
					(shape circle)
					(size 0.3556 0.3556)
					(clearance 0.0889)
				)
			)
		)
		(pad "N11" thru_hole circle
			(at 1.750009 2.750007 180)
			(size 0.3048 0.3048)
			(drill 0.127)
			(layers "*.Cu" "*.Mask")
			(remove_unused_layers no)
			(net "EXT_3.3V")
			(clearance 0.1143)
			(thermal_gap 0.1143)
			(padstack
				(mode front_inner_back)
				(layer "Inner"
					(shape circle)
					(size 0 0)
				)
				(layer "B.Cu"
					(shape circle)
					(size 0.3556 0.3556)
					(clearance 0.0889)
				)
			)
		)
		(pad "N12" thru_hole circle
			(at 2.250008 2.750007 180)
			(size 0.3048 0.3048)
			(drill 0.127)
			(layers "*.Cu" "*.Mask")
			(remove_unused_layers no)
			(net "CPLD_NIC_MEZZ_ID0")
			(clearance 0.1143)
			(thermal_gap 0.1143)
			(padstack
				(mode front_inner_back)
				(layer "Inner"
					(shape circle)
					(size 0 0)
				)
				(layer "B.Cu"
					(shape circle)
					(size 0.3556 0.3556)
					(clearance 0.0889)
				)
			)
		)
		(pad "N13" thru_hole circle
			(at 2.750007 2.750007 180)
			(size 0.3048 0.3048)
			(drill 0.127)
			(layers "*.Cu" "*.Mask")
			(remove_unused_layers no)
			(net "NFP_SRESET_L")
			(clearance 0.1143)
			(thermal_gap 0.1143)
			(padstack
				(mode front_inner_back)
				(layer "Inner"
					(shape circle)
					(size 0 0)
				)
				(layer "B.Cu"
					(shape circle)
					(size 0.3556 0.3556)
					(clearance 0.0889)
				)
			)
		)
		(pad "N14" smd circle
			(at 3.250006 2.750007 180)
			(size 0.254 0.254)
			(layers "F.Cu" "F.Mask" "F.Paste")
			(net "NFP_PGOOD4")
		)
		(pad "P1" smd circle
			(at -3.250006 3.250006 180)
			(size 0.254 0.254)
			(layers "F.Cu" "F.Mask" "F.Paste")
			(net "EXT_3.3V")
		)
		(pad "P2" smd circle
			(at -2.750007 3.250006 180)
			(size 0.254 0.254)
			(layers "F.Cu" "F.Mask" "F.Paste")
			(net "_NC_CPLD_7")
		)
		(pad "P3" smd circle
			(at -2.250008 3.250006 180)
			(size 0.254 0.254)
			(layers "F.Cu" "F.Mask" "F.Paste")
			(net "CPLD_GPIO_2")
		)
		(pad "P4" smd circle
			(at -1.750009 3.250006 180)
			(size 0.254 0.254)
			(layers "F.Cu" "F.Mask" "F.Paste")
			(net "CPLD_PCIE0_WAKE_L")
		)
		(pad "P5" smd circle
			(at -1.25001 3.250006 180)
			(size 0.254 0.254)
			(layers "F.Cu" "F.Mask" "F.Paste")
			(net "GND")
		)
		(pad "P6" smd circle
			(at -0.750011 3.250006 180)
			(size 0.254 0.254)
			(layers "F.Cu" "F.Mask" "F.Paste")
			(net "NFP_PCIE0_RESET_OUT_L")
		)
		(pad "P7" smd circle
			(at -0.250012 3.250006 180)
			(size 0.254 0.254)
			(layers "F.Cu" "F.Mask" "F.Paste")
			(net "CPLD_SMBUS_SCL")
		)
		(pad "P8" smd circle
			(at 0.250012 3.250006 180)
			(size 0.254 0.254)
			(layers "F.Cu" "F.Mask" "F.Paste")
			(net "CPLD_GPIO_0")
		)
		(pad "P9" smd circle
			(at 0.750011 3.250006 180)
			(size 0.254 0.254)
			(layers "F.Cu" "F.Mask" "F.Paste")
			(net "_NC_CPLD_12")
		)
		(pad "P10" smd circle
			(at 1.25001 3.250006 180)
			(size 0.254 0.254)
			(layers "F.Cu" "F.Mask" "F.Paste")
			(net "GND")
		)
		(pad "P11" smd circle
			(at 1.750009 3.250006 180)
			(size 0.254 0.254)
			(layers "F.Cu" "F.Mask" "F.Paste")
			(net "NFP_SPI2_CS")
		)
		(pad "P12" smd circle
			(at 2.250008 3.250006 180)
			(size 0.254 0.254)
			(layers "F.Cu" "F.Mask" "F.Paste")
			(net "_NC_CPLD_15")
		)
		(pad "P13" smd circle
			(at 2.750007 3.250006 180)
			(size 0.254 0.254)
			(layers "F.Cu" "F.Mask" "F.Paste")
			(net "NFP_SPI2_MOSI")
		)
		(pad "P14" smd circle
			(at 3.250006 3.250006 180)
			(size 0.254 0.254)
			(layers "F.Cu" "F.Mask" "F.Paste")
			(net "EXT_3.3V")
		)
		(zone
			(layer "F.Cu")
			(hatch none 0.5)
			(connect_pads
				(clearance 0)
			)
			(min_thickness 0.25)
			(keepout
				(tracks not_allowed)
				(vias allowed)
				(pads allowed)
				(copperpour not_allowed)
				(footprints allowed)
			)
			(placement
				(enabled no)
				(sheetname "")
			)
			(fill
				(thermal_gap 0.5)
				(thermal_bridge_width 0.5)
				(island_removal_mode 0)
			)
			(polygon
				(pts
					(arc
						(start 27.686 19.7104)
						(mid 25.654 19.7104)
						(end 27.686 19.7104)
					)
				)
			)
		)
		(zone
			(layer "F.Cu")
			(hatch none 0.5)
			(connect_pads
				(clearance 0)
			)
			(min_thickness 0.25)
			(keepout
				(tracks not_allowed)
				(vias allowed)
				(pads allowed)
				(copperpour not_allowed)
				(footprints allowed)
			)
			(placement
				(enabled no)
				(sheetname "")
			)
			(fill
				(thermal_gap 0.5)
				(thermal_bridge_width 0.5)
				(island_removal_mode 0)
			)
			(polygon
				(pts
					(arc
						(start 37.719 30.1244)
						(mid 35.687 30.1244)
						(end 37.719 30.1244)
					)
				)
			)
		)
	)
	(footprint ""
		(layer "F.Cu")
		(at 80.250995 18.255996)
		(property "Reference" "V2_A-A10"
			(at 0 0 0)
			(layer "F.SilkS")
			(hide yes)
			(effects
				(font
					(size 1.27 1.27)
				)
			)
		)
		(property "Value" ""
			(at 0 0 0)
			(layer "F.Fab")
			(effects
				(font
					(size 1.27 1.27)
				)
			)
		)
		(duplicate_pad_numbers_are_jumpers no)
		(pad "1" thru_hole circle
			(at 0 0)
			(size 0.762 0.762)
			(drill 0.20574)
			(layers "*.Cu" "*.Mask")
			(remove_unused_layers no)
			(net "DDR0_32A_A10")
			(clearance 0.127)
			(thermal_gap 0.127)
			(padstack
				(mode front_inner_back)
				(layer "Inner"
					(shape circle)
					(size 0.4572 0.4572)
					(clearance 0.1143)
				)
				(layer "B.Cu"
					(shape circle)
					(size 0.4572 0.4572)
					(clearance 0.1143)
				)
			)
		)
	)
	(footprint ""
		(layer "F.Cu")
		(at 78.232 32.576414)
		(property "Reference" "C111"
			(at -0.60833 3.618586 90)
			(unlocked yes)
			(layer "F.SilkS")
			(effects
				(font
					(size 0.7874 0.5842)
					(thickness 0.127)
				)
				(justify left)
			)
		)
		(property "Value" "0.1UF"
			(at -0.091846 0.2921 90)
			(unlocked yes)
			(layer "F.Fab")
			(hide yes)
			(effects
				(font
					(size 0.7874 0.5842)
					(thickness 0.2032)
				)
				(justify left)
			)
		)
		(property "Device Type" "CAPC0073"
			(at -0.091846 0.2921 90)
			(unlocked yes)
			(layer "F.Fab")
			(hide yes)
			(effects
				(font
					(size 0.7874 0.5842)
					(thickness 0.2032)
				)
				(justify left)
			)
		)
		(duplicate_pad_numbers_are_jumpers no)
		(fp_poly
			(pts
				(xy 0.635 1.0668) (xy 0.635 -1.0668) (xy -0.635 -1.0668) (xy -0.635 1.0668)
			)
			(stroke
				(width 0)
				(type default)
			)
			(fill no)
			(layer "F.CrtYd")
		)
		(fp_line
			(start -0.254 -0.508)
			(end 0.254 -0.508)
			(stroke
				(width 0.0254)
				(type default)
			)
			(layer "F.Fab")
		)
		(fp_line
			(start -0.254 0.508)
			(end -0.254 -0.508)
			(stroke
				(width 0.0254)
				(type default)
			)
			(layer "F.Fab")
		)
		(fp_line
			(start 0.254 -0.508)
			(end 0.254 0.508)
			(stroke
				(width 0.0254)
				(type default)
			)
			(layer "F.Fab")
		)
		(fp_line
			(start 0.254 0.508)
			(end -0.254 0.508)
			(stroke
				(width 0.0254)
				(type default)
			)
			(layer "F.Fab")
		)
		(pad "1" smd rect
			(at 0 -0.4191)
			(size 0.508 0.5334)
			(layers "F.Cu" "F.Mask" "F.Paste")
			(net "DDR_VDDQ")
		)
		(pad "2" smd rect
			(at 0 0.4191)
			(size 0.508 0.5334)
			(layers "F.Cu" "F.Mask" "F.Paste")
			(net "DDR_VTT")
		)
		(zone
			(layer "F.Cu")
			(hatch none 0.5)
			(connect_pads
				(clearance 0)
			)
			(min_thickness 0.25)
			(keepout
				(tracks not_allowed)
				(vias allowed)
				(pads allowed)
				(copperpour not_allowed)
				(footprints allowed)
			)
			(placement
				(enabled no)
				(sheetname "")
			)
			(fill
				(thermal_gap 0.5)
				(thermal_bridge_width 0.5)
				(island_removal_mode 0)
			)
			(polygon
				(pts
					(xy 78.2574 32.551014) (xy 78.2574 32.601814) (xy 78.2066 32.601814) (xy 78.2066 32.551014)
				)
			)
		)
	)
	(footprint ""
		(layer "F.Cu")
		(at 84.250987 30.612994)
		(property "Reference" "V3_A-A08"
			(at 0 0 0)
			(layer "F.SilkS")
			(hide yes)
			(effects
				(font
					(size 1.27 1.27)
				)
			)
		)
		(property "Value" ""
			(at 0 0 0)
			(layer "F.Fab")
			(effects
				(font
					(size 1.27 1.27)
				)
			)
		)
		(duplicate_pad_numbers_are_jumpers no)
		(pad "1" thru_hole circle
			(at 0 0)
			(size 0.762 0.762)
			(drill 0.20574)
			(layers "*.Cu" "*.Mask")
			(remove_unused_layers no)
			(net "DDR0_32A_A8")
			(clearance 0.127)
			(thermal_gap 0.127)
			(padstack
				(mode front_inner_back)
				(layer "Inner"
					(shape circle)
					(size 0.4572 0.4572)
					(clearance 0.1143)
				)
				(layer "B.Cu"
					(shape circle)
					(size 0.4572 0.4572)
					(clearance 0.1143)
				)
			)
		)
	)
	(footprint ""
		(layer "F.Cu")
		(at 54.737 18.542 180)
		(property "Reference" "U1"
			(at -12.192 17.9705 0)
			(unlocked yes)
			(layer "F.SilkS")
			(effects
				(font
					(size 1.27 0.9652)
					(thickness 0.1524)
				)
				(justify left)
			)
		)
		(property "Value" "*"
			(at -0.4826 1.74879 180)
			(unlocked yes)
			(layer "F.Fab")
			(hide yes)
			(effects
				(font
					(size 1.27 0.9652)
					(thickness 0.000001)
				)
				(justify left)
			)
		)
		(property "Device Type" "ICBG0048"
			(at -0.4826 1.74879 180)
			(unlocked yes)
			(layer "F.Fab")
			(hide yes)
			(effects
				(font
					(size 1.27 0.9652)
					(thickness 0.000001)
				)
				(justify left)
			)
		)
		(duplicate_pad_numbers_are_jumpers no)
		(fp_line
			(start 16.891 16.891)
			(end 5.524906 16.891)
			(stroke
				(width 0.2032)
				(type default)
			)
			(layer "F.SilkS")
		)
		(fp_line
			(start 16.891 16.891)
			(end -16.891 16.891)
			(stroke
				(width 0.2032)
				(type default)
			)
			(layer "F.SilkS")
		)
		(fp_line
			(start 16.891 -16.891)
			(end 16.891 16.891)
			(stroke
				(width 0.2032)
				(type default)
			)
			(layer "F.SilkS")
		)
		(fp_line
			(start 16.891 -16.891)
			(end 16.891 15.593263)
			(stroke
				(width 0.2032)
				(type default)
			)
			(layer "F.SilkS")
		)
		(fp_line
			(start 12.274956 -16.891)
			(end 16.891 -16.891)
			(stroke
				(width 0.2032)
				(type default)
			)
			(layer "F.SilkS")
		)
		(fp_line
			(start 4.387545 16.891)
			(end 3.38488 16.891)
			(stroke
				(width 0.2032)
				(type default)
			)
			(layer "F.SilkS")
		)
		(fp_line
			(start 2.20312 16.891)
			(end 1.355369 16.891)
			(stroke
				(width 0.2032)
				(type default)
			)
			(layer "F.SilkS")
		)
		(fp_line
			(start 0.168631 16.891)
			(end -16.891 16.891)
			(stroke
				(width 0.2032)
				(type default)
			)
			(layer "F.SilkS")
		)
		(fp_line
			(start -16.891 16.891)
			(end -16.891 -16.891)
			(stroke
				(width 0.2032)
				(type default)
			)
			(layer "F.SilkS")
		)
		(fp_line
			(start -16.891 16.891)
			(end -16.891 -16.891)
			(stroke
				(width 0.2032)
				(type default)
			)
			(layer "F.SilkS")
		)
		(fp_line
			(start -16.891 -16.891)
			(end 16.891 -16.891)
			(stroke
				(width 0.2032)
				(type default)
			)
			(layer "F.SilkS")
		)
		(fp_line
			(start -16.891 -16.891)
			(end 11.601044 -16.891)
			(stroke
				(width 0.2032)
				(type default)
			)
			(layer "F.SilkS")
		)
		(fp_arc
			(start -17.285614 -17.567935)
			(mid -17.491851 -17.326957)
			(end -17.796002 -17.236999)
			(stroke
				(width 0.202997)
				(type default)
			)
			(layer "F.SilkS")
		)
		(fp_arc
			(start -17.796002 -17.236999)
			(mid -17.954708 -17.259998)
			(end -18.100345 -17.327118)
			(stroke
				(width 0.202997)
				(type default)
			)
			(layer "F.SilkS")
		)
		(fp_arc
			(start -17.796002 -18.355005)
			(mid -17.760088 -18.353862)
			(end -17.724323 -18.350408)
			(stroke
				(width 0.202997)
				(type default)
			)
			(layer "F.SilkS")
		)
		(fp_arc
			(start -17.869535 -18.350128)
			(mid -17.832849 -18.353781)
			(end -17.796002 -18.355005)
			(stroke
				(width 0.202997)
				(type default)
			)
			(layer "F.SilkS")
		)
		(fp_circle
			(center -17.542002 -17.415002)
			(end -18.101005 -17.415002)
			(stroke
				(width 0.202997)
				(type default)
			)
			(fill no)
			(layer "F.SilkS")
		)
		(fp_line
			(start 17.75399 13.999997)
			(end 17.253991 13.999997)
			(stroke
				(width 0.202997)
				(type default)
			)
			(layer "B.SilkS")
		)
		(fp_line
			(start 17.75399 3.999992)
			(end 17.253991 3.999992)
			(stroke
				(width 0.202997)
				(type default)
			)
			(layer "B.SilkS")
		)
		(fp_line
			(start 17.75399 -1.999996)
			(end 17.253991 -1.999996)
			(stroke
				(width 0.202997)
				(type default)
			)
			(layer "B.SilkS")
		)
		(fp_line
			(start 17.75399 -12.000001)
			(end 17.253991 -12.000001)
			(stroke
				(width 0.202997)
				(type default)
			)
			(layer "B.SilkS")
		)
		(fp_line
			(start 17.24599 9.000007)
			(end 16.745991 9.000007)
			(stroke
				(width 0.202997)
				(type default)
			)
			(layer "B.SilkS")
		)
		(fp_line
			(start 16.891 16.891)
			(end -16.891 16.891)
			(stroke
				(width 0.2032)
				(type default)
			)
			(layer "B.SilkS")
		)
		(fp_line
			(start 16.891 -16.891)
			(end 16.891 16.891)
			(stroke
				(width 0.2032)
				(type default)
			)
			(layer "B.SilkS")
		)
		(fp_line
			(start 15.97599 -7.000011)
			(end 15.475991 -7.000011)
			(stroke
				(width 0.202997)
				(type default)
			)
			(layer "B.SilkS")
		)
		(fp_line
			(start 13.999997 17.75399)
			(end 13.999997 17.253991)
			(stroke
				(width 0.202997)
				(type default)
			)
			(layer "B.SilkS")
		)
		(fp_line
			(start 13.999997 -17.253991)
			(end 13.999997 -17.75399)
			(stroke
				(width 0.202997)
				(type default)
			)
			(layer "B.SilkS")
		)
		(fp_line
			(start 9.000007 17.75399)
			(end 9.000007 17.253991)
			(stroke
				(width 0.202997)
				(type default)
			)
			(layer "B.SilkS")
		)
		(fp_line
			(start 9.000007 -17.253991)
			(end 9.000007 -17.75399)
			(stroke
				(width 0.202997)
				(type default)
			)
			(layer "B.SilkS")
		)
		(fp_line
			(start 3.999992 17.75399)
			(end 3.999992 17.253991)
			(stroke
				(width 0.202997)
				(type default)
			)
			(layer "B.SilkS")
		)
		(fp_line
			(start 3.999992 -17.253991)
			(end 3.999992 -17.75399)
			(stroke
				(width 0.202997)
				(type default)
			)
			(layer "B.SilkS")
		)
		(fp_line
			(start -1.999996 17.75399)
			(end -1.999996 17.253991)
			(stroke
				(width 0.202997)
				(type default)
			)
			(layer "B.SilkS")
		)
		(fp_line
			(start -1.999996 -17.253991)
			(end -1.999996 -17.75399)
			(stroke
				(width 0.202997)
				(type default)
			)
			(layer "B.SilkS")
		)
		(fp_line
			(start -7.000011 17.75399)
			(end -7.000011 17.253991)
			(stroke
				(width 0.202997)
				(type default)
			)
			(layer "B.SilkS")
		)
		(fp_line
			(start -7.000011 -17.253991)
			(end -7.000011 -17.75399)
			(stroke
				(width 0.202997)
				(type default)
			)
			(layer "B.SilkS")
		)
		(fp_line
			(start -12.000001 17.75399)
			(end -12.000001 17.253991)
			(stroke
				(width 0.202997)
				(type default)
			)
			(layer "B.SilkS")
		)
		(fp_line
			(start -12.000001 -17.253991)
			(end -12.000001 -17.75399)
			(stroke
				(width 0.202997)
				(type default)
			)
			(layer "B.SilkS")
		)
		(fp_line
			(start -16.237991 -7.000011)
			(end -16.73799 -7.000011)
			(stroke
				(width 0.202997)
				(type default)
			)
			(layer "B.SilkS")
		)
		(fp_line
			(start -16.237991 -12.000001)
			(end -16.73799 -12.000001)
			(stroke
				(width 0.202997)
				(type default)
			)
			(layer "B.SilkS")
		)
		(fp_line
			(start -16.891 16.891)
			(end -16.891 -16.891)
			(stroke
				(width 0.2032)
				(type default)
			)
			(layer "B.SilkS")
		)
		(fp_line
			(start -16.891 -16.891)
			(end 16.891 -16.891)
			(stroke
				(width 0.2032)
				(type default)
			)
			(layer "B.SilkS")
		)
		(fp_line
			(start -17.253991 13.999997)
			(end -17.75399 13.999997)
			(stroke
				(width 0.202997)
				(type default)
			)
			(layer "B.SilkS")
		)
		(fp_line
			(start -17.253991 9.000007)
			(end -17.75399 9.000007)
			(stroke
				(width 0.202997)
				(type default)
			)
			(layer "B.SilkS")
		)
		(fp_line
			(start -17.253991 3.999992)
			(end -17.75399 3.999992)
			(stroke
				(width 0.202997)
				(type default)
			)
			(layer "B.SilkS")
		)
		(fp_line
			(start -17.253991 -1.999996)
			(end -17.75399 -1.999996)
			(stroke
				(width 0.202997)
				(type default)
			)
			(layer "B.SilkS")
		)
		(fp_circle
			(center -18.177002 -17.796002)
			(end -18.700598 -17.796002)
			(stroke
				(width 0.2032)
				(type default)
			)
			(fill no)
			(layer "B.SilkS")
		)
		(fp_poly
			(pts
				(xy -20.409992 20.409992) (xy 20.409992 20.409992) (xy 20.409992 -20.409992) (xy -20.409992 -20.409992)
			)
			(stroke
				(width 0)
				(type default)
			)
			(fill no)
			(layer "F.CrtYd")
		)
		(fp_line
			(start 16.599992 16.599992)
			(end 16.599992 -16.599992)
			(stroke
				(width 0.2032)
				(type default)
			)
			(layer "F.Fab")
		)
		(fp_line
			(start 16.599992 -16.599992)
			(end -16.599992 -16.599992)
			(stroke
				(width 0.2032)
				(type default)
			)
			(layer "F.Fab")
		)
		(fp_line
			(start -16.599992 16.599992)
			(end 16.599992 16.599992)
			(stroke
				(width 0.2032)
				(type default)
			)
			(layer "F.Fab")
		)
		(fp_line
			(start -16.599992 -16.599992)
			(end -16.599992 16.599992)
			(stroke
				(width 0.2032)
				(type default)
			)
			(layer "F.Fab")
		)
		(fp_circle
			(center -15.510002 -15.510002)
			(end -16.069005 -15.510002)
			(stroke
				(width 0.202997)
				(type default)
			)
			(fill no)
			(layer "F.Fab")
		)
		(fp_text user "32"
			(at 16.129 -17.55267 0)
			(unlocked yes)
			(layer "F.SilkS")
			(effects
				(font
					(size 0.7874 0.5842)
					(thickness 0.127)
				)
				(justify left)
			)
		)
		(fp_text user "1"
			(at -15.367 -17.55267 0)
			(unlocked yes)
			(layer "F.SilkS")
			(effects
				(font
					(size 0.7874 0.5842)
					(thickness 0.127)
				)
				(justify left)
			)
		)
		(fp_text user "A"
			(at -17.399 -15.52067 0)
			(unlocked yes)
			(layer "F.SilkS")
			(effects
				(font
					(size 0.7874 0.5842)
					(thickness 0.127)
				)
				(justify left)
			)
		)
		(fp_text user "AM"
			(at -17.526 15.72133 0)
			(unlocked yes)
			(layer "F.SilkS")
			(effects
				(font
					(size 0.7874 0.5842)
					(thickness 0.127)
				)
				(justify left)
			)
		)
		(fp_text user "AE"
			(at 18.31467 8.255 270)
			(unlocked yes)
			(layer "B.SilkS")
			(effects
				(font
					(size 0.7874 0.5842)
					(thickness 0.127)
				)
				(justify left mirror)
			)
		)
		(fp_text user "E"
			(at 18.161 -12.21867 0)
			(unlocked yes)
			(layer "B.SilkS")
			(effects
				(font
					(size 0.7874 0.5842)
					(thickness 0.127)
				)
				(justify left mirror)
			)
		)
		(fp_text user "AK"
			(at 18.002199 14.088618 0)
			(unlocked yes)
			(layer "B.SilkS")
			(effects
				(font
					(size 0.7874 0.5842)
					(thickness 0.127)
				)
				(justify left mirror)
			)
		)
		(fp_text user "AM"
			(at 17.314189 16.51574 0)
			(unlocked yes)
			(layer "B.SilkS")
			(effects
				(font
					(size 0.7874 0.5842)
					(thickness 0.127)
				)
				(justify left mirror)
			)
		)
		(fp_text user "A"
			(at 17.145 -15.64767 0)
			(unlocked yes)
			(layer "B.SilkS")
			(effects
				(font
					(size 0.7874 0.5842)
					(thickness 0.127)
				)
				(justify left mirror)
			)
		)
		(fp_text user "Y"
			(at 15.875 3.02133 0)
			(unlocked yes)
			(layer "B.SilkS")
			(effects
				(font
					(size 0.7874 0.5842)
					(thickness 0.127)
				)
				(justify left mirror)
			)
		)
		(fp_text user "32"
			(at 15.748 17.62633 0)
			(unlocked yes)
			(layer "B.SilkS")
			(effects
				(font
					(size 0.7874 0.5842)
					(thickness 0.127)
				)
				(justify left mirror)
			)
		)
		(fp_text user "32"
			(at 15.494 -17.55267 0)
			(unlocked yes)
			(layer "B.SilkS")
			(effects
				(font
					(size 0.7874 0.5842)
					(thickness 0.127)
				)
				(justify left mirror)
			)
		)
		(fp_text user "R"
			(at 15.367 -1.80467 0)
			(unlocked yes)
			(layer "B.SilkS")
			(effects
				(font
					(size 0.7874 0.5842)
					(thickness 0.127)
				)
				(justify left mirror)
			)
		)
		(fp_text user "K"
			(at 13.208 -7.13867 0)
			(unlocked yes)
			(layer "B.SilkS")
			(effects
				(font
					(size 0.7874 0.5842)
					(thickness 0.127)
				)
				(justify left mirror)
			)
		)
		(fp_text user "AK"
			(at -14.732 14.07033 0)
			(unlocked yes)
			(layer "B.SilkS")
			(effects
				(font
					(size 0.7874 0.5842)
					(thickness 0.127)
				)
				(justify left mirror)
			)
		)
		(fp_text user "K"
			(at -15.113 -7.13867 0)
			(unlocked yes)
			(layer "B.SilkS")
			(effects
				(font
					(size 0.7874 0.5842)
					(thickness 0.127)
				)
				(justify left mirror)
			)
		)
		(fp_text user "E"
			(at -15.113 -11.96467 0)
			(unlocked yes)
			(layer "B.SilkS")
			(effects
				(font
					(size 0.7874 0.5842)
					(thickness 0.127)
				)
				(justify left mirror)
			)
		)
		(fp_text user "1"
			(at -15.494 17.62633 0)
			(unlocked yes)
			(layer "B.SilkS")
			(effects
				(font
					(size 0.7874 0.5842)
					(thickness 0.127)
				)
				(justify left mirror)
			)
		)
		(fp_text user "AM"
			(at -15.59433 15.24 270)
			(unlocked yes)
			(layer "B.SilkS")
			(effects
				(font
					(size 0.7874 0.5842)
					(thickness 0.127)
				)
				(justify left mirror)
			)
		)
		(fp_text user "Y"
			(at -15.748 3.40233 0)
			(unlocked yes)
			(layer "B.SilkS")
			(effects
				(font
					(size 0.7874 0.5842)
					(thickness 0.127)
				)
				(justify left mirror)
			)
		)
		(fp_text user "R"
			(at -15.875 -2.56667 0)
			(unlocked yes)
			(layer "B.SilkS")
			(effects
				(font
					(size 0.7874 0.5842)
					(thickness 0.127)
				)
				(justify left mirror)
			)
		)
		(fp_text user "1"
			(at -17.018 -18.06067 0)
			(unlocked yes)
			(layer "B.SilkS")
			(effects
				(font
					(size 0.7874 0.5842)
					(thickness 0.127)
				)
				(justify left mirror)
			)
		)
		(fp_text user "A"
			(at -18.034 -16.53667 0)
			(unlocked yes)
			(layer "B.SilkS")
			(effects
				(font
					(size 0.7874 0.5842)
					(thickness 0.127)
				)
				(justify left mirror)
			)
		)
		(fp_text user "AE"
			(at -19.304 8.73633 0)
			(unlocked yes)
			(layer "B.SilkS")
			(effects
				(font
					(size 0.7874 0.5842)
					(thickness 0.127)
				)
				(justify left mirror)
			)
		)
		(fp_text user "32"
			(at 15.875 -17.19707 0)
			(unlocked yes)
			(layer "F.Fab")
			(effects
				(font
					(size 0.7874 0.5842)
					(thickness 0.127)
				)
				(justify left)
			)
		)
		(fp_text user "1"
			(at -15.24 -17.29867 0)
			(unlocked yes)
			(layer "F.Fab")
			(effects
				(font
					(size 0.7874 0.5842)
					(thickness 0.127)
				)
				(justify left)
			)
		)
		(fp_text user "A"
			(at -16.891 -15.39367 0)
			(unlocked yes)
			(layer "F.Fab")
			(effects
				(font
					(size 0.7874 0.5842)
					(thickness 0.127)
				)
				(justify left)
			)
		)
		(fp_text user "AM"
			(at -17.018 16.10233 0)
			(unlocked yes)
			(layer "F.Fab")
			(effects
				(font
					(size 0.7874 0.5842)
					(thickness 0.127)
				)
				(justify left)
			)
		)
		(pad "" smd circle
			(at -15.875 18.161 180)
			(size 1.0668 1.0668)
			(layers "F.Cu" "F.Mask" "F.Paste")
		)
		(pad "" smd circle
			(at 12.573 -17.78 180)
			(size 1.0668 1.0668)
			(layers "F.Cu" "F.Mask" "F.Paste")
		)
		(pad "A2" smd circle
			(at -14.499996 -15.499994 180)
			(size 0.6604 0.6604)
			(layers "F.Cu" "F.Mask" "F.Paste")
			(net "GND")
		)
		(pad "A3" smd circle
			(at -13.499998 -15.499994 180)
			(size 0.6604 0.6604)
			(layers "F.Cu" "F.Mask" "F.Paste")
			(net "GND")
		)
		(pad "A4" smd circle
			(at -12.5 -15.499994 180)
			(size 0.508 0.508)
			(layers "F.Cu" "F.Mask" "F.Paste")
			(net "GND")
		)
		(pad "A5" smd circle
			(at -11.500002 -15.499994 180)
			(size 0.508 0.508)
			(layers "F.Cu" "F.Mask" "F.Paste")
			(net "GND")
		)
		(pad "A6" smd circle
			(at -10.500004 -15.499994 180)
			(size 0.508 0.508)
			(layers "F.Cu" "F.Mask" "F.Paste")
			(net "GND")
		)
		(pad "A7" smd circle
			(at -9.500006 -15.499994 180)
			(size 0.508 0.508)
			(layers "F.Cu" "F.Mask" "F.Paste")
			(net "GND")
		)
		(pad "A8" smd circle
			(at -8.500008 -15.499994 180)
			(size 0.508 0.508)
			(layers "F.Cu" "F.Mask" "F.Paste")
			(net "GND")
		)
		(pad "A9" smd circle
			(at -7.50001 -15.499994 180)
			(size 0.508 0.508)
			(layers "F.Cu" "F.Mask" "F.Paste")
			(net "GND")
		)
		(pad "A10" smd circle
			(at -6.500012 -15.499994 180)
			(size 0.508 0.508)
			(layers "F.Cu" "F.Mask" "F.Paste")
			(net "GND")
		)
		(pad "A11" smd circle
			(at -5.499989 -15.499994 180)
			(size 0.508 0.508)
			(layers "F.Cu" "F.Mask" "F.Paste")
			(net "VDD_CORE")
		)
		(pad "A12" smd circle
			(at -4.499991 -15.499994 180)
			(size 0.508 0.508)
			(layers "F.Cu" "F.Mask" "F.Paste")
			(net "GND")
		)
		(pad "A13" smd circle
			(at -3.499993 -15.499994 180)
			(size 0.508 0.508)
			(layers "F.Cu" "F.Mask" "F.Paste")
			(net "VDD_CORE")
		)
		(pad "A14" smd circle
			(at -2.499995 -15.499994 180)
			(size 0.508 0.508)
			(layers "F.Cu" "F.Mask" "F.Paste")
			(net "GND")
		)
		(pad "A15" smd circle
			(at -1.499997 -15.499994 180)
			(size 0.508 0.508)
			(layers "F.Cu" "F.Mask" "F.Paste")
			(net "VDD_CORE")
		)
		(pad "A16" smd circle
			(at -0.499999 -15.499994 180)
			(size 0.508 0.508)
			(layers "F.Cu" "F.Mask" "F.Paste")
			(net "GND")
		)
		(pad "A17" smd circle
			(at 0.499999 -15.499994 180)
			(size 0.508 0.508)
			(layers "F.Cu" "F.Mask" "F.Paste")
			(net "VDD_CORE")
		)
		(pad "A18" smd circle
			(at 1.499997 -15.499994 180)
			(size 0.508 0.508)
			(layers "F.Cu" "F.Mask" "F.Paste")
			(net "GND")
		)
		(pad "A19" smd circle
			(at 2.499995 -15.499994 180)
			(size 0.508 0.508)
			(layers "F.Cu" "F.Mask" "F.Paste")
			(net "VDD_CORE")
		)
		(pad "A20" smd circle
			(at 3.499993 -15.499994 180)
			(size 0.508 0.508)
			(layers "F.Cu" "F.Mask" "F.Paste")
			(net "GND")
		)
		(pad "A21" smd circle
			(at 4.499991 -15.499994 180)
			(size 0.508 0.508)
			(layers "F.Cu" "F.Mask" "F.Paste")
			(net "VDD_CORE")
		)
		(pad "A22" smd circle
			(at 5.499989 -15.499994 180)
			(size 0.508 0.508)
			(layers "F.Cu" "F.Mask" "F.Paste")
			(net "GND")
		)
		(pad "A23" smd circle
			(at 6.500012 -15.499994 180)
			(size 0.508 0.508)
			(layers "F.Cu" "F.Mask" "F.Paste")
			(net "VDD_CORE")
		)
		(pad "A24" smd circle
			(at 7.50001 -15.499994 180)
			(size 0.508 0.508)
			(layers "F.Cu" "F.Mask" "F.Paste")
			(net "GND")
		)
		(pad "A25" smd circle
			(at 8.500008 -15.499994 180)
			(size 0.508 0.508)
			(layers "F.Cu" "F.Mask" "F.Paste")
			(net "VDD_CORE")
		)
		(pad "A26" smd circle
			(at 9.500006 -15.499994 180)
			(size 0.508 0.508)
			(layers "F.Cu" "F.Mask" "F.Paste")
			(net "GND")
		)
		(pad "A27" smd circle
			(at 10.500004 -15.499994 180)
			(size 0.508 0.508)
			(layers "F.Cu" "F.Mask" "F.Paste")
			(net "_NC_TEST_SCAN_0_OUT33")
		)
		(pad "A28" smd circle
			(at 11.500002 -15.499994 180)
			(size 0.508 0.508)
			(layers "F.Cu" "F.Mask" "F.Paste")
			(net "_NC_TEST_SCAN_0_OUT27")
		)
		(pad "A29" smd circle
			(at 12.5 -15.499994 180)
			(size 0.508 0.508)
			(layers "F.Cu" "F.Mask" "F.Paste")
			(net "_NC_TEST_SCAN_0_OUT30")
		)
		(pad "A30" smd circle
			(at 13.499998 -15.499994 180)
			(size 0.6604 0.6604)
			(layers "F.Cu" "F.Mask" "F.Paste")
			(net "GND")
		)
		(pad "A31" smd circle
			(at 14.499996 -15.499994 180)
			(size 0.6604 0.6604)
			(layers "F.Cu" "F.Mask" "F.Paste")
			(net "GND")
		)
		(pad "AA1" smd circle
			(at -15.499994 4.499991 180)
			(size 0.508 0.508)
			(layers "F.Cu" "F.Mask" "F.Paste")
			(net "DDR0_32A_DQ19")
		)
		(pad "AA2" smd circle
			(at -14.499996 4.499991 180)
			(size 0.508 0.508)
			(layers "F.Cu" "F.Mask" "F.Paste")
			(net "DDR_VDDQ")
		)
		(pad "AA3" smd circle
			(at -13.499998 4.499991 180)
			(size 0.508 0.508)
			(layers "F.Cu" "F.Mask" "F.Paste")
			(net "DDR0_32A_DQ16")
		)
		(pad "AA4" smd circle
			(at -12.5 4.499991 180)
			(size 0.508 0.508)
			(layers "F.Cu" "F.Mask" "F.Paste")
			(net "DDR0_32A_DQ21")
		)
		(pad "AA5" smd circle
			(at -11.500002 4.499991 180)
			(size 0.508 0.508)
			(layers "F.Cu" "F.Mask" "F.Paste")
			(net "DDR_VDDQ")
		)
		(pad "AA6" smd circle
			(at -10.500004 4.499991 180)
			(size 0.508 0.508)
			(layers "F.Cu" "F.Mask" "F.Paste")
			(net "DDR0_32A_DQ18")
		)
		(pad "AA7" smd circle
			(at -9.500006 4.499991 180)
			(size 0.508 0.508)
			(layers "F.Cu" "F.Mask" "F.Paste")
			(net "DDR0_32A_ODT0")
		)
		(pad "AA8" smd circle
			(at -8.500008 4.499991 180)
			(size 0.508 0.508)
			(layers "F.Cu" "F.Mask" "F.Paste")
			(net "DDR_VDDQ")
		)
		(pad "AA9" smd circle
			(at -7.50001 4.499991 180)
			(size 0.508 0.508)
			(layers "F.Cu" "F.Mask" "F.Paste")
			(net "A_AZQ")
		)
		(pad "AA10" smd circle
			(at -6.500012 4.499991 180)
			(size 0.508 0.508)
			(layers "F.Cu" "F.Mask" "F.Paste")
			(net "VDDA_DDR0_32B")
		)
		(pad "AA11" smd circle
			(at -5.499989 4.499991 180)
			(size 0.508 0.508)
			(layers "F.Cu" "F.Mask" "F.Paste")
			(net "VDD_CORE")
		)
		(pad "AA12" smd circle
			(at -4.499991 4.499991 180)
			(size 0.508 0.508)
			(layers "F.Cu" "F.Mask" "F.Paste")
			(net "GND")
		)
		(pad "AA13" smd circle
			(at -3.499993 4.499991 180)
			(size 0.508 0.508)
			(layers "F.Cu" "F.Mask" "F.Paste")
			(net "VDD_CORE")
		)
		(pad "AA14" smd circle
			(at -2.499995 4.499991 180)
			(size 0.508 0.508)
			(layers "F.Cu" "F.Mask" "F.Paste")
			(net "GND")
		)
		(pad "AA15" smd circle
			(at -1.499997 4.499991 180)
			(size 0.508 0.508)
			(layers "F.Cu" "F.Mask" "F.Paste")
			(net "VDD_CORE")
		)
		(pad "AA16" smd circle
			(at -0.499999 4.499991 180)
			(size 0.508 0.508)
			(layers "F.Cu" "F.Mask" "F.Paste")
			(net "GND")
		)
		(pad "AA17" smd circle
			(at 0.499999 4.499991 180)
			(size 0.508 0.508)
			(layers "F.Cu" "F.Mask" "F.Paste")
			(net "VDD_CORE")
		)
		(pad "AA18" smd circle
			(at 1.499997 4.499991 180)
			(size 0.508 0.508)
			(layers "F.Cu" "F.Mask" "F.Paste")
			(net "GND")
		)
		(pad "AA19" smd circle
			(at 2.499995 4.499991 180)
			(size 0.508 0.508)
			(layers "F.Cu" "F.Mask" "F.Paste")
			(net "VDD_CORE")
		)
		(pad "AA20" smd circle
			(at 3.499993 4.499991 180)
			(size 0.508 0.508)
			(layers "F.Cu" "F.Mask" "F.Paste")
			(net "GND")
		)
		(pad "AA21" smd circle
			(at 4.499991 4.499991 180)
			(size 0.508 0.508)
			(layers "F.Cu" "F.Mask" "F.Paste")
			(net "VDD_CORE")
		)
		(pad "AA22" smd circle
			(at 5.499989 4.499991 180)
			(size 0.508 0.508)
			(layers "F.Cu" "F.Mask" "F.Paste")
			(net "GND")
		)
		(pad "AA23" smd circle
			(at 6.500012 4.499991 180)
			(size 0.508 0.508)
			(layers "F.Cu" "F.Mask" "F.Paste")
			(net "VDD_CORE")
		)
		(pad "AA24" smd circle
			(at 7.50001 4.499991 180)
			(size 0.508 0.508)
			(layers "F.Cu" "F.Mask" "F.Paste")
			(net "GND")
		)
		(pad "AA25" smd circle
			(at 8.500008 4.499991 180)
			(size 0.508 0.508)
			(layers "F.Cu" "F.Mask" "F.Paste")
			(net "VDD_CORE")
		)
		(pad "AA26" smd circle
			(at 9.500006 4.499991 180)
			(size 0.508 0.508)
			(layers "F.Cu" "F.Mask" "F.Paste")
			(net "GND")
		)
		(pad "AA27" smd circle
			(at 10.500004 4.499991 180)
			(size 0.508 0.508)
			(layers "F.Cu" "F.Mask" "F.Paste")
			(net "VDD_3.3V")
		)
		(pad "AA28" smd circle
			(at 11.500002 4.499991 180)
			(size 0.508 0.508)
			(layers "F.Cu" "F.Mask" "F.Paste")
			(net "NFP_CPLD_INT_L")
		)
		(pad "AA29" smd circle
			(at 12.5 4.499991 180)
			(size 0.508 0.508)
			(layers "F.Cu" "F.Mask" "F.Paste")
			(net "NFP_ARM_SPI_FLASH_WP_L")
		)
		(pad "AA30" smd circle
			(at 13.499998 4.499991 180)
			(size 0.508 0.508)
			(layers "F.Cu" "F.Mask" "F.Paste")
			(net "_NC_NFP_GPIO6")
		)
		(pad "AA31" smd circle
			(at 14.499996 4.499991 180)
			(size 0.508 0.508)
			(layers "F.Cu" "F.Mask" "F.Paste")
			(net "NFP_JTAG_ARM_TCK")
		)
		(pad "AA32" smd circle
			(at 15.499994 4.499991 180)
			(size 0.508 0.508)
			(layers "F.Cu" "F.Mask" "F.Paste")
			(net "NFP_JTAG_ARM_TMS")
		)
		(pad "AB1" smd circle
			(at -15.499994 5.499989 180)
			(size 0.508 0.508)
			(layers "F.Cu" "F.Mask" "F.Paste")
			(net "DDR0_32A_DQ17")
		)
		(pad "AB2" smd circle
			(at -14.499996 5.499989 180)
			(size 0.508 0.508)
			(layers "F.Cu" "F.Mask" "F.Paste")
			(net "GND")
		)
		(pad "AB3" smd circle
			(at -13.499998 5.499989 180)
			(size 0.508 0.508)
			(layers "F.Cu" "F.Mask" "F.Paste")
			(net "DDR0_32A_DQ8")
		)
		(pad "AB4" smd circle
			(at -12.5 5.499989 180)
			(size 0.508 0.508)
			(layers "F.Cu" "F.Mask" "F.Paste")
			(net "DDR0_32A_DQ10")
		)
		(pad "AB5" smd circle
			(at -11.500002 5.499989 180)
			(size 0.508 0.508)
			(layers "F.Cu" "F.Mask" "F.Paste")
			(net "GND")
		)
		(pad "AB6" smd circle
			(at -10.500004 5.499989 180)
			(size 0.508 0.508)
			(layers "F.Cu" "F.Mask" "F.Paste")
			(net "DDR0_32A_BA1")
		)
		(pad "AB7" smd circle
			(at -9.500006 5.499989 180)
			(size 0.508 0.508)
			(layers "F.Cu" "F.Mask" "F.Paste")
			(net "DDR0_32A_RAS_L")
		)
		(pad "AB8" smd circle
			(at -8.500008 5.499989 180)
			(size 0.508 0.508)
			(layers "F.Cu" "F.Mask" "F.Paste")
			(net "GND")
		)
		(pad "AB9" smd circle
			(at -7.50001 5.499989 180)
			(size 0.508 0.508)
			(layers "F.Cu" "F.Mask" "F.Paste")
			(net "DDR0_32A_CAS_L")
		)
		(pad "AB10" smd circle
			(at -6.500012 5.499989 180)
			(size 0.508 0.508)
			(layers "F.Cu" "F.Mask" "F.Paste")
			(net "VDDA_DDR0_32A")
		)
		(pad "AB11" smd circle
			(at -5.499989 5.499989 180)
			(size 0.508 0.508)
			(layers "F.Cu" "F.Mask" "F.Paste")
			(net "GND")
		)
		(pad "AB12" smd circle
			(at -4.499991 5.499989 180)
			(size 0.508 0.508)
			(layers "F.Cu" "F.Mask" "F.Paste")
			(net "VDD_CORE")
		)
		(pad "AB13" smd circle
			(at -3.499993 5.499989 180)
			(size 0.508 0.508)
			(layers "F.Cu" "F.Mask" "F.Paste")
			(net "GND")
		)
		(pad "AB14" smd circle
			(at -2.499995 5.499989 180)
			(size 0.508 0.508)
			(layers "F.Cu" "F.Mask" "F.Paste")
			(net "VDD_CORE")
		)
		(pad "AB15" smd circle
			(at -1.499997 5.499989 180)
			(size 0.508 0.508)
			(layers "F.Cu" "F.Mask" "F.Paste")
			(net "GND")
		)
		(pad "AB16" smd circle
			(at -0.499999 5.499989 180)
			(size 0.508 0.508)
			(layers "F.Cu" "F.Mask" "F.Paste")
			(net "VDD_CORE")
		)
		(pad "AB17" smd circle
			(at 0.499999 5.499989 180)
			(size 0.508 0.508)
			(layers "F.Cu" "F.Mask" "F.Paste")
			(net "GND")
		)
		(pad "AB18" smd circle
			(at 1.499997 5.499989 180)
			(size 0.508 0.508)
			(layers "F.Cu" "F.Mask" "F.Paste")
			(net "VDD_CORE")
		)
		(pad "AB19" smd circle
			(at 2.499995 5.499989 180)
			(size 0.508 0.508)
			(layers "F.Cu" "F.Mask" "F.Paste")
			(net "GND")
		)
		(pad "AB20" smd circle
			(at 3.499993 5.499989 180)
			(size 0.508 0.508)
			(layers "F.Cu" "F.Mask" "F.Paste")
			(net "VDD_CORE")
		)
		(pad "AB21" smd circle
			(at 4.499991 5.499989 180)
			(size 0.508 0.508)
			(layers "F.Cu" "F.Mask" "F.Paste")
			(net "GND")
		)
		(pad "AB22" smd circle
			(at 5.499989 5.499989 180)
			(size 0.508 0.508)
			(layers "F.Cu" "F.Mask" "F.Paste")
			(net "VDD_CORE")
		)
		(pad "AB23" smd circle
			(at 6.500012 5.499989 180)
			(size 0.508 0.508)
			(layers "F.Cu" "F.Mask" "F.Paste")
			(net "GND")
		)
		(pad "AB24" smd circle
			(at 7.50001 5.499989 180)
			(size 0.508 0.508)
			(layers "F.Cu" "F.Mask" "F.Paste")
			(net "VDD_CORE")
		)
		(pad "AB25" smd circle
			(at 8.500008 5.499989 180)
			(size 0.508 0.508)
			(layers "F.Cu" "F.Mask" "F.Paste")
			(net "GND")
		)
		(pad "AB26" smd circle
			(at 9.500006 5.499989 180)
			(size 0.508 0.508)
			(layers "F.Cu" "F.Mask" "F.Paste")
			(net "VDD_3.3V")
		)
		(pad "AB27" smd circle
			(at 10.500004 5.499989 180)
			(size 0.508 0.508)
			(layers "F.Cu" "F.Mask" "F.Paste")
			(net "CPLD_PGRM_JTAG_SEL")
		)
		(pad "AB28" smd circle
			(at 11.500002 5.499989 180)
			(size 0.508 0.508)
			(layers "F.Cu" "F.Mask" "F.Paste")
			(net "_PSU_I2C_SDA")
		)
		(pad "AB29" smd circle
			(at 12.5 5.499989 180)
			(size 0.508 0.508)
			(layers "F.Cu" "F.Mask" "F.Paste")
			(net "_PSU_I2C_SCL")
		)
		(pad "AB30" smd circle
			(at 13.499998 5.499989 180)
			(size 0.508 0.508)
			(layers "F.Cu" "F.Mask" "F.Paste")
			(net "NFP_FAIL_SAFE_BOOT_L")
		)
		(pad "AB31" smd circle
			(at 14.499996 5.499989 180)
			(size 0.508 0.508)
			(layers "F.Cu" "F.Mask" "F.Paste")
			(net "PGRM_JTAG_TRST_L")
		)
		(pad "AB32" smd circle
			(at 15.499994 5.499989 180)
			(size 0.508 0.508)
			(layers "F.Cu" "F.Mask" "F.Paste")
			(net "PGRM_JTAG_TCK")
		)
		(pad "AC1" smd circle
			(at -15.499994 6.500012 180)
			(size 0.508 0.508)
			(layers "F.Cu" "F.Mask" "F.Paste")
			(net "DDR0_32A_DQ11")
		)
		(pad "AC2" smd circle
			(at -14.499996 6.500012 180)
			(size 0.508 0.508)
			(layers "F.Cu" "F.Mask" "F.Paste")
			(net "DDR0_32A_DQ13")
		)
		(pad "AC3" smd circle
			(at -13.499998 6.500012 180)
			(size 0.508 0.508)
			(layers "F.Cu" "F.Mask" "F.Paste")
			(net "DDR0_32A_DQS1_P")
		)
		(pad "AC4" smd circle
			(at -12.5 6.500012 180)
			(size 0.508 0.508)
			(layers "F.Cu" "F.Mask" "F.Paste")
			(net "DDR0_32A_DQS1_N")
		)
		(pad "AC5" smd circle
			(at -11.500002 6.500012 180)
			(size 0.508 0.508)
			(layers "F.Cu" "F.Mask" "F.Paste")
			(net "DDR0_32A_DQ12")
		)
		(pad "AC6" smd circle
			(at -10.500004 6.500012 180)
			(size 0.508 0.508)
			(layers "F.Cu" "F.Mask" "F.Paste")
			(net "DDR0_32A_WE_L")
		)
		(pad "AC7" smd circle
			(at -9.500006 6.500012 180)
			(size 0.508 0.508)
			(layers "F.Cu" "F.Mask" "F.Paste")
			(net "DDR0_32A_CKE0")
		)
		(pad "AC8" smd circle
			(at -8.500008 6.500012 180)
			(size 0.508 0.508)
			(layers "F.Cu" "F.Mask" "F.Paste")
			(net "DDR0_32A_A4")
		)
		(pad "AC9" smd circle
			(at -7.50001 6.500012 180)
			(size 0.508 0.508)
			(layers "F.Cu" "F.Mask" "F.Paste")
			(net "_NC_NFP_DDR0_32A_PLL_ATO")
		)
		(pad "AC10" smd circle
			(at -6.500012 6.500012 180)
			(size 0.508 0.508)
			(layers "F.Cu" "F.Mask" "F.Paste")
			(net "VDDA_DDR0_32A")
		)
		(pad "AC11" smd circle
			(at -5.499989 6.500012 180)
			(size 0.508 0.508)
			(layers "F.Cu" "F.Mask" "F.Paste")
			(net "VDD_CORE")
		)
		(pad "AC12" smd circle
			(at -4.499991 6.500012 180)
			(size 0.508 0.508)
			(layers "F.Cu" "F.Mask" "F.Paste")
			(net "GND")
		)
		(pad "AC13" smd circle
			(at -3.499993 6.500012 180)
			(size 0.508 0.508)
			(layers "F.Cu" "F.Mask" "F.Paste")
			(net "VDD_CORE")
		)
		(pad "AC14" smd circle
			(at -2.499995 6.500012 180)
			(size 0.508 0.508)
			(layers "F.Cu" "F.Mask" "F.Paste")
			(net "GND")
		)
		(pad "AC15" smd circle
			(at -1.499997 6.500012 180)
			(size 0.508 0.508)
			(layers "F.Cu" "F.Mask" "F.Paste")
			(net "VDD_CORE")
		)
		(pad "AC16" smd circle
			(at -0.499999 6.500012 180)
			(size 0.508 0.508)
			(layers "F.Cu" "F.Mask" "F.Paste")
			(net "GND")
		)
		(pad "AC17" smd circle
			(at 0.499999 6.500012 180)
			(size 0.508 0.508)
			(layers "F.Cu" "F.Mask" "F.Paste")
			(net "VDD_CORE")
		)
		(pad "AC18" smd circle
			(at 1.499997 6.500012 180)
			(size 0.508 0.508)
			(layers "F.Cu" "F.Mask" "F.Paste")
			(net "VDDA_PLL")
		)
		(pad "AC19" smd circle
			(at 2.499995 6.500012 180)
			(size 0.508 0.508)
			(layers "F.Cu" "F.Mask" "F.Paste")
			(net "VDD_CORE")
		)
		(pad "AC20" smd circle
			(at 3.499993 6.500012 180)
			(size 0.508 0.508)
			(layers "F.Cu" "F.Mask" "F.Paste")
			(net "GND")
		)
		(pad "AC21" smd circle
			(at 4.499991 6.500012 180)
			(size 0.508 0.508)
			(layers "F.Cu" "F.Mask" "F.Paste")
			(net "VDD_CORE")
		)
		(pad "AC22" smd circle
			(at 5.499989 6.500012 180)
			(size 0.508 0.508)
			(layers "F.Cu" "F.Mask" "F.Paste")
			(net "GND")
		)
		(pad "AC23" smd circle
			(at 6.500012 6.500012 180)
			(size 0.508 0.508)
			(layers "F.Cu" "F.Mask" "F.Paste")
			(net "VDD_CORE")
		)
		(pad "AC24" smd circle
			(at 7.50001 6.500012 180)
			(size 0.508 0.508)
			(layers "F.Cu" "F.Mask" "F.Paste")
			(net "NFP_VDD_CORE_SENSE_VSS")
		)
		(pad "AC25" smd circle
			(at 8.500008 6.500012 180)
			(size 0.508 0.508)
			(layers "F.Cu" "F.Mask" "F.Paste")
			(net "NFP_VDD_CORE_SENSE_VDD")
		)
		(pad "AC26" smd circle
			(at 9.500006 6.500012 180)
			(size 0.508 0.508)
			(layers "F.Cu" "F.Mask" "F.Paste")
			(net "GND")
		)
		(pad "AC27" smd circle
			(at 10.500004 6.500012 180)
			(size 0.508 0.508)
			(layers "F.Cu" "F.Mask" "F.Paste")
			(net "NFP_CPLD_PRGM_JTAG_TDI")
		)
		(pad "AC28" smd circle
			(at 11.500002 6.500012 180)
			(size 0.508 0.508)
			(layers "F.Cu" "F.Mask" "F.Paste")
			(net "NFP_CPLD_PRGM_JTAG_TDO")
		)
		(pad "AC29" smd circle
			(at 12.5 6.500012 180)
			(size 0.508 0.508)
			(layers "F.Cu" "F.Mask" "F.Paste")
			(net "GND")
		)
		(pad "AC30" smd circle
			(at 13.499998 6.500012 180)
			(size 0.508 0.508)
			(layers "F.Cu" "F.Mask" "F.Paste")
			(net "NFP_CPLD_PRGM_JTAG_TMS")
		)
		(pad "AC31" smd circle
			(at 14.499996 6.500012 180)
			(size 0.508 0.508)
			(layers "F.Cu" "F.Mask" "F.Paste")
			(net "PGRM_JTAG_TMS")
		)
		(pad "AC32" smd circle
			(at 15.499994 6.500012 180)
			(size 0.508 0.508)
			(layers "F.Cu" "F.Mask" "F.Paste")
			(net "_PGRM_JTAG_TDO")
		)
		(pad "AD1" smd circle
			(at -15.499994 7.50001 180)
			(size 0.508 0.508)
			(layers "F.Cu" "F.Mask" "F.Paste")
			(net "DDR0_32A_DQ3")
		)
		(pad "AD2" smd circle
			(at -14.499996 7.50001 180)
			(size 0.508 0.508)
			(layers "F.Cu" "F.Mask" "F.Paste")
			(net "DDR0_32A_DQ9")
		)
		(pad "AD3" smd circle
			(at -13.499998 7.50001 180)
			(size 0.508 0.508)
			(layers "F.Cu" "F.Mask" "F.Paste")
			(net "DDR0_32A_DM1")
		)
		(pad "AD4" smd circle
			(at -12.5 7.50001 180)
			(size 0.508 0.508)
			(layers "F.Cu" "F.Mask" "F.Paste")
			(net "DDR0_32A_DQ14")
		)
		(pad "AD5" smd circle
			(at -11.500002 7.50001 180)
			(size 0.508 0.508)
			(layers "F.Cu" "F.Mask" "F.Paste")
			(net "DDR0_32A_DQ15")
		)
		(pad "AD6" smd circle
			(at -10.500004 7.50001 180)
			(size 0.508 0.508)
			(layers "F.Cu" "F.Mask" "F.Paste")
			(net "DDR0_32A_BA2")
		)
		(pad "AD7" smd circle
			(at -9.500006 7.50001 180)
			(size 0.508 0.508)
			(layers "F.Cu" "F.Mask" "F.Paste")
			(net "DDR0_32A_A6")
		)
		(pad "AD8" smd circle
			(at -8.500008 7.50001 180)
			(size 0.508 0.508)
			(layers "F.Cu" "F.Mask" "F.Paste")
			(net "DDR0_32A_A0")
		)
		(pad "AD9" smd circle
			(at -7.50001 7.50001 180)
			(size 0.508 0.508)
			(layers "F.Cu" "F.Mask" "F.Paste")
			(net "DDR0_32A_A2")
		)
		(pad "AD10" smd circle
			(at -6.500012 7.50001 180)
			(size 0.508 0.508)
			(layers "F.Cu" "F.Mask" "F.Paste")
			(net "GND")
		)
		(pad "AD11" smd circle
			(at -5.499989 7.50001 180)
			(size 0.508 0.508)
			(layers "F.Cu" "F.Mask" "F.Paste")
			(net "GND")
		)
		(pad "AD12" smd circle
			(at -4.499991 7.50001 180)
			(size 0.508 0.508)
			(layers "F.Cu" "F.Mask" "F.Paste")
			(net "VDD_CORE")
		)
		(pad "AD13" smd circle
			(at -3.499993 7.50001 180)
			(size 0.508 0.508)
			(layers "F.Cu" "F.Mask" "F.Paste")
			(net "GND")
		)
		(pad "AD14" smd circle
			(at -2.499995 7.50001 180)
			(size 0.508 0.508)
			(layers "F.Cu" "F.Mask" "F.Paste")
			(net "VDD_CORE")
		)
		(pad "AD15" smd circle
			(at -1.499997 7.50001 180)
			(size 0.508 0.508)
			(layers "F.Cu" "F.Mask" "F.Paste")
			(net "GND")
		)
		(pad "AD16" smd circle
			(at -0.499999 7.50001 180)
			(size 0.508 0.508)
			(layers "F.Cu" "F.Mask" "F.Paste")
			(net "VDD_CORE")
		)
		(pad "AD17" smd circle
			(at 0.499999 7.50001 180)
			(size 0.508 0.508)
			(layers "F.Cu" "F.Mask" "F.Paste")
			(net "GND")
		)
		(pad "AD18" smd circle
			(at 1.499997 7.50001 180)
			(size 0.508 0.508)
			(layers "F.Cu" "F.Mask" "F.Paste")
			(net "VDD_CORE")
		)
		(pad "AD19" smd circle
			(at 2.499995 7.50001 180)
			(size 0.508 0.508)
			(layers "F.Cu" "F.Mask" "F.Paste")
			(net "GND")
		)
		(pad "AD20" smd circle
			(at 3.499993 7.50001 180)
			(size 0.508 0.508)
			(layers "F.Cu" "F.Mask" "F.Paste")
			(net "VDD_CORE")
		)
		(pad "AD21" smd circle
			(at 4.499991 7.50001 180)
			(size 0.508 0.508)
			(layers "F.Cu" "F.Mask" "F.Paste")
			(net "GND")
		)
		(pad "AD22" smd circle
			(at 5.499989 7.50001 180)
			(size 0.508 0.508)
			(layers "F.Cu" "F.Mask" "F.Paste")
			(net "VDD_CORE")
		)
		(pad "AD23" smd circle
			(at 6.500012 7.50001 180)
			(size 0.508 0.508)
			(layers "F.Cu" "F.Mask" "F.Paste")
			(net "GND")
		)
		(pad "AD24" smd circle
			(at 7.50001 7.50001 180)
			(size 0.508 0.508)
			(layers "F.Cu" "F.Mask" "F.Paste")
			(net "VDD_CORE")
		)
		(pad "AD25" smd circle
			(at 8.500008 7.50001 180)
			(size 0.508 0.508)
			(layers "F.Cu" "F.Mask" "F.Paste")
			(net "GND")
		)
		(pad "AD26" smd circle
			(at 9.500006 7.50001 180)
			(size 0.508 0.508)
			(layers "F.Cu" "F.Mask" "F.Paste")
			(net "VDD_CORE")
		)
		(pad "AD27" smd circle
			(at 10.500004 7.50001 180)
			(size 0.508 0.508)
			(layers "F.Cu" "F.Mask" "F.Paste")
			(net "VDD_3.3V")
		)
		(pad "AD28" smd circle
			(at 11.500002 7.50001 180)
			(size 0.508 0.508)
			(layers "F.Cu" "F.Mask" "F.Paste")
			(net "NFP_CPLD_PRGM_JTAG_TCK")
		)
		(pad "AD29" smd circle
			(at 12.5 7.50001 180)
			(size 0.508 0.508)
			(layers "F.Cu" "F.Mask" "F.Paste")
			(net "MUX_NFP_SMBUS_SCL")
		)
		(pad "AD30" smd circle
			(at 13.499998 7.50001 180)
			(size 0.508 0.508)
			(layers "F.Cu" "F.Mask" "F.Paste")
			(net "MUX_NFP_SMBUS_ALERT_L")
		)
		(pad "AD31" smd circle
			(at 14.499996 7.50001 180)
			(size 0.508 0.508)
			(layers "F.Cu" "F.Mask" "F.Paste")
			(net "GND")
		)
		(pad "AD32" smd circle
			(at 15.499994 7.50001 180)
			(size 0.508 0.508)
			(layers "F.Cu" "F.Mask" "F.Paste")
			(net "PGRM_JTAG_TDI")
		)
		(pad "AE1" smd circle
			(at -15.499994 8.500008 180)
			(size 0.508 0.508)
			(layers "F.Cu" "F.Mask" "F.Paste")
			(net "DDR0_32A_DQS0_N")
		)
		(pad "AE2" smd circle
			(at -14.499996 8.500008 180)
			(size 0.508 0.508)
			(layers "F.Cu" "F.Mask" "F.Paste")
			(net "DDR0_32A_DQ2")
		)
		(pad "AE3" smd circle
			(at -13.499998 8.500008 180)
			(size 0.508 0.508)
			(layers "F.Cu" "F.Mask" "F.Paste")
			(net "DDR0_32A_DQ1")
		)
		(pad "AE4" smd circle
			(at -12.5 8.500008 180)
			(size 0.508 0.508)
			(layers "F.Cu" "F.Mask" "F.Paste")
			(net "DDR0_32A_DQ5")
		)
		(pad "AE5" smd circle
			(at -11.500002 8.500008 180)
			(size 0.508 0.508)
			(layers "F.Cu" "F.Mask" "F.Paste")
			(net "DDR0_32A_DQ0")
		)
		(pad "AE6" smd circle
			(at -10.500004 8.500008 180)
			(size 0.508 0.508)
			(layers "F.Cu" "F.Mask" "F.Paste")
			(net "DDR0_32A_A9")
		)
		(pad "AE7" smd circle
			(at -9.500006 8.500008 180)
			(size 0.508 0.508)
			(layers "F.Cu" "F.Mask" "F.Paste")
			(net "DDR0_32A_A8")
		)
		(pad "AE8" smd circle
			(at -8.500008 8.500008 180)
			(size 0.508 0.508)
			(layers "F.Cu" "F.Mask" "F.Paste")
			(net "DDR0_32A_A13")
		)
		(pad "AE9" smd circle
			(at -7.50001 8.500008 180)
			(size 0.508 0.508)
			(layers "F.Cu" "F.Mask" "F.Paste")
			(net "DDR_VDDQ")
		)
		(pad "AE10" smd circle
			(at -6.500012 8.500008 180)
			(size 0.508 0.508)
			(layers "F.Cu" "F.Mask" "F.Paste")
			(net "GND")
		)
		(pad "AE11" smd circle
			(at -5.499989 8.500008 180)
			(size 0.508 0.508)
			(layers "F.Cu" "F.Mask" "F.Paste")
			(net "GND")
		)
		(pad "AE12" smd circle
			(at -4.499991 8.500008 180)
			(size 0.508 0.508)
			(layers "F.Cu" "F.Mask" "F.Paste")
			(net "GND")
		)
		(pad "AE13" smd circle
			(at -3.499993 8.500008 180)
			(size 0.508 0.508)
			(layers "F.Cu" "F.Mask" "F.Paste")
			(net "PCIE0_REFCLK_P")
		)
		(pad "AE14" smd circle
			(at -2.499995 8.500008 180)
			(size 0.508 0.508)
			(layers "F.Cu" "F.Mask" "F.Paste")
			(net "PCIE0_REFCLK_N")
		)
		(pad "AE15" smd circle
			(at -1.499997 8.500008 180)
			(size 0.508 0.508)
			(layers "F.Cu" "F.Mask" "F.Paste")
			(net "VDD_CORE")
		)
		(pad "AE16" smd circle
			(at -0.499999 8.500008 180)
			(size 0.508 0.508)
			(layers "F.Cu" "F.Mask" "F.Paste")
			(net "GND")
		)
		(pad "AE17" smd circle
			(at 0.499999 8.500008 180)
			(size 0.508 0.508)
			(layers "F.Cu" "F.Mask" "F.Paste")
			(net "VDD_CORE")
		)
		(pad "AE18" smd circle
			(at 1.499997 8.500008 180)
			(size 0.508 0.508)
			(layers "F.Cu" "F.Mask" "F.Paste")
			(net "GND")
		)
		(pad "AE19" smd circle
			(at 2.499995 8.500008 180)
			(size 0.508 0.508)
			(layers "F.Cu" "F.Mask" "F.Paste")
			(net "VDD_CORE")
		)
		(pad "AE20" smd circle
			(at 3.499993 8.500008 180)
			(size 0.508 0.508)
			(layers "F.Cu" "F.Mask" "F.Paste")
			(net "GND")
		)
		(pad "AE21" smd circle
			(at 4.499991 8.500008 180)
			(size 0.508 0.508)
			(layers "F.Cu" "F.Mask" "F.Paste")
			(net "VDD_CORE")
		)
		(pad "AE22" smd circle
			(at 5.499989 8.500008 180)
			(size 0.508 0.508)
			(layers "F.Cu" "F.Mask" "F.Paste")
			(net "VDDA_SERDES")
		)
		(pad "AE23" smd circle
			(at 6.500012 8.500008 180)
			(size 0.508 0.508)
			(layers "F.Cu" "F.Mask" "F.Paste")
			(net "VDDA_SERDES")
		)
		(pad "AE24" smd circle
			(at 7.50001 8.500008 180)
			(size 0.508 0.508)
			(layers "F.Cu" "F.Mask" "F.Paste")
			(net "VDDA_SERDES")
		)
		(pad "AE25" smd circle
			(at 8.500008 8.500008 180)
			(size 0.508 0.508)
			(layers "F.Cu" "F.Mask" "F.Paste")
			(net "NFP_SERDES012_SYSCLK_IN_P")
		)
		(pad "AE26" smd circle
			(at 9.500006 8.500008 180)
			(size 0.508 0.508)
			(layers "F.Cu" "F.Mask" "F.Paste")
			(net "NFP_SERDES012_SYSCLK_IN_N")
		)
		(pad "AE27" smd circle
			(at 10.500004 8.500008 180)
			(size 0.508 0.508)
			(layers "F.Cu" "F.Mask" "F.Paste")
			(net "GND")
		)
		(pad "AE28" smd circle
			(at 11.500002 8.500008 180)
			(size 0.508 0.508)
			(layers "F.Cu" "F.Mask" "F.Paste")
			(net "MUX_NFP_PCIE0_WAKE_L")
		)
		(pad "AE29" smd circle
			(at 12.5 8.500008 180)
			(size 0.508 0.508)
			(layers "F.Cu" "F.Mask" "F.Paste")
			(net "MUX_NFP_SMBUS_SDA")
		)
		(pad "AE30" smd circle
			(at 13.499998 8.500008 180)
			(size 0.508 0.508)
			(layers "F.Cu" "F.Mask" "F.Paste")
			(net "_NC_NFP_GPIO19")
		)
		(pad "AE31" smd circle
			(at 14.499996 8.500008 180)
			(size 0.508 0.508)
			(layers "F.Cu" "F.Mask" "F.Paste")
			(net "_NC_NFP_GPIO21")
		)
		(pad "AE32" smd circle
			(at 15.499994 8.500008 180)
			(size 0.508 0.508)
			(layers "F.Cu" "F.Mask" "F.Paste")
			(net "_NC_NFP_GPIO23")
		)
		(pad "AF1" smd circle
			(at -15.499994 9.500006 180)
			(size 0.508 0.508)
			(layers "F.Cu" "F.Mask" "F.Paste")
			(net "DDR0_32A_DQS0_P")
		)
		(pad "AF2" smd circle
			(at -14.499996 9.500006 180)
			(size 0.508 0.508)
			(layers "F.Cu" "F.Mask" "F.Paste")
			(net "DDR0_32A_DQ4")
		)
		(pad "AF3" smd circle
			(at -13.499998 9.500006 180)
			(size 0.508 0.508)
			(layers "F.Cu" "F.Mask" "F.Paste")
			(net "GND")
		)
		(pad "AF4" smd circle
			(at -12.5 9.500006 180)
			(size 0.508 0.508)
			(layers "F.Cu" "F.Mask" "F.Paste")
			(net "GND")
		)
		(pad "AF5" smd circle
			(at -11.500002 9.500006 180)
			(size 0.508 0.508)
			(layers "F.Cu" "F.Mask" "F.Paste")
			(net "_NC_NFP_PCIE1_APROBE1")
		)
		(pad "AF6" smd circle
			(at -10.500004 9.500006 180)
			(size 0.508 0.508)
			(layers "F.Cu" "F.Mask" "F.Paste")
			(net "GND")
		)
		(pad "AF7" smd circle
			(at -9.500006 9.500006 180)
			(size 0.508 0.508)
			(layers "F.Cu" "F.Mask" "F.Paste")
			(net "_NC_NFP_PCIE1_APROBE2")
		)
		(pad "AF8" smd circle
			(at -8.500008 9.500006 180)
			(size 0.508 0.508)
			(layers "F.Cu" "F.Mask" "F.Paste")
			(net "GND")
		)
		(pad "AF9" smd circle
			(at -7.50001 9.500006 180)
			(size 0.508 0.508)
			(layers "F.Cu" "F.Mask" "F.Paste")
			(net "GND")
		)
		(pad "AF10" smd circle
			(at -6.500012 9.500006 180)
			(size 0.508 0.508)
			(layers "F.Cu" "F.Mask" "F.Paste")
			(net "GND")
		)
		(pad "AF11" smd circle
			(at -5.499989 9.500006 180)
			(size 0.508 0.508)
			(layers "F.Cu" "F.Mask" "F.Paste")
			(net "GND")
		)
		(pad "AF12" smd circle
			(at -4.499991 9.500006 180)
			(size 0.508 0.508)
			(layers "F.Cu" "F.Mask" "F.Paste")
			(net "VDDA_PCIE0")
		)
		(pad "AF13" smd circle
			(at -3.499993 9.500006 180)
			(size 0.508 0.508)
			(layers "F.Cu" "F.Mask" "F.Paste")
			(net "VDDA_PCIE0")
		)
		(pad "AF14" smd circle
			(at -2.499995 9.500006 180)
			(size 0.508 0.508)
			(layers "F.Cu" "F.Mask" "F.Paste")
			(net "VDDA_PCIE0")
		)
		(pad "AF15" smd circle
			(at -1.499997 9.500006 180)
			(size 0.508 0.508)
			(layers "F.Cu" "F.Mask" "F.Paste")
			(net "_NC_NFP_PCIE0_APROBE1")
		)
		(pad "AF16" smd circle
			(at -0.499999 9.500006 180)
			(size 0.508 0.508)
			(layers "F.Cu" "F.Mask" "F.Paste")
			(net "VDDAH_PCIE0")
		)
		(pad "AF17" smd circle
			(at 0.499999 9.500006 180)
			(size 0.508 0.508)
			(layers "F.Cu" "F.Mask" "F.Paste")
			(net "_NC_NFP_PCIE0_APROBE2")
		)
		(pad "AF18" smd circle
			(at 1.499997 9.500006 180)
			(size 0.508 0.508)
			(layers "F.Cu" "F.Mask" "F.Paste")
			(net "GND")
		)
		(pad "AF19" smd circle
			(at 2.499995 9.500006 180)
			(size 0.508 0.508)
			(layers "F.Cu" "F.Mask" "F.Paste")
			(net "_NC_NFP_SERDES0_APROBE")
		)
		(pad "AF20" smd circle
			(at 3.499993 9.500006 180)
			(size 0.508 0.508)
			(layers "F.Cu" "F.Mask" "F.Paste")
			(net "VDDAH_SERDES")
		)
		(pad "AF21" smd circle
			(at 4.499991 9.500006 180)
			(size 0.508 0.508)
			(layers "F.Cu" "F.Mask" "F.Paste")
			(net "VDDAH_SERDES")
		)
		(pad "AF22" smd circle
			(at 5.499989 9.500006 180)
			(size 0.508 0.508)
			(layers "F.Cu" "F.Mask" "F.Paste")
			(net "VDDA_SERDES")
		)
		(pad "AF23" smd circle
			(at 6.500012 9.500006 180)
			(size 0.508 0.508)
			(layers "F.Cu" "F.Mask" "F.Paste")
			(net "VDDA_SERDES")
		)
		(pad "AF24" smd circle
			(at 7.50001 9.500006 180)
			(size 0.508 0.508)
			(layers "F.Cu" "F.Mask" "F.Paste")
			(net "GND")
		)
		(pad "AF25" smd circle
			(at 8.500008 9.500006 180)
			(size 0.508 0.508)
			(layers "F.Cu" "F.Mask" "F.Paste")
			(net "_NC_NFP_SERDES1_APROBE")
		)
		(pad "AF26" smd circle
			(at 9.500006 9.500006 180)
			(size 0.508 0.508)
			(layers "F.Cu" "F.Mask" "F.Paste")
			(net "GND")
		)
		(pad "AF27" smd circle
			(at 10.500004 9.500006 180)
			(size 0.508 0.508)
			(layers "F.Cu" "F.Mask" "F.Paste")
			(net "_NC_NFP_SERDES2_APROBE")
		)
		(pad "AF28" smd circle
			(at 11.500002 9.500006 180)
			(size 0.508 0.508)
			(layers "F.Cu" "F.Mask" "F.Paste")
			(net "VDD_1.2V")
		)
		(pad "AF29" smd circle
			(at 12.5 9.500006 180)
			(size 0.508 0.508)
			(layers "F.Cu" "F.Mask" "F.Paste")
			(net "VDD_1.2V")
		)
		(pad "AF30" smd circle
			(at 13.499998 9.500006 180)
			(size 0.508 0.508)
			(layers "F.Cu" "F.Mask" "F.Paste")
			(net "_NC_NFP_GPIO20")
		)
		(pad "AF31" smd circle
			(at 14.499996 9.500006 180)
			(size 0.508 0.508)
			(layers "F.Cu" "F.Mask" "F.Paste")
			(net "_NC_NFP_GPIO22")
		)
		(pad "AF32" smd circle
			(at 15.499994 9.500006 180)
			(size 0.508 0.508)
			(layers "F.Cu" "F.Mask" "F.Paste")
			(net "NFP_CORE_VID6")
		)
		(pad "AG1" smd circle
			(at -15.499994 10.500004 180)
			(size 0.508 0.508)
			(layers "F.Cu" "F.Mask" "F.Paste")
			(net "DDR0_32A_DQ7")
		)
		(pad "AG2" smd circle
			(at -14.499996 10.500004 180)
			(size 0.508 0.508)
			(layers "F.Cu" "F.Mask" "F.Paste")
			(net "DDR0_32A_DQ6")
		)
		(pad "AG3" smd circle
			(at -13.499998 10.500004 180)
			(size 0.508 0.508)
			(layers "F.Cu" "F.Mask" "F.Paste")
			(net "GND")
		)
		(pad "AG4" smd circle
			(at -12.5 10.500004 180)
			(size 0.508 0.508)
			(layers "F.Cu" "F.Mask" "F.Paste")
			(net "GND")
		)
		(pad "AG5" smd circle
			(at -11.500002 10.500004 180)
			(size 0.508 0.508)
			(layers "F.Cu" "F.Mask" "F.Paste")
			(net "GND")
		)
		(pad "AG6" smd circle
			(at -10.500004 10.500004 180)
			(size 0.508 0.508)
			(layers "F.Cu" "F.Mask" "F.Paste")
			(net "GND")
		)
		(pad "AG7" smd circle
			(at -9.500006 10.500004 180)
			(size 0.508 0.508)
			(layers "F.Cu" "F.Mask" "F.Paste")
			(net "GND")
		)
		(pad "AG8" smd circle
			(at -8.500008 10.500004 180)
			(size 0.508 0.508)
			(layers "F.Cu" "F.Mask" "F.Paste")
			(net "GND")
		)
		(pad "AG9" smd circle
			(at -7.50001 10.500004 180)
			(size 0.508 0.508)
			(layers "F.Cu" "F.Mask" "F.Paste")
			(net "GND")
		)
		(pad "AG10" smd circle
			(at -6.500012 10.500004 180)
			(size 0.508 0.508)
			(layers "F.Cu" "F.Mask" "F.Paste")
			(net "GND")
		)
		(pad "AG11" smd circle
			(at -5.499989 10.500004 180)
			(size 0.508 0.508)
			(layers "F.Cu" "F.Mask" "F.Paste")
			(net "GND")
		)
		(pad "AG12" smd circle
			(at -4.499991 10.500004 180)
			(size 0.508 0.508)
			(layers "F.Cu" "F.Mask" "F.Paste")
			(net "NFP_PCIE0_PET0_N")
		)
		(pad "AG13" smd circle
			(at -3.499993 10.500004 180)
			(size 0.508 0.508)
			(layers "F.Cu" "F.Mask" "F.Paste")
			(net "GND")
		)
		(pad "AG14" smd circle
			(at -2.499995 10.500004 180)
			(size 0.508 0.508)
			(layers "F.Cu" "F.Mask" "F.Paste")
			(net "NFP_PCIE0_PET2_N")
		)
		(pad "AG15" smd circle
			(at -1.499997 10.500004 180)
			(size 0.508 0.508)
			(layers "F.Cu" "F.Mask" "F.Paste")
			(net "GND")
		)
		(pad "AG16" smd circle
			(at -0.499999 10.500004 180)
			(size 0.508 0.508)
			(layers "F.Cu" "F.Mask" "F.Paste")
			(net "NFP_PCIE0_PET4_N")
		)
		(pad "AG17" smd circle
			(at 0.499999 10.500004 180)
			(size 0.508 0.508)
			(layers "F.Cu" "F.Mask" "F.Paste")
			(net "GND")
		)
		(pad "AG18" smd circle
			(at 1.499997 10.500004 180)
			(size 0.508 0.508)
			(layers "F.Cu" "F.Mask" "F.Paste")
			(net "NFP_PCIE0_PET6_N")
		)
		(pad "AG19" smd circle
			(at 2.499995 10.500004 180)
			(size 0.508 0.508)
			(layers "F.Cu" "F.Mask" "F.Paste")
			(net "GND")
		)
		(pad "AG20" smd circle
			(at 3.499993 10.500004 180)
			(size 0.508 0.508)
			(layers "F.Cu" "F.Mask" "F.Paste")
			(net "NFP_SERDES0_RX0_N")
		)
		(pad "AG21" smd circle
			(at 4.499991 10.500004 180)
			(size 0.508 0.508)
			(layers "F.Cu" "F.Mask" "F.Paste")
			(net "GND")
		)
		(pad "AG22" smd circle
			(at 5.499989 10.500004 180)
			(size 0.508 0.508)
			(layers "F.Cu" "F.Mask" "F.Paste")
			(net "GND")
		)
		(pad "AG23" smd circle
			(at 6.500012 10.500004 180)
			(size 0.508 0.508)
			(layers "F.Cu" "F.Mask" "F.Paste")
			(net "GND")
		)
		(pad "AG24" smd circle
			(at 7.50001 10.500004 180)
			(size 0.508 0.508)
			(layers "F.Cu" "F.Mask" "F.Paste")
			(net "NFP_SERDES1_RX0_N")
		)
		(pad "AG25" smd circle
			(at 8.500008 10.500004 180)
			(size 0.508 0.508)
			(layers "F.Cu" "F.Mask" "F.Paste")
			(net "GND")
		)
		(pad "AG26" smd circle
			(at 9.500006 10.500004 180)
			(size 0.508 0.508)
			(layers "F.Cu" "F.Mask" "F.Paste")
			(net "NFP_SERDES1_RX2_N")
		)
		(pad "AG27" smd circle
			(at 10.500004 10.500004 180)
			(size 0.508 0.508)
			(layers "F.Cu" "F.Mask" "F.Paste")
			(net "GND")
		)
		(pad "AG28" smd circle
			(at 11.500002 10.500004 180)
			(size 0.508 0.508)
			(layers "F.Cu" "F.Mask" "F.Paste")
			(net "GND")
		)
		(pad "AG29" smd circle
			(at 12.5 10.500004 180)
			(size 0.508 0.508)
			(layers "F.Cu" "F.Mask" "F.Paste")
			(net "GND")
		)
		(pad "AG30" smd circle
			(at 13.499998 10.500004 180)
			(size 0.508 0.508)
			(layers "F.Cu" "F.Mask" "F.Paste")
			(net "NFP_CORE_VID7")
		)
		(pad "AG31" smd circle
			(at 14.499996 10.500004 180)
			(size 0.508 0.508)
			(layers "F.Cu" "F.Mask" "F.Paste")
			(net "NFP_CORE_VID1")
		)
		(pad "AG32" smd circle
			(at 15.499994 10.500004 180)
			(size 0.508 0.508)
			(layers "F.Cu" "F.Mask" "F.Paste")
			(net "NFP_CORE_VID4")
		)
		(pad "AH1" smd circle
			(at -15.499994 11.500002 180)
			(size 0.508 0.508)
			(layers "F.Cu" "F.Mask" "F.Paste")
			(net "DDR0_32A_DM0")
		)
		(pad "AH2" smd circle
			(at -14.499996 11.500002 180)
			(size 0.508 0.508)
			(layers "F.Cu" "F.Mask" "F.Paste")
			(net "DDR_VDDQ")
		)
		(pad "AH3" smd circle
			(at -13.499998 11.500002 180)
			(size 0.508 0.508)
			(layers "F.Cu" "F.Mask" "F.Paste")
			(net "GND")
		)
		(pad "AH4" smd circle
			(at -12.5 11.500002 180)
			(size 0.508 0.508)
			(layers "F.Cu" "F.Mask" "F.Paste")
			(net "GND")
		)
		(pad "AH5" smd circle
			(at -11.500002 11.500002 180)
			(size 0.508 0.508)
			(layers "F.Cu" "F.Mask" "F.Paste")
			(net "GND")
		)
		(pad "AH6" smd circle
			(at -10.500004 11.500002 180)
			(size 0.508 0.508)
			(layers "F.Cu" "F.Mask" "F.Paste")
			(net "GND")
		)
		(pad "AH7" smd circle
			(at -9.500006 11.500002 180)
			(size 0.508 0.508)
			(layers "F.Cu" "F.Mask" "F.Paste")
			(net "GND")
		)
		(pad "AH8" smd circle
			(at -8.500008 11.500002 180)
			(size 0.508 0.508)
			(layers "F.Cu" "F.Mask" "F.Paste")
			(net "GND")
		)
		(pad "AH9" smd circle
			(at -7.50001 11.500002 180)
			(size 0.508 0.508)
			(layers "F.Cu" "F.Mask" "F.Paste")
			(net "GND")
		)
		(pad "AH10" smd circle
			(at -6.500012 11.500002 180)
			(size 0.508 0.508)
			(layers "F.Cu" "F.Mask" "F.Paste")
			(net "GND")
		)
		(pad "AH11" smd circle
			(at -5.499989 11.500002 180)
			(size 0.508 0.508)
			(layers "F.Cu" "F.Mask" "F.Paste")
			(net "GND")
		)
		(pad "AH12" smd circle
			(at -4.499991 11.500002 180)
			(size 0.508 0.508)
			(layers "F.Cu" "F.Mask" "F.Paste")
			(net "NFP_PCIE0_PET0_P")
		)
		(pad "AH13" smd circle
			(at -3.499993 11.500002 180)
			(size 0.508 0.508)
			(layers "F.Cu" "F.Mask" "F.Paste")
			(net "NFP_PCIE0_PET1_N")
		)
		(pad "AH14" smd circle
			(at -2.499995 11.500002 180)
			(size 0.508 0.508)
			(layers "F.Cu" "F.Mask" "F.Paste")
			(net "NFP_PCIE0_PET2_P")
		)
		(pad "AH15" smd circle
			(at -1.499997 11.500002 180)
			(size 0.508 0.508)
			(layers "F.Cu" "F.Mask" "F.Paste")
			(net "NFP_PCIE0_PET3_N")
		)
		(pad "AH16" smd circle
			(at -0.499999 11.500002 180)
			(size 0.508 0.508)
			(layers "F.Cu" "F.Mask" "F.Paste")
			(net "NFP_PCIE0_PET4_P")
		)
		(pad "AH17" smd circle
			(at 0.499999 11.500002 180)
			(size 0.508 0.508)
			(layers "F.Cu" "F.Mask" "F.Paste")
			(net "NFP_PCIE0_PET5_N")
		)
		(pad "AH18" smd circle
			(at 1.499997 11.500002 180)
			(size 0.508 0.508)
			(layers "F.Cu" "F.Mask" "F.Paste")
			(net "NFP_PCIE0_PET6_P")
		)
		(pad "AH19" smd circle
			(at 2.499995 11.500002 180)
			(size 0.508 0.508)
			(layers "F.Cu" "F.Mask" "F.Paste")
			(net "NFP_PCIE0_PET7_N")
		)
		(pad "AH20" smd circle
			(at 3.499993 11.500002 180)
			(size 0.508 0.508)
			(layers "F.Cu" "F.Mask" "F.Paste")
			(net "NFP_SERDES0_RX0_P")
		)
		(pad "AH21" smd circle
			(at 4.499991 11.500002 180)
			(size 0.508 0.508)
			(layers "F.Cu" "F.Mask" "F.Paste")
			(net "GND")
		)
		(pad "AH22" smd circle
			(at 5.499989 11.500002 180)
			(size 0.508 0.508)
			(layers "F.Cu" "F.Mask" "F.Paste")
			(net "GND")
		)
		(pad "AH23" smd circle
			(at 6.500012 11.500002 180)
			(size 0.508 0.508)
			(layers "F.Cu" "F.Mask" "F.Paste")
			(net "GND")
		)
		(pad "AH24" smd circle
			(at 7.50001 11.500002 180)
			(size 0.508 0.508)
			(layers "F.Cu" "F.Mask" "F.Paste")
			(net "NFP_SERDES1_RX0_P")
		)
		(pad "AH25" smd circle
			(at 8.500008 11.500002 180)
			(size 0.508 0.508)
			(layers "F.Cu" "F.Mask" "F.Paste")
			(net "NFP_SERDES1_RX1_N")
		)
		(pad "AH26" smd circle
			(at 9.500006 11.500002 180)
			(size 0.508 0.508)
			(layers "F.Cu" "F.Mask" "F.Paste")
			(net "NFP_SERDES1_RX2_P")
		)
		(pad "AH27" smd circle
			(at 10.500004 11.500002 180)
			(size 0.508 0.508)
			(layers "F.Cu" "F.Mask" "F.Paste")
			(net "NFP_SERDES1_RX3_N")
		)
		(pad "AH28" smd circle
			(at 11.500002 11.500002 180)
			(size 0.508 0.508)
			(layers "F.Cu" "F.Mask" "F.Paste")
			(net "GND")
		)
		(pad "AH29" smd circle
			(at 12.5 11.500002 180)
			(size 0.508 0.508)
			(layers "F.Cu" "F.Mask" "F.Paste")
			(net "GND")
		)
		(pad "AH30" smd circle
			(at 13.499998 11.500002 180)
			(size 0.508 0.508)
			(layers "F.Cu" "F.Mask" "F.Paste")
			(net "GND")
		)
		(pad "AH31" smd circle
			(at 14.499996 11.500002 180)
			(size 0.508 0.508)
			(layers "F.Cu" "F.Mask" "F.Paste")
			(net "NFP_CORE_VID5")
		)
		(pad "AH32" smd circle
			(at 15.499994 11.500002 180)
			(size 0.508 0.508)
			(layers "F.Cu" "F.Mask" "F.Paste")
			(net "NFP_CORE_VID2")
		)
		(pad "AJ1" smd circle
			(at -15.499994 12.5 180)
			(size 0.508 0.508)
			(layers "F.Cu" "F.Mask" "F.Paste")
			(net "GND")
		)
		(pad "AJ2" smd circle
			(at -14.499996 12.5 180)
			(size 0.508 0.508)
			(layers "F.Cu" "F.Mask" "F.Paste")
			(net "GND")
		)
		(pad "AJ3" smd circle
			(at -13.499998 12.5 180)
			(size 0.508 0.508)
			(layers "F.Cu" "F.Mask" "F.Paste")
			(net "GND")
		)
		(pad "AJ4" smd circle
			(at -12.5 12.5 180)
			(size 0.508 0.508)
			(layers "F.Cu" "F.Mask" "F.Paste")
			(net "GND")
		)
		(pad "AJ5" smd circle
			(at -11.500002 12.5 180)
			(size 0.508 0.508)
			(layers "F.Cu" "F.Mask" "F.Paste")
			(net "GND")
		)
		(pad "AJ6" smd circle
			(at -10.500004 12.5 180)
			(size 0.508 0.508)
			(layers "F.Cu" "F.Mask" "F.Paste")
			(net "GND")
		)
		(pad "AJ7" smd circle
			(at -9.500006 12.5 180)
			(size 0.508 0.508)
			(layers "F.Cu" "F.Mask" "F.Paste")
			(net "GND")
		)
		(pad "AJ8" smd circle
			(at -8.500008 12.5 180)
			(size 0.508 0.508)
			(layers "F.Cu" "F.Mask" "F.Paste")
			(net "GND")
		)
		(pad "AJ9" smd circle
			(at -7.50001 12.5 180)
			(size 0.508 0.508)
			(layers "F.Cu" "F.Mask" "F.Paste")
			(net "GND")
		)
		(pad "AJ10" smd circle
			(at -6.500012 12.5 180)
			(size 0.508 0.508)
			(layers "F.Cu" "F.Mask" "F.Paste")
			(net "GND")
		)
		(pad "AJ11" smd circle
			(at -5.499989 12.5 180)
			(size 0.508 0.508)
			(layers "F.Cu" "F.Mask" "F.Paste")
			(net "GND")
		)
		(pad "AJ12" smd circle
			(at -4.499991 12.5 180)
			(size 0.508 0.508)
			(layers "F.Cu" "F.Mask" "F.Paste")
			(net "GND")
		)
		(pad "AJ13" smd circle
			(at -3.499993 12.5 180)
			(size 0.508 0.508)
			(layers "F.Cu" "F.Mask" "F.Paste")
			(net "NFP_PCIE0_PET1_P")
		)
		(pad "AJ14" smd circle
			(at -2.499995 12.5 180)
			(size 0.508 0.508)
			(layers "F.Cu" "F.Mask" "F.Paste")
			(net "GND")
		)
		(pad "AJ15" smd circle
			(at -1.499997 12.5 180)
			(size 0.508 0.508)
			(layers "F.Cu" "F.Mask" "F.Paste")
			(net "NFP_PCIE0_PET3_P")
		)
		(pad "AJ16" smd circle
			(at -0.499999 12.5 180)
			(size 0.508 0.508)
			(layers "F.Cu" "F.Mask" "F.Paste")
			(net "GND")
		)
		(pad "AJ17" smd circle
			(at 0.499999 12.5 180)
			(size 0.508 0.508)
			(layers "F.Cu" "F.Mask" "F.Paste")
			(net "NFP_PCIE0_PET5_P")
		)
		(pad "AJ18" smd circle
			(at 1.499997 12.5 180)
			(size 0.508 0.508)
			(layers "F.Cu" "F.Mask" "F.Paste")
			(net "GND")
		)
		(pad "AJ19" smd circle
			(at 2.499995 12.5 180)
			(size 0.508 0.508)
			(layers "F.Cu" "F.Mask" "F.Paste")
			(net "NFP_PCIE0_PET7_P")
		)
		(pad "AJ20" smd circle
			(at 3.499993 12.5 180)
			(size 0.508 0.508)
			(layers "F.Cu" "F.Mask" "F.Paste")
			(net "GND")
		)
		(pad "AJ21" smd circle
			(at 4.499991 12.5 180)
			(size 0.508 0.508)
			(layers "F.Cu" "F.Mask" "F.Paste")
			(net "GND")
		)
		(pad "AJ22" smd circle
			(at 5.499989 12.5 180)
			(size 0.508 0.508)
			(layers "F.Cu" "F.Mask" "F.Paste")
			(net "GND")
		)
		(pad "AJ23" smd circle
			(at 6.500012 12.5 180)
			(size 0.508 0.508)
			(layers "F.Cu" "F.Mask" "F.Paste")
			(net "GND")
		)
		(pad "AJ24" smd circle
			(at 7.50001 12.5 180)
			(size 0.508 0.508)
			(layers "F.Cu" "F.Mask" "F.Paste")
			(net "GND")
		)
		(pad "AJ25" smd circle
			(at 8.500008 12.5 180)
			(size 0.508 0.508)
			(layers "F.Cu" "F.Mask" "F.Paste")
			(net "NFP_SERDES1_RX1_P")
		)
		(pad "AJ26" smd circle
			(at 9.500006 12.5 180)
			(size 0.508 0.508)
			(layers "F.Cu" "F.Mask" "F.Paste")
			(net "GND")
		)
		(pad "AJ27" smd circle
			(at 10.500004 12.5 180)
			(size 0.508 0.508)
			(layers "F.Cu" "F.Mask" "F.Paste")
			(net "NFP_SERDES1_RX3_P")
		)
		(pad "AJ28" smd circle
			(at 11.500002 12.5 180)
			(size 0.508 0.508)
			(layers "F.Cu" "F.Mask" "F.Paste")
			(net "GND")
		)
		(pad "AJ29" smd circle
			(at 12.5 12.5 180)
			(size 0.508 0.508)
			(layers "F.Cu" "F.Mask" "F.Paste")
			(net "GND")
		)
		(pad "AJ30" smd circle
			(at 13.499998 12.5 180)
			(size 0.508 0.508)
			(layers "F.Cu" "F.Mask" "F.Paste")
			(net "GND")
		)
		(pad "AJ31" smd circle
			(at 14.499996 12.5 180)
			(size 0.508 0.508)
			(layers "F.Cu" "F.Mask" "F.Paste")
			(net "NFP_CORE_VID0")
		)
		(pad "AJ32" smd circle
			(at 15.499994 12.5 180)
			(size 0.508 0.508)
			(layers "F.Cu" "F.Mask" "F.Paste")
			(net "NFP_CORE_VID3")
		)
		(pad "AK1" smd circle
			(at -15.499994 13.499998 180)
			(size 0.6604 0.6604)
			(layers "F.Cu" "F.Mask" "F.Paste")
			(net "GND")
		)
		(pad "AK2" smd circle
			(at -14.499996 13.499998 180)
			(size 0.508 0.508)
			(layers "F.Cu" "F.Mask" "F.Paste")
			(net "GND")
		)
		(pad "AK3" smd circle
			(at -13.499998 13.499998 180)
			(size 0.508 0.508)
			(layers "F.Cu" "F.Mask" "F.Paste")
			(net "GND")
		)
		(pad "AK4" smd circle
			(at -12.5 13.499998 180)
			(size 0.508 0.508)
			(layers "F.Cu" "F.Mask" "F.Paste")
			(net "_NC_NFP_PCIE1_PET0_N")
		)
		(pad "AK5" smd circle
			(at -11.500002 13.499998 180)
			(size 0.508 0.508)
			(layers "F.Cu" "F.Mask" "F.Paste")
			(net "GND")
		)
		(pad "AK6" smd circle
			(at -10.500004 13.499998 180)
			(size 0.508 0.508)
			(layers "F.Cu" "F.Mask" "F.Paste")
			(net "_NC_NFP_PCIE1_PET2_N")
		)
		(pad "AK7" smd circle
			(at -9.500006 13.499998 180)
			(size 0.508 0.508)
			(layers "F.Cu" "F.Mask" "F.Paste")
			(net "GND")
		)
		(pad "AK8" smd circle
			(at -8.500008 13.499998 180)
			(size 0.508 0.508)
			(layers "F.Cu" "F.Mask" "F.Paste")
			(net "_NC_NFP_PCIE1_PET4_N")
		)
		(pad "AK9" smd circle
			(at -7.50001 13.499998 180)
			(size 0.508 0.508)
			(layers "F.Cu" "F.Mask" "F.Paste")
			(net "GND")
		)
		(pad "AK10" smd circle
			(at -6.500012 13.499998 180)
			(size 0.508 0.508)
			(layers "F.Cu" "F.Mask" "F.Paste")
			(net "_NC_NFP_PCIE1_PET6_N")
		)
		(pad "AK11" smd circle
			(at -5.499989 13.499998 180)
			(size 0.508 0.508)
			(layers "F.Cu" "F.Mask" "F.Paste")
			(net "GND")
		)
		(pad "AK12" smd circle
			(at -4.499991 13.499998 180)
			(size 0.508 0.508)
			(layers "F.Cu" "F.Mask" "F.Paste")
			(net "_NFP_PCIE0_PER0_N")
		)
		(pad "AK13" smd circle
			(at -3.499993 13.499998 180)
			(size 0.508 0.508)
			(layers "F.Cu" "F.Mask" "F.Paste")
			(net "GND")
		)
		(pad "AK14" smd circle
			(at -2.499995 13.499998 180)
			(size 0.508 0.508)
			(layers "F.Cu" "F.Mask" "F.Paste")
			(net "_NFP_PCIE0_PER2_N")
		)
		(pad "AK15" smd circle
			(at -1.499997 13.499998 180)
			(size 0.508 0.508)
			(layers "F.Cu" "F.Mask" "F.Paste")
			(net "GND")
		)
		(pad "AK16" smd circle
			(at -0.499999 13.499998 180)
			(size 0.508 0.508)
			(layers "F.Cu" "F.Mask" "F.Paste")
			(net "_NFP_PCIE0_PER4_N")
		)
		(pad "AK17" smd circle
			(at 0.499999 13.499998 180)
			(size 0.508 0.508)
			(layers "F.Cu" "F.Mask" "F.Paste")
			(net "GND")
		)
		(pad "AK18" smd circle
			(at 1.499997 13.499998 180)
			(size 0.508 0.508)
			(layers "F.Cu" "F.Mask" "F.Paste")
			(net "_NFP_PCIE0_PER6_N")
		)
		(pad "AK19" smd circle
			(at 2.499995 13.499998 180)
			(size 0.508 0.508)
			(layers "F.Cu" "F.Mask" "F.Paste")
			(net "GND")
		)
		(pad "AK20" smd circle
			(at 3.499993 13.499998 180)
			(size 0.508 0.508)
			(layers "F.Cu" "F.Mask" "F.Paste")
			(net "NFP_SERDES0_TX0_N")
		)
		(pad "AK21" smd circle
			(at 4.499991 13.499998 180)
			(size 0.508 0.508)
			(layers "F.Cu" "F.Mask" "F.Paste")
			(net "GND")
		)
		(pad "AK22" smd circle
			(at 5.499989 13.499998 180)
			(size 0.508 0.508)
			(layers "F.Cu" "F.Mask" "F.Paste")
			(net "_NC_NFP_SERDES0_TX2_N")
		)
		(pad "AK23" smd circle
			(at 6.500012 13.499998 180)
			(size 0.508 0.508)
			(layers "F.Cu" "F.Mask" "F.Paste")
			(net "GND")
		)
		(pad "AK24" smd circle
			(at 7.50001 13.499998 180)
			(size 0.508 0.508)
			(layers "F.Cu" "F.Mask" "F.Paste")
			(net "NFP_SERDES1_TX0_N")
		)
		(pad "AK25" smd circle
			(at 8.500008 13.499998 180)
			(size 0.508 0.508)
			(layers "F.Cu" "F.Mask" "F.Paste")
			(net "GND")
		)
		(pad "AK26" smd circle
			(at 9.500006 13.499998 180)
			(size 0.508 0.508)
			(layers "F.Cu" "F.Mask" "F.Paste")
			(net "NFP_SERDES1_TX2_N")
		)
		(pad "AK27" smd circle
			(at 10.500004 13.499998 180)
			(size 0.508 0.508)
			(layers "F.Cu" "F.Mask" "F.Paste")
			(net "GND")
		)
		(pad "AK28" smd circle
			(at 11.500002 13.499998 180)
			(size 0.508 0.508)
			(layers "F.Cu" "F.Mask" "F.Paste")
			(net "_NC_NFP_SERDES2_TX0_N")
		)
		(pad "AK29" smd circle
			(at 12.5 13.499998 180)
			(size 0.508 0.508)
			(layers "F.Cu" "F.Mask" "F.Paste")
			(net "GND")
		)
		(pad "AK30" smd circle
			(at 13.499998 13.499998 180)
			(size 0.508 0.508)
			(layers "F.Cu" "F.Mask" "F.Paste")
			(net "GND")
		)
		(pad "AK31" smd circle
			(at 14.499996 13.499998 180)
			(size 0.508 0.508)
			(layers "F.Cu" "F.Mask" "F.Paste")
			(net "_NC_NFP_TEST_EDM")
		)
		(pad "AK32" smd circle
			(at 15.499994 13.499998 180)
			(size 0.6604 0.6604)
			(layers "F.Cu" "F.Mask" "F.Paste")
			(net "GND")
		)
		(pad "AL1" smd circle
			(at -15.499994 14.499996 180)
			(size 0.6604 0.6604)
			(layers "F.Cu" "F.Mask" "F.Paste")
			(net "GND")
		)
		(pad "AL2" smd circle
			(at -14.499996 14.499996 180)
			(size 0.6604 0.6604)
			(layers "F.Cu" "F.Mask" "F.Paste")
			(net "GND")
		)
		(pad "AL3" smd circle
			(at -13.499998 14.499996 180)
			(size 0.508 0.508)
			(layers "F.Cu" "F.Mask" "F.Paste")
			(net "GND")
		)
		(pad "AL4" smd circle
			(at -12.5 14.499996 180)
			(size 0.508 0.508)
			(layers "F.Cu" "F.Mask" "F.Paste")
			(net "_NC_NFP_PCIE1_PET0_P")
		)
		(pad "AL5" smd circle
			(at -11.500002 14.499996 180)
			(size 0.508 0.508)
			(layers "F.Cu" "F.Mask" "F.Paste")
			(net "_NC_NFP_PCIE1_PET1_N")
		)
		(pad "AL6" smd circle
			(at -10.500004 14.499996 180)
			(size 0.508 0.508)
			(layers "F.Cu" "F.Mask" "F.Paste")
			(net "_NC_NFP_PCIE1_PET2_P")
		)
		(pad "AL7" smd circle
			(at -9.500006 14.499996 180)
			(size 0.508 0.508)
			(layers "F.Cu" "F.Mask" "F.Paste")
			(net "_NC_NFP_PCIE1_PET3_N")
		)
		(pad "AL8" smd circle
			(at -8.500008 14.499996 180)
			(size 0.508 0.508)
			(layers "F.Cu" "F.Mask" "F.Paste")
			(net "_NC_NFP_PCIE1_PET4_P")
		)
		(pad "AL9" smd circle
			(at -7.50001 14.499996 180)
			(size 0.508 0.508)
			(layers "F.Cu" "F.Mask" "F.Paste")
			(net "_NC_NFP_PCIE1_PET5_N")
		)
		(pad "AL10" smd circle
			(at -6.500012 14.499996 180)
			(size 0.508 0.508)
			(layers "F.Cu" "F.Mask" "F.Paste")
			(net "_NC_NFP_PCIE1_PET6_P")
		)
		(pad "AL11" smd circle
			(at -5.499989 14.499996 180)
			(size 0.508 0.508)
			(layers "F.Cu" "F.Mask" "F.Paste")
			(net "_NC_NFP_PCIE1_PET7_N")
		)
		(pad "AL12" smd circle
			(at -4.499991 14.499996 180)
			(size 0.508 0.508)
			(layers "F.Cu" "F.Mask" "F.Paste")
			(net "_NFP_PCIE0_PER0_P")
		)
		(pad "AL13" smd circle
			(at -3.499993 14.499996 180)
			(size 0.508 0.508)
			(layers "F.Cu" "F.Mask" "F.Paste")
			(net "_NFP_PCIE0_PER1_N")
		)
		(pad "AL14" smd circle
			(at -2.499995 14.499996 180)
			(size 0.508 0.508)
			(layers "F.Cu" "F.Mask" "F.Paste")
			(net "_NFP_PCIE0_PER2_P")
		)
		(pad "AL15" smd circle
			(at -1.499997 14.499996 180)
			(size 0.508 0.508)
			(layers "F.Cu" "F.Mask" "F.Paste")
			(net "_NFP_PCIE0_PER3_N")
		)
		(pad "AL16" smd circle
			(at -0.499999 14.499996 180)
			(size 0.508 0.508)
			(layers "F.Cu" "F.Mask" "F.Paste")
			(net "_NFP_PCIE0_PER4_P")
		)
		(pad "AL17" smd circle
			(at 0.499999 14.499996 180)
			(size 0.508 0.508)
			(layers "F.Cu" "F.Mask" "F.Paste")
			(net "_NFP_PCIE0_PER5_N")
		)
		(pad "AL18" smd circle
			(at 1.499997 14.499996 180)
			(size 0.508 0.508)
			(layers "F.Cu" "F.Mask" "F.Paste")
			(net "_NFP_PCIE0_PER6_P")
		)
		(pad "AL19" smd circle
			(at 2.499995 14.499996 180)
			(size 0.508 0.508)
			(layers "F.Cu" "F.Mask" "F.Paste")
			(net "_NFP_PCIE0_PER7_N")
		)
		(pad "AL20" smd circle
			(at 3.499993 14.499996 180)
			(size 0.508 0.508)
			(layers "F.Cu" "F.Mask" "F.Paste")
			(net "NFP_SERDES0_TX0_P")
		)
		(pad "AL21" smd circle
			(at 4.499991 14.499996 180)
			(size 0.508 0.508)
			(layers "F.Cu" "F.Mask" "F.Paste")
			(net "_NC_NFP_SERDES0_TX1_N")
		)
		(pad "AL22" smd circle
			(at 5.499989 14.499996 180)
			(size 0.508 0.508)
			(layers "F.Cu" "F.Mask" "F.Paste")
			(net "_NC_NFP_SERDES0_TX2_P")
		)
		(pad "AL23" smd circle
			(at 6.500012 14.499996 180)
			(size 0.508 0.508)
			(layers "F.Cu" "F.Mask" "F.Paste")
			(net "_NC_NFP_SERDES0_TX3_N")
		)
		(pad "AL24" smd circle
			(at 7.50001 14.499996 180)
			(size 0.508 0.508)
			(layers "F.Cu" "F.Mask" "F.Paste")
			(net "NFP_SERDES1_TX0_P")
		)
		(pad "AL25" smd circle
			(at 8.500008 14.499996 180)
			(size 0.508 0.508)
			(layers "F.Cu" "F.Mask" "F.Paste")
			(net "NFP_SERDES1_TX1_N")
		)
		(pad "AL26" smd circle
			(at 9.500006 14.499996 180)
			(size 0.508 0.508)
			(layers "F.Cu" "F.Mask" "F.Paste")
			(net "NFP_SERDES1_TX2_P")
		)
		(pad "AL27" smd circle
			(at 10.500004 14.499996 180)
			(size 0.508 0.508)
			(layers "F.Cu" "F.Mask" "F.Paste")
			(net "NFP_SERDES1_TX3_N")
		)
		(pad "AL28" smd circle
			(at 11.500002 14.499996 180)
			(size 0.508 0.508)
			(layers "F.Cu" "F.Mask" "F.Paste")
			(net "_NC_NFP_SERDES2_TX0_P")
		)
		(pad "AL29" smd circle
			(at 12.5 14.499996 180)
			(size 0.508 0.508)
			(layers "F.Cu" "F.Mask" "F.Paste")
			(net "_NC_NFP_SERDES2_TX1_N")
		)
		(pad "AL30" smd circle
			(at 13.499998 14.499996 180)
			(size 0.508 0.508)
			(layers "F.Cu" "F.Mask" "F.Paste")
			(net "GND")
		)
		(pad "AL31" smd circle
			(at 14.499996 14.499996 180)
			(size 0.6604 0.6604)
			(layers "F.Cu" "F.Mask" "F.Paste")
			(net "GND")
		)
		(pad "AL32" smd circle
			(at 15.499994 14.499996 180)
			(size 0.6604 0.6604)
			(layers "F.Cu" "F.Mask" "F.Paste")
			(net "GND")
		)
		(pad "AM2" smd circle
			(at -14.499996 15.499994 180)
			(size 0.6604 0.6604)
			(layers "F.Cu" "F.Mask" "F.Paste")
			(net "GND")
		)
		(pad "AM3" smd circle
			(at -13.499998 15.499994 180)
			(size 0.6604 0.6604)
			(layers "F.Cu" "F.Mask" "F.Paste")
			(net "GND")
		)
		(pad "AM4" smd circle
			(at -12.5 15.499994 180)
			(size 0.508 0.508)
			(layers "F.Cu" "F.Mask" "F.Paste")
			(net "GND")
		)
		(pad "AM5" smd circle
			(at -11.500002 15.499994 180)
			(size 0.508 0.508)
			(layers "F.Cu" "F.Mask" "F.Paste")
			(net "_NC_NFP_PCIE1_PET1_P")
		)
		(pad "AM6" smd circle
			(at -10.500004 15.499994 180)
			(size 0.508 0.508)
			(layers "F.Cu" "F.Mask" "F.Paste")
			(net "GND")
		)
		(pad "AM7" smd circle
			(at -9.500006 15.499994 180)
			(size 0.508 0.508)
			(layers "F.Cu" "F.Mask" "F.Paste")
			(net "_NC_NFP_PCIE1_PET3_P")
		)
		(pad "AM8" smd circle
			(at -8.500008 15.499994 180)
			(size 0.508 0.508)
			(layers "F.Cu" "F.Mask" "F.Paste")
			(net "GND")
		)
		(pad "AM9" smd circle
			(at -7.50001 15.499994 180)
			(size 0.508 0.508)
			(layers "F.Cu" "F.Mask" "F.Paste")
			(net "_NC_NFP_PCIE1_PET5_P")
		)
		(pad "AM10" smd circle
			(at -6.500012 15.499994 180)
			(size 0.508 0.508)
			(layers "F.Cu" "F.Mask" "F.Paste")
			(net "GND")
		)
		(pad "AM11" smd circle
			(at -5.499989 15.499994 180)
			(size 0.508 0.508)
			(layers "F.Cu" "F.Mask" "F.Paste")
			(net "_NC_NFP_PCIE1_PET7_P")
		)
		(pad "AM12" smd circle
			(at -4.499991 15.499994 180)
			(size 0.508 0.508)
			(layers "F.Cu" "F.Mask" "F.Paste")
			(net "GND")
		)
		(pad "AM13" smd circle
			(at -3.499993 15.499994 180)
			(size 0.508 0.508)
			(layers "F.Cu" "F.Mask" "F.Paste")
			(net "_NFP_PCIE0_PER1_P")
		)
		(pad "AM14" smd circle
			(at -2.499995 15.499994 180)
			(size 0.508 0.508)
			(layers "F.Cu" "F.Mask" "F.Paste")
			(net "GND")
		)
		(pad "AM15" smd circle
			(at -1.499997 15.499994 180)
			(size 0.508 0.508)
			(layers "F.Cu" "F.Mask" "F.Paste")
			(net "_NFP_PCIE0_PER3_P")
		)
		(pad "AM16" smd circle
			(at -0.499999 15.499994 180)
			(size 0.508 0.508)
			(layers "F.Cu" "F.Mask" "F.Paste")
			(net "GND")
		)
		(pad "AM17" smd circle
			(at 0.499999 15.499994 180)
			(size 0.508 0.508)
			(layers "F.Cu" "F.Mask" "F.Paste")
			(net "_NFP_PCIE0_PER5_P")
		)
		(pad "AM18" smd circle
			(at 1.499997 15.499994 180)
			(size 0.508 0.508)
			(layers "F.Cu" "F.Mask" "F.Paste")
			(net "GND")
		)
		(pad "AM19" smd circle
			(at 2.499995 15.499994 180)
			(size 0.508 0.508)
			(layers "F.Cu" "F.Mask" "F.Paste")
			(net "_NFP_PCIE0_PER7_P")
		)
		(pad "AM20" smd circle
			(at 3.499993 15.499994 180)
			(size 0.508 0.508)
			(layers "F.Cu" "F.Mask" "F.Paste")
			(net "GND")
		)
		(pad "AM21" smd circle
			(at 4.499991 15.499994 180)
			(size 0.508 0.508)
			(layers "F.Cu" "F.Mask" "F.Paste")
			(net "_NC_NFP_SERDES0_TX1_P")
		)
		(pad "AM22" smd circle
			(at 5.499989 15.499994 180)
			(size 0.508 0.508)
			(layers "F.Cu" "F.Mask" "F.Paste")
			(net "GND")
		)
		(pad "AM23" smd circle
			(at 6.500012 15.499994 180)
			(size 0.508 0.508)
			(layers "F.Cu" "F.Mask" "F.Paste")
			(net "_NC_NFP_SERDES0_TX3_P")
		)
		(pad "AM24" smd circle
			(at 7.50001 15.499994 180)
			(size 0.508 0.508)
			(layers "F.Cu" "F.Mask" "F.Paste")
			(net "GND")
		)
		(pad "AM25" smd circle
			(at 8.500008 15.499994 180)
			(size 0.508 0.508)
			(layers "F.Cu" "F.Mask" "F.Paste")
			(net "NFP_SERDES1_TX1_P")
		)
		(pad "AM26" smd circle
			(at 9.500006 15.499994 180)
			(size 0.508 0.508)
			(layers "F.Cu" "F.Mask" "F.Paste")
			(net "GND")
		)
		(pad "AM27" smd circle
			(at 10.500004 15.499994 180)
			(size 0.508 0.508)
			(layers "F.Cu" "F.Mask" "F.Paste")
			(net "NFP_SERDES1_TX3_P")
		)
		(pad "AM28" smd circle
			(at 11.500002 15.499994 180)
			(size 0.508 0.508)
			(layers "F.Cu" "F.Mask" "F.Paste")
			(net "GND")
		)
		(pad "AM29" smd circle
			(at 12.5 15.499994 180)
			(size 0.508 0.508)
			(layers "F.Cu" "F.Mask" "F.Paste")
			(net "_NC_NFP_SERDES2_TX1_P")
		)
		(pad "AM30" smd circle
			(at 13.499998 15.499994 180)
			(size 0.6604 0.6604)
			(layers "F.Cu" "F.Mask" "F.Paste")
			(net "GND")
		)
		(pad "AM31" smd circle
			(at 14.499996 15.499994 180)
			(size 0.6604 0.6604)
			(layers "F.Cu" "F.Mask" "F.Paste")
			(net "GND")
		)
		(pad "B1" smd circle
			(at -15.499994 -14.499996 180)
			(size 0.6604 0.6604)
			(layers "F.Cu" "F.Mask" "F.Paste")
			(net "GND")
		)
		(pad "B2" smd circle
			(at -14.499996 -14.499996 180)
			(size 0.6604 0.6604)
			(layers "F.Cu" "F.Mask" "F.Paste")
			(net "DDR_VDDQ")
		)
		(pad "B3" smd circle
			(at -13.499998 -14.499996 180)
			(size 0.508 0.508)
			(layers "F.Cu" "F.Mask" "F.Paste")
			(net "GND")
		)
		(pad "B4" smd circle
			(at -12.5 -14.499996 180)
			(size 0.508 0.508)
			(layers "F.Cu" "F.Mask" "F.Paste")
			(net "DDR_VDDQ")
		)
		(pad "B5" smd circle
			(at -11.500002 -14.499996 180)
			(size 0.508 0.508)
			(layers "F.Cu" "F.Mask" "F.Paste")
			(net "GND")
		)
		(pad "B6" smd circle
			(at -10.500004 -14.499996 180)
			(size 0.508 0.508)
			(layers "F.Cu" "F.Mask" "F.Paste")
			(net "DDR_VDDQ")
		)
		(pad "B7" smd circle
			(at -9.500006 -14.499996 180)
			(size 0.508 0.508)
			(layers "F.Cu" "F.Mask" "F.Paste")
			(net "GND")
		)
		(pad "B8" smd circle
			(at -8.500008 -14.499996 180)
			(size 0.508 0.508)
			(layers "F.Cu" "F.Mask" "F.Paste")
			(net "DDR_VDDQ")
		)
		(pad "B9" smd circle
			(at -7.50001 -14.499996 180)
			(size 0.508 0.508)
			(layers "F.Cu" "F.Mask" "F.Paste")
			(net "GND")
		)
		(pad "B10" smd circle
			(at -6.500012 -14.499996 180)
			(size 0.508 0.508)
			(layers "F.Cu" "F.Mask" "F.Paste")
			(net "GND")
		)
		(pad "B11" smd circle
			(at -5.499989 -14.499996 180)
			(size 0.508 0.508)
			(layers "F.Cu" "F.Mask" "F.Paste")
			(net "GND")
		)
		(pad "B12" smd circle
			(at -4.499991 -14.499996 180)
			(size 0.508 0.508)
			(layers "F.Cu" "F.Mask" "F.Paste")
			(net "VDD_CORE")
		)
		(pad "B13" smd circle
			(at -3.499993 -14.499996 180)
			(size 0.508 0.508)
			(layers "F.Cu" "F.Mask" "F.Paste")
			(net "GND")
		)
		(pad "B14" smd circle
			(at -2.499995 -14.499996 180)
			(size 0.508 0.508)
			(layers "F.Cu" "F.Mask" "F.Paste")
			(net "VDD_CORE")
		)
		(pad "B15" smd circle
			(at -1.499997 -14.499996 180)
			(size 0.508 0.508)
			(layers "F.Cu" "F.Mask" "F.Paste")
			(net "GND")
		)
		(pad "B16" smd circle
			(at -0.499999 -14.499996 180)
			(size 0.508 0.508)
			(layers "F.Cu" "F.Mask" "F.Paste")
			(net "VDD_CORE")
		)
		(pad "B17" smd circle
			(at 0.499999 -14.499996 180)
			(size 0.508 0.508)
			(layers "F.Cu" "F.Mask" "F.Paste")
			(net "GND")
		)
		(pad "B18" smd circle
			(at 1.499997 -14.499996 180)
			(size 0.508 0.508)
			(layers "F.Cu" "F.Mask" "F.Paste")
			(net "VDD_CORE")
		)
		(pad "B19" smd circle
			(at 2.499995 -14.499996 180)
			(size 0.508 0.508)
			(layers "F.Cu" "F.Mask" "F.Paste")
			(net "GND")
		)
		(pad "B20" smd circle
			(at 3.499993 -14.499996 180)
			(size 0.508 0.508)
			(layers "F.Cu" "F.Mask" "F.Paste")
			(net "VDD_CORE")
		)
		(pad "B21" smd circle
			(at 4.499991 -14.499996 180)
			(size 0.508 0.508)
			(layers "F.Cu" "F.Mask" "F.Paste")
			(net "GND")
		)
		(pad "B22" smd circle
			(at 5.499989 -14.499996 180)
			(size 0.508 0.508)
			(layers "F.Cu" "F.Mask" "F.Paste")
			(net "VDD_CORE")
		)
		(pad "B23" smd circle
			(at 6.500012 -14.499996 180)
			(size 0.508 0.508)
			(layers "F.Cu" "F.Mask" "F.Paste")
			(net "GND")
		)
		(pad "B24" smd circle
			(at 7.50001 -14.499996 180)
			(size 0.508 0.508)
			(layers "F.Cu" "F.Mask" "F.Paste")
			(net "VDD_CORE")
		)
		(pad "B25" smd circle
			(at 8.500008 -14.499996 180)
			(size 0.508 0.508)
			(layers "F.Cu" "F.Mask" "F.Paste")
			(net "GND")
		)
		(pad "B26" smd circle
			(at 9.500006 -14.499996 180)
			(size 0.508 0.508)
			(layers "F.Cu" "F.Mask" "F.Paste")
			(net "VDD_CORE")
		)
		(pad "B27" smd circle
			(at 10.500004 -14.499996 180)
			(size 0.508 0.508)
			(layers "F.Cu" "F.Mask" "F.Paste")
			(net "_NC_TEST_SCAN_0_OUT35")
		)
		(pad "B28" smd circle
			(at 11.500002 -14.499996 180)
			(size 0.508 0.508)
			(layers "F.Cu" "F.Mask" "F.Paste")
			(net "_NC_TEST_SCAN_0_OUT34")
		)
		(pad "B29" smd circle
			(at 12.5 -14.499996 180)
			(size 0.508 0.508)
			(layers "F.Cu" "F.Mask" "F.Paste")
			(net "_NC_TEST_SCAN_0_OUT28")
		)
		(pad "B30" smd circle
			(at 13.499998 -14.499996 180)
			(size 0.508 0.508)
			(layers "F.Cu" "F.Mask" "F.Paste")
			(net "_NC_VDDQ_TEST_SCAN_0_OUT")
		)
		(pad "B31" smd circle
			(at 14.499996 -14.499996 180)
			(size 0.6604 0.6604)
			(layers "F.Cu" "F.Mask" "F.Paste")
			(net "GND")
		)
		(pad "B32" smd circle
			(at 15.499994 -14.499996 180)
			(size 0.6604 0.6604)
			(layers "F.Cu" "F.Mask" "F.Paste")
			(net "GND")
		)
		(pad "C1" smd circle
			(at -15.499994 -13.499998 180)
			(size 0.6604 0.6604)
			(layers "F.Cu" "F.Mask" "F.Paste")
			(net "GND")
		)
		(pad "C2" smd circle
			(at -14.499996 -13.499998 180)
			(size 0.508 0.508)
			(layers "F.Cu" "F.Mask" "F.Paste")
			(net "_NC_DDR0_32B_DQS4_P")
		)
		(pad "C3" smd circle
			(at -13.499998 -13.499998 180)
			(size 0.508 0.508)
			(layers "F.Cu" "F.Mask" "F.Paste")
			(net "_NC_DDR0_32B_DQS4_N")
		)
		(pad "C4" smd circle
			(at -12.5 -13.499998 180)
			(size 0.508 0.508)
			(layers "F.Cu" "F.Mask" "F.Paste")
			(net "_NC_DDR0_32B_CB7")
		)
		(pad "C5" smd circle
			(at -11.500002 -13.499998 180)
			(size 0.508 0.508)
			(layers "F.Cu" "F.Mask" "F.Paste")
			(net "_NC_DDR0_32B_CB0")
		)
		(pad "C6" smd circle
			(at -10.500004 -13.499998 180)
			(size 0.508 0.508)
			(layers "F.Cu" "F.Mask" "F.Paste")
			(net "_NC_NFP_DDR0_32B_PLL_DTO0")
		)
		(pad "C7" smd circle
			(at -9.500006 -13.499998 180)
			(size 0.508 0.508)
			(layers "F.Cu" "F.Mask" "F.Paste")
			(net "_NC_NFP_DDR0_32B_PLL_DTO1")
		)
		(pad "C8" smd circle
			(at -8.500008 -13.499998 180)
			(size 0.508 0.508)
			(layers "F.Cu" "F.Mask" "F.Paste")
			(net "_NC_DDR0_32B_BA1")
		)
		(pad "C9" smd circle
			(at -7.50001 -13.499998 180)
			(size 0.508 0.508)
			(layers "F.Cu" "F.Mask" "F.Paste")
			(net "DDR_VDDQ")
		)
		(pad "C10" smd circle
			(at -6.500012 -13.499998 180)
			(size 0.508 0.508)
			(layers "F.Cu" "F.Mask" "F.Paste")
			(net "GND")
		)
		(pad "C11" smd circle
			(at -5.499989 -13.499998 180)
			(size 0.508 0.508)
			(layers "F.Cu" "F.Mask" "F.Paste")
			(net "VDD_CORE")
		)
		(pad "C12" smd circle
			(at -4.499991 -13.499998 180)
			(size 0.508 0.508)
			(layers "F.Cu" "F.Mask" "F.Paste")
			(net "GND")
		)
		(pad "C13" smd circle
			(at -3.499993 -13.499998 180)
			(size 0.508 0.508)
			(layers "F.Cu" "F.Mask" "F.Paste")
			(net "VDD_CORE")
		)
		(pad "C14" smd circle
			(at -2.499995 -13.499998 180)
			(size 0.508 0.508)
			(layers "F.Cu" "F.Mask" "F.Paste")
			(net "GND")
		)
		(pad "C15" smd circle
			(at -1.499997 -13.499998 180)
			(size 0.508 0.508)
			(layers "F.Cu" "F.Mask" "F.Paste")
			(net "VDD_CORE")
		)
		(pad "C16" smd circle
			(at -0.499999 -13.499998 180)
			(size 0.508 0.508)
			(layers "F.Cu" "F.Mask" "F.Paste")
			(net "GND")
		)
		(pad "C17" smd circle
			(at 0.499999 -13.499998 180)
			(size 0.508 0.508)
			(layers "F.Cu" "F.Mask" "F.Paste")
			(net "VDD_CORE")
		)
		(pad "C18" smd circle
			(at 1.499997 -13.499998 180)
			(size 0.508 0.508)
			(layers "F.Cu" "F.Mask" "F.Paste")
			(net "GND")
		)
		(pad "C19" smd circle
			(at 2.499995 -13.499998 180)
			(size 0.508 0.508)
			(layers "F.Cu" "F.Mask" "F.Paste")
			(net "VDD_CORE")
		)
		(pad "C20" smd circle
			(at 3.499993 -13.499998 180)
			(size 0.508 0.508)
			(layers "F.Cu" "F.Mask" "F.Paste")
			(net "GND")
		)
		(pad "C21" smd circle
			(at 4.499991 -13.499998 180)
			(size 0.508 0.508)
			(layers "F.Cu" "F.Mask" "F.Paste")
			(net "VDD_CORE")
		)
		(pad "C22" smd circle
			(at 5.499989 -13.499998 180)
			(size 0.508 0.508)
			(layers "F.Cu" "F.Mask" "F.Paste")
			(net "GND")
		)
		(pad "C23" smd circle
			(at 6.500012 -13.499998 180)
			(size 0.508 0.508)
			(layers "F.Cu" "F.Mask" "F.Paste")
			(net "VDD_CORE")
		)
		(pad "C24" smd circle
			(at 7.50001 -13.499998 180)
			(size 0.508 0.508)
			(layers "F.Cu" "F.Mask" "F.Paste")
			(net "GND")
		)
		(pad "C25" smd circle
			(at 8.500008 -13.499998 180)
			(size 0.508 0.508)
			(layers "F.Cu" "F.Mask" "F.Paste")
			(net "VDD_CORE")
		)
		(pad "C26" smd circle
			(at 9.500006 -13.499998 180)
			(size 0.508 0.508)
			(layers "F.Cu" "F.Mask" "F.Paste")
			(net "GND")
		)
		(pad "C27" smd circle
			(at 10.500004 -13.499998 180)
			(size 0.508 0.508)
			(layers "F.Cu" "F.Mask" "F.Paste")
			(net "_NC_TEST_SCAN_0_OUT37")
		)
		(pad "C28" smd circle
			(at 11.500002 -13.499998 180)
			(size 0.508 0.508)
			(layers "F.Cu" "F.Mask" "F.Paste")
			(net "_NC_TEST_SCAN_0_OUT29")
		)
		(pad "C29" smd circle
			(at 12.5 -13.499998 180)
			(size 0.508 0.508)
			(layers "F.Cu" "F.Mask" "F.Paste")
			(net "_NC_TEST_SCAN_0_OUT31")
		)
		(pad "C30" smd circle
			(at 13.499998 -13.499998 180)
			(size 0.508 0.508)
			(layers "F.Cu" "F.Mask" "F.Paste")
			(net "_NC_TEST_SCAN_0_OUT25")
		)
		(pad "C31" smd circle
			(at 14.499996 -13.499998 180)
			(size 0.508 0.508)
			(layers "F.Cu" "F.Mask" "F.Paste")
			(net "_NC_TEST_SCAN_0_OUT24")
		)
		(pad "C32" smd circle
			(at 15.499994 -13.499998 180)
			(size 0.6604 0.6604)
			(layers "F.Cu" "F.Mask" "F.Paste")
			(net "GND")
		)
		(pad "D1" smd circle
			(at -15.499994 -12.5 180)
			(size 0.508 0.508)
			(layers "F.Cu" "F.Mask" "F.Paste")
			(net "_NC_DDR0_32B_CB4")
		)
		(pad "D2" smd circle
			(at -14.499996 -12.5 180)
			(size 0.508 0.508)
			(layers "F.Cu" "F.Mask" "F.Paste")
			(net "_NC_DDR0_32B_CB3")
		)
		(pad "D3" smd circle
			(at -13.499998 -12.5 180)
			(size 0.508 0.508)
			(layers "F.Cu" "F.Mask" "F.Paste")
			(net "_NC_DDR0_32B_CB5")
		)
		(pad "D4" smd circle
			(at -12.5 -12.5 180)
			(size 0.508 0.508)
			(layers "F.Cu" "F.Mask" "F.Paste")
			(net "_NC_DDR0_32B_CB1")
		)
		(pad "D5" smd circle
			(at -11.500002 -12.5 180)
			(size 0.508 0.508)
			(layers "F.Cu" "F.Mask" "F.Paste")
			(net "_NC_DDR0_32B_CB6")
		)
		(pad "D6" smd circle
			(at -10.500004 -12.5 180)
			(size 0.508 0.508)
			(layers "F.Cu" "F.Mask" "F.Paste")
			(net "_NC_DDR0_32B_A15")
		)
		(pad "D7" smd circle
			(at -9.500006 -12.5 180)
			(size 0.508 0.508)
			(layers "F.Cu" "F.Mask" "F.Paste")
			(net "_NC_DDR0_32B_A10")
		)
		(pad "D8" smd circle
			(at -8.500008 -12.5 180)
			(size 0.508 0.508)
			(layers "F.Cu" "F.Mask" "F.Paste")
			(net "_NC_DDR0_32B_A13")
		)
		(pad "D9" smd circle
			(at -7.50001 -12.5 180)
			(size 0.508 0.508)
			(layers "F.Cu" "F.Mask" "F.Paste")
			(net "_NC_DDR0_32B_ODT1")
		)
		(pad "D10" smd circle
			(at -6.500012 -12.5 180)
			(size 0.508 0.508)
			(layers "F.Cu" "F.Mask" "F.Paste")
			(net "GND")
		)
		(pad "D11" smd circle
			(at -5.499989 -12.5 180)
			(size 0.508 0.508)
			(layers "F.Cu" "F.Mask" "F.Paste")
			(net "GND")
		)
		(pad "D12" smd circle
			(at -4.499991 -12.5 180)
			(size 0.508 0.508)
			(layers "F.Cu" "F.Mask" "F.Paste")
			(net "VDD_CORE")
		)
		(pad "D13" smd circle
			(at -3.499993 -12.5 180)
			(size 0.508 0.508)
			(layers "F.Cu" "F.Mask" "F.Paste")
			(net "GND")
		)
		(pad "D14" smd circle
			(at -2.499995 -12.5 180)
			(size 0.508 0.508)
			(layers "F.Cu" "F.Mask" "F.Paste")
			(net "VDD_CORE")
		)
		(pad "D15" smd circle
			(at -1.499997 -12.5 180)
			(size 0.508 0.508)
			(layers "F.Cu" "F.Mask" "F.Paste")
			(net "GND")
		)
		(pad "D16" smd circle
			(at -0.499999 -12.5 180)
			(size 0.508 0.508)
			(layers "F.Cu" "F.Mask" "F.Paste")
			(net "VDD_CORE")
		)
		(pad "D17" smd circle
			(at 0.499999 -12.5 180)
			(size 0.508 0.508)
			(layers "F.Cu" "F.Mask" "F.Paste")
			(net "GND")
		)
		(pad "D18" smd circle
			(at 1.499997 -12.5 180)
			(size 0.508 0.508)
			(layers "F.Cu" "F.Mask" "F.Paste")
			(net "VDD_CORE")
		)
		(pad "D19" smd circle
			(at 2.499995 -12.5 180)
			(size 0.508 0.508)
			(layers "F.Cu" "F.Mask" "F.Paste")
			(net "GND")
		)
		(pad "D20" smd circle
			(at 3.499993 -12.5 180)
			(size 0.508 0.508)
			(layers "F.Cu" "F.Mask" "F.Paste")
			(net "VDD_CORE")
		)
		(pad "D21" smd circle
			(at 4.499991 -12.5 180)
			(size 0.508 0.508)
			(layers "F.Cu" "F.Mask" "F.Paste")
			(net "GND")
		)
		(pad "D22" smd circle
			(at 5.499989 -12.5 180)
			(size 0.508 0.508)
			(layers "F.Cu" "F.Mask" "F.Paste")
			(net "VDD_CORE")
		)
		(pad "D23" smd circle
			(at 6.500012 -12.5 180)
			(size 0.508 0.508)
			(layers "F.Cu" "F.Mask" "F.Paste")
			(net "GND")
		)
		(pad "D24" smd circle
			(at 7.50001 -12.5 180)
			(size 0.508 0.508)
			(layers "F.Cu" "F.Mask" "F.Paste")
			(net "VDD_CORE")
		)
		(pad "D25" smd circle
			(at 8.500008 -12.5 180)
			(size 0.508 0.508)
			(layers "F.Cu" "F.Mask" "F.Paste")
			(net "GND")
		)
		(pad "D26" smd circle
			(at 9.500006 -12.5 180)
			(size 0.508 0.508)
			(layers "F.Cu" "F.Mask" "F.Paste")
			(net "VDD_CORE")
		)
		(pad "D27" smd circle
			(at 10.500004 -12.5 180)
			(size 0.508 0.508)
			(layers "F.Cu" "F.Mask" "F.Paste")
			(net "_NC_TEST_SCAN_0_OUT36")
		)
		(pad "D28" smd circle
			(at 11.500002 -12.5 180)
			(size 0.508 0.508)
			(layers "F.Cu" "F.Mask" "F.Paste")
			(net "GND")
		)
		(pad "D29" smd circle
			(at 12.5 -12.5 180)
			(size 0.508 0.508)
			(layers "F.Cu" "F.Mask" "F.Paste")
			(net "_NC_TEST_SCAN_0_OUT32")
		)
		(pad "D30" smd circle
			(at 13.499998 -12.5 180)
			(size 0.508 0.508)
			(layers "F.Cu" "F.Mask" "F.Paste")
			(net "_NC_TEST_SCAN_0_OUT23")
		)
		(pad "D31" smd circle
			(at 14.499996 -12.5 180)
			(size 0.508 0.508)
			(layers "F.Cu" "F.Mask" "F.Paste")
			(net "_NC_TEST_SCAN_0_OUT22")
		)
		(pad "D32" smd circle
			(at 15.499994 -12.5 180)
			(size 0.508 0.508)
			(layers "F.Cu" "F.Mask" "F.Paste")
			(net "_NC_TEST_SCAN_0_OUT26")
		)
		(pad "E1" smd circle
			(at -15.499994 -11.500002 180)
			(size 0.508 0.508)
			(layers "F.Cu" "F.Mask" "F.Paste")
			(net "_NC_DDR0_32B_DM4")
		)
		(pad "E2" smd circle
			(at -14.499996 -11.500002 180)
			(size 0.508 0.508)
			(layers "F.Cu" "F.Mask" "F.Paste")
			(net "_NC_DDR0_32B_CB2")
		)
		(pad "E3" smd circle
			(at -13.499998 -11.500002 180)
			(size 0.508 0.508)
			(layers "F.Cu" "F.Mask" "F.Paste")
			(net "_NC_DDR0_32B_DM3")
		)
		(pad "E4" smd circle
			(at -12.5 -11.500002 180)
			(size 0.508 0.508)
			(layers "F.Cu" "F.Mask" "F.Paste")
			(net "DDR_VDDQ")
		)
		(pad "E5" smd circle
			(at -11.500002 -11.500002 180)
			(size 0.508 0.508)
			(layers "F.Cu" "F.Mask" "F.Paste")
			(net "_NC_DDR0_32B_DQ30")
		)
		(pad "E6" smd circle
			(at -10.500004 -11.500002 180)
			(size 0.508 0.508)
			(layers "F.Cu" "F.Mask" "F.Paste")
			(net "_NC_DDR0_32B_A9")
		)
		(pad "E7" smd circle
			(at -9.500006 -11.500002 180)
			(size 0.508 0.508)
			(layers "F.Cu" "F.Mask" "F.Paste")
			(net "_NC_DDR0_32B_CKE0")
		)
		(pad "E8" smd circle
			(at -8.500008 -11.500002 180)
			(size 0.508 0.508)
			(layers "F.Cu" "F.Mask" "F.Paste")
			(net "DDR_VDDQ")
		)
		(pad "E9" smd circle
			(at -7.50001 -11.500002 180)
			(size 0.508 0.508)
			(layers "F.Cu" "F.Mask" "F.Paste")
			(net "_NC_DDR0_32B_CK0_N")
		)
		(pad "E10" smd circle
			(at -6.500012 -11.500002 180)
			(size 0.508 0.508)
			(layers "F.Cu" "F.Mask" "F.Paste")
			(net "GND")
		)
		(pad "E11" smd circle
			(at -5.499989 -11.500002 180)
			(size 0.508 0.508)
			(layers "F.Cu" "F.Mask" "F.Paste")
			(net "VDD_CORE")
		)
		(pad "E12" smd circle
			(at -4.499991 -11.500002 180)
			(size 0.508 0.508)
			(layers "F.Cu" "F.Mask" "F.Paste")
			(net "GND")
		)
		(pad "E13" smd circle
			(at -3.499993 -11.500002 180)
			(size 0.508 0.508)
			(layers "F.Cu" "F.Mask" "F.Paste")
			(net "VDD_CORE")
		)
		(pad "E14" smd circle
			(at -2.499995 -11.500002 180)
			(size 0.508 0.508)
			(layers "F.Cu" "F.Mask" "F.Paste")
			(net "GND")
		)
		(pad "E15" smd circle
			(at -1.499997 -11.500002 180)
			(size 0.508 0.508)
			(layers "F.Cu" "F.Mask" "F.Paste")
			(net "VDD_CORE")
		)
		(pad "E16" smd circle
			(at -0.499999 -11.500002 180)
			(size 0.508 0.508)
			(layers "F.Cu" "F.Mask" "F.Paste")
			(net "GND")
		)
		(pad "E17" smd circle
			(at 0.499999 -11.500002 180)
			(size 0.508 0.508)
			(layers "F.Cu" "F.Mask" "F.Paste")
			(net "VDD_CORE")
		)
		(pad "E18" smd circle
			(at 1.499997 -11.500002 180)
			(size 0.508 0.508)
			(layers "F.Cu" "F.Mask" "F.Paste")
			(net "GND")
		)
		(pad "E19" smd circle
			(at 2.499995 -11.500002 180)
			(size 0.508 0.508)
			(layers "F.Cu" "F.Mask" "F.Paste")
			(net "VDD_CORE")
		)
		(pad "E20" smd circle
			(at 3.499993 -11.500002 180)
			(size 0.508 0.508)
			(layers "F.Cu" "F.Mask" "F.Paste")
			(net "GND")
		)
		(pad "E21" smd circle
			(at 4.499991 -11.500002 180)
			(size 0.508 0.508)
			(layers "F.Cu" "F.Mask" "F.Paste")
			(net "VDD_CORE")
		)
		(pad "E22" smd circle
			(at 5.499989 -11.500002 180)
			(size 0.508 0.508)
			(layers "F.Cu" "F.Mask" "F.Paste")
			(net "GND")
		)
		(pad "E23" smd circle
			(at 6.500012 -11.500002 180)
			(size 0.508 0.508)
			(layers "F.Cu" "F.Mask" "F.Paste")
			(net "VDD_CORE")
		)
		(pad "E24" smd circle
			(at 7.50001 -11.500002 180)
			(size 0.508 0.508)
			(layers "F.Cu" "F.Mask" "F.Paste")
			(net "GND")
		)
		(pad "E25" smd circle
			(at 8.500008 -11.500002 180)
			(size 0.508 0.508)
			(layers "F.Cu" "F.Mask" "F.Paste")
			(net "VDD_CORE")
		)
		(pad "E26" smd circle
			(at 9.500006 -11.500002 180)
			(size 0.508 0.508)
			(layers "F.Cu" "F.Mask" "F.Paste")
			(net "GND")
		)
		(pad "E27" smd circle
			(at 10.500004 -11.500002 180)
			(size 0.508 0.508)
			(layers "F.Cu" "F.Mask" "F.Paste")
			(net "VDD_CORE")
		)
		(pad "E28" smd circle
			(at 11.500002 -11.500002 180)
			(size 0.508 0.508)
			(layers "F.Cu" "F.Mask" "F.Paste")
			(net "_NC_VDDQ_TEST_SCAN_0_OUT_1")
		)
		(pad "E29" smd circle
			(at 12.5 -11.500002 180)
			(size 0.508 0.508)
			(layers "F.Cu" "F.Mask" "F.Paste")
			(net "_NC_TEST_SCAN_0_OUT21")
		)
		(pad "E30" smd circle
			(at 13.499998 -11.500002 180)
			(size 0.508 0.508)
			(layers "F.Cu" "F.Mask" "F.Paste")
			(net "_NC_TEST_SCAN_0_OUT20")
		)
		(pad "E31" smd circle
			(at 14.499996 -11.500002 180)
			(size 0.508 0.508)
			(layers "F.Cu" "F.Mask" "F.Paste")
			(net "_NC_TEST_SCAN_0_OUT19")
		)
		(pad "E32" smd circle
			(at 15.499994 -11.500002 180)
			(size 0.508 0.508)
			(layers "F.Cu" "F.Mask" "F.Paste")
			(net "_NC_TEST_SCAN_0_OUT18")
		)
		(pad "F1" smd circle
			(at -15.499994 -10.500004 180)
			(size 0.508 0.508)
			(layers "F.Cu" "F.Mask" "F.Paste")
			(net "_NC_DDR0_32B_DQ27")
		)
		(pad "F2" smd circle
			(at -14.499996 -10.500004 180)
			(size 0.508 0.508)
			(layers "F.Cu" "F.Mask" "F.Paste")
			(net "_NC_DDR0_32B_DQ28")
		)
		(pad "F3" smd circle
			(at -13.499998 -10.500004 180)
			(size 0.508 0.508)
			(layers "F.Cu" "F.Mask" "F.Paste")
			(net "_NC_DDR0_32B_DQ29")
		)
		(pad "F4" smd circle
			(at -12.5 -10.500004 180)
			(size 0.508 0.508)
			(layers "F.Cu" "F.Mask" "F.Paste")
			(net "GND")
		)
		(pad "F5" smd circle
			(at -11.500002 -10.500004 180)
			(size 0.508 0.508)
			(layers "F.Cu" "F.Mask" "F.Paste")
			(net "_NC_DDR0_32B_DQ24")
		)
		(pad "F6" smd circle
			(at -10.500004 -10.500004 180)
			(size 0.508 0.508)
			(layers "F.Cu" "F.Mask" "F.Paste")
			(net "_NC_DDR0_32B_PAR_OUT")
		)
		(pad "F7" smd circle
			(at -9.500006 -10.500004 180)
			(size 0.508 0.508)
			(layers "F.Cu" "F.Mask" "F.Paste")
			(net "_NC_DDR0_32B_PAR_ERR_L")
		)
		(pad "F8" smd circle
			(at -8.500008 -10.500004 180)
			(size 0.508 0.508)
			(layers "F.Cu" "F.Mask" "F.Paste")
			(net "GND")
		)
		(pad "F9" smd circle
			(at -7.50001 -10.500004 180)
			(size 0.508 0.508)
			(layers "F.Cu" "F.Mask" "F.Paste")
			(net "_NC_DDR0_32B_CK0_P")
		)
		(pad "F10" smd circle
			(at -6.500012 -10.500004 180)
			(size 0.508 0.508)
			(layers "F.Cu" "F.Mask" "F.Paste")
			(net "GND")
		)
		(pad "F11" smd circle
			(at -5.499989 -10.500004 180)
			(size 0.508 0.508)
			(layers "F.Cu" "F.Mask" "F.Paste")
			(net "GND")
		)
		(pad "F12" smd circle
			(at -4.499991 -10.500004 180)
			(size 0.508 0.508)
			(layers "F.Cu" "F.Mask" "F.Paste")
			(net "VDD_CORE")
		)
		(pad "F13" smd circle
			(at -3.499993 -10.500004 180)
			(size 0.508 0.508)
			(layers "F.Cu" "F.Mask" "F.Paste")
			(net "GND")
		)
		(pad "F14" smd circle
			(at -2.499995 -10.500004 180)
			(size 0.508 0.508)
			(layers "F.Cu" "F.Mask" "F.Paste")
			(net "VDD_CORE")
		)
		(pad "F15" smd circle
			(at -1.499997 -10.500004 180)
			(size 0.508 0.508)
			(layers "F.Cu" "F.Mask" "F.Paste")
			(net "GND")
		)
		(pad "F16" smd circle
			(at -0.499999 -10.500004 180)
			(size 0.508 0.508)
			(layers "F.Cu" "F.Mask" "F.Paste")
			(net "VDD_CORE")
		)
		(pad "F17" smd circle
			(at 0.499999 -10.500004 180)
			(size 0.508 0.508)
			(layers "F.Cu" "F.Mask" "F.Paste")
			(net "GND")
		)
		(pad "F18" smd circle
			(at 1.499997 -10.500004 180)
			(size 0.508 0.508)
			(layers "F.Cu" "F.Mask" "F.Paste")
			(net "VDD_CORE")
		)
		(pad "F19" smd circle
			(at 2.499995 -10.500004 180)
			(size 0.508 0.508)
			(layers "F.Cu" "F.Mask" "F.Paste")
			(net "GND")
		)
		(pad "F20" smd circle
			(at 3.499993 -10.500004 180)
			(size 0.508 0.508)
			(layers "F.Cu" "F.Mask" "F.Paste")
			(net "VDD_CORE")
		)
		(pad "F21" smd circle
			(at 4.499991 -10.500004 180)
			(size 0.508 0.508)
			(layers "F.Cu" "F.Mask" "F.Paste")
			(net "GND")
		)
		(pad "F22" smd circle
			(at 5.499989 -10.500004 180)
			(size 0.508 0.508)
			(layers "F.Cu" "F.Mask" "F.Paste")
			(net "VDD_CORE")
		)
		(pad "F23" smd circle
			(at 6.500012 -10.500004 180)
			(size 0.508 0.508)
			(layers "F.Cu" "F.Mask" "F.Paste")
			(net "GND")
		)
		(pad "F24" smd circle
			(at 7.50001 -10.500004 180)
			(size 0.508 0.508)
			(layers "F.Cu" "F.Mask" "F.Paste")
			(net "VDD_CORE")
		)
		(pad "F25" smd circle
			(at 8.500008 -10.500004 180)
			(size 0.508 0.508)
			(layers "F.Cu" "F.Mask" "F.Paste")
			(net "GND")
		)
		(pad "F26" smd circle
			(at 9.500006 -10.500004 180)
			(size 0.508 0.508)
			(layers "F.Cu" "F.Mask" "F.Paste")
			(net "VDD_CORE")
		)
		(pad "F27" smd circle
			(at 10.500004 -10.500004 180)
			(size 0.508 0.508)
			(layers "F.Cu" "F.Mask" "F.Paste")
			(net "GND")
		)
		(pad "F28" smd circle
			(at 11.500002 -10.500004 180)
			(size 0.508 0.508)
			(layers "F.Cu" "F.Mask" "F.Paste")
			(net "_NC_TEST_SCAN_0_OUT16")
		)
		(pad "F29" smd circle
			(at 12.5 -10.500004 180)
			(size 0.508 0.508)
			(layers "F.Cu" "F.Mask" "F.Paste")
			(net "_NC_TEST_SCAN_0_OUT15")
		)
		(pad "F30" smd circle
			(at 13.499998 -10.500004 180)
			(size 0.508 0.508)
			(layers "F.Cu" "F.Mask" "F.Paste")
			(net "_NC_TEST_SCAN_0_OUT14")
		)
		(pad "F31" smd circle
			(at 14.499996 -10.500004 180)
			(size 0.508 0.508)
			(layers "F.Cu" "F.Mask" "F.Paste")
			(net "GND")
		)
		(pad "F32" smd circle
			(at 15.499994 -10.500004 180)
			(size 0.508 0.508)
			(layers "F.Cu" "F.Mask" "F.Paste")
			(net "_NC_TEST_SCAN_0_OUT13")
		)
		(pad "G1" smd circle
			(at -15.499994 -9.500006 180)
			(size 0.508 0.508)
			(layers "F.Cu" "F.Mask" "F.Paste")
			(net "_NC_DDR0_32B_DQ25")
		)
		(pad "G2" smd circle
			(at -14.499996 -9.500006 180)
			(size 0.508 0.508)
			(layers "F.Cu" "F.Mask" "F.Paste")
			(net "_NC_DDR0_32B_DQS3_N")
		)
		(pad "G3" smd circle
			(at -13.499998 -9.500006 180)
			(size 0.508 0.508)
			(layers "F.Cu" "F.Mask" "F.Paste")
			(net "_NC_DDR0_32B_DQS3_P")
		)
		(pad "G4" smd circle
			(at -12.5 -9.500006 180)
			(size 0.508 0.508)
			(layers "F.Cu" "F.Mask" "F.Paste")
			(net "_NC_DDR0_32B_DQ26")
		)
		(pad "G5" smd circle
			(at -11.500002 -9.500006 180)
			(size 0.508 0.508)
			(layers "F.Cu" "F.Mask" "F.Paste")
			(net "_NC_DDR0_32B_DQ31")
		)
		(pad "G6" smd circle
			(at -10.500004 -9.500006 180)
			(size 0.508 0.508)
			(layers "F.Cu" "F.Mask" "F.Paste")
			(net "_NC_DDR0_32B_A12")
		)
		(pad "G7" smd circle
			(at -9.500006 -9.500006 180)
			(size 0.508 0.508)
			(layers "F.Cu" "F.Mask" "F.Paste")
			(net "_NC_DDR0_32B_CK1_N")
		)
		(pad "G8" smd circle
			(at -8.500008 -9.500006 180)
			(size 0.508 0.508)
			(layers "F.Cu" "F.Mask" "F.Paste")
			(net "_NC_DDR0_32B_A2")
		)
		(pad "G9" smd circle
			(at -7.50001 -9.500006 180)
			(size 0.508 0.508)
			(layers "F.Cu" "F.Mask" "F.Paste")
			(net "_NC_DDR0_32B_A0")
		)
		(pad "G10" smd circle
			(at -6.500012 -9.500006 180)
			(size 0.508 0.508)
			(layers "F.Cu" "F.Mask" "F.Paste")
			(net "GND")
		)
		(pad "G11" smd circle
			(at -5.499989 -9.500006 180)
			(size 0.508 0.508)
			(layers "F.Cu" "F.Mask" "F.Paste")
			(net "VDD_CORE")
		)
		(pad "G12" smd circle
			(at -4.499991 -9.500006 180)
			(size 0.508 0.508)
			(layers "F.Cu" "F.Mask" "F.Paste")
			(net "GND")
		)
		(pad "G13" smd circle
			(at -3.499993 -9.500006 180)
			(size 0.508 0.508)
			(layers "F.Cu" "F.Mask" "F.Paste")
			(net "VDD_CORE")
		)
		(pad "G14" smd circle
			(at -2.499995 -9.500006 180)
			(size 0.508 0.508)
			(layers "F.Cu" "F.Mask" "F.Paste")
			(net "GND")
		)
		(pad "G15" smd circle
			(at -1.499997 -9.500006 180)
			(size 0.508 0.508)
			(layers "F.Cu" "F.Mask" "F.Paste")
			(net "VDD_CORE")
		)
		(pad "G16" smd circle
			(at -0.499999 -9.500006 180)
			(size 0.508 0.508)
			(layers "F.Cu" "F.Mask" "F.Paste")
			(net "GND")
		)
		(pad "G17" smd circle
			(at 0.499999 -9.500006 180)
			(size 0.508 0.508)
			(layers "F.Cu" "F.Mask" "F.Paste")
			(net "VDD_CORE")
		)
		(pad "G18" smd circle
			(at 1.499997 -9.500006 180)
			(size 0.508 0.508)
			(layers "F.Cu" "F.Mask" "F.Paste")
			(net "GND")
		)
		(pad "G19" smd circle
			(at 2.499995 -9.500006 180)
			(size 0.508 0.508)
			(layers "F.Cu" "F.Mask" "F.Paste")
			(net "VDD_CORE")
		)
		(pad "G20" smd circle
			(at 3.499993 -9.500006 180)
			(size 0.508 0.508)
			(layers "F.Cu" "F.Mask" "F.Paste")
			(net "GND")
		)
		(pad "G21" smd circle
			(at 4.499991 -9.500006 180)
			(size 0.508 0.508)
			(layers "F.Cu" "F.Mask" "F.Paste")
			(net "VDD_CORE")
		)
		(pad "G22" smd circle
			(at 5.499989 -9.500006 180)
			(size 0.508 0.508)
			(layers "F.Cu" "F.Mask" "F.Paste")
			(net "GND")
		)
		(pad "G23" smd circle
			(at 6.500012 -9.500006 180)
			(size 0.508 0.508)
			(layers "F.Cu" "F.Mask" "F.Paste")
			(net "VDD_CORE")
		)
		(pad "G24" smd circle
			(at 7.50001 -9.500006 180)
			(size 0.508 0.508)
			(layers "F.Cu" "F.Mask" "F.Paste")
			(net "GND")
		)
		(pad "G25" smd circle
			(at 8.500008 -9.500006 180)
			(size 0.508 0.508)
			(layers "F.Cu" "F.Mask" "F.Paste")
			(net "VDD_CORE")
		)
		(pad "G26" smd circle
			(at 9.500006 -9.500006 180)
			(size 0.508 0.508)
			(layers "F.Cu" "F.Mask" "F.Paste")
			(net "GND")
		)
		(pad "G27" smd circle
			(at 10.500004 -9.500006 180)
			(size 0.508 0.508)
			(layers "F.Cu" "F.Mask" "F.Paste")
			(net "VDD_CORE")
		)
		(pad "G28" smd circle
			(at 11.500002 -9.500006 180)
			(size 0.508 0.508)
			(layers "F.Cu" "F.Mask" "F.Paste")
			(net "_NC_TEST_SCAN_0_OUT12")
		)
		(pad "G29" smd circle
			(at 12.5 -9.500006 180)
			(size 0.508 0.508)
			(layers "F.Cu" "F.Mask" "F.Paste")
			(net "_NC_TEST_SCAN_0_OUT11")
		)
		(pad "G30" smd circle
			(at 13.499998 -9.500006 180)
			(size 0.508 0.508)
			(layers "F.Cu" "F.Mask" "F.Paste")
			(net "_NC_TEST_SCAN_0_OUT17")
		)
		(pad "G31" smd circle
			(at 14.499996 -9.500006 180)
			(size 0.508 0.508)
			(layers "F.Cu" "F.Mask" "F.Paste")
			(net "_NC_VDDQ_TEST_SCAN_0_OUT_2")
		)
		(pad "G32" smd circle
			(at 15.499994 -9.500006 180)
			(size 0.508 0.508)
			(layers "F.Cu" "F.Mask" "F.Paste")
			(net "_NC_TEST_SCAN_0_OUT10")
		)
		(pad "H1" smd circle
			(at -15.499994 -8.500008 180)
			(size 0.508 0.508)
			(layers "F.Cu" "F.Mask" "F.Paste")
			(net "_NC_DDR0_32B_DQ17")
		)
		(pad "H2" smd circle
			(at -14.499996 -8.500008 180)
			(size 0.508 0.508)
			(layers "F.Cu" "F.Mask" "F.Paste")
			(net "_NC_DDR0_32B_DM2")
		)
		(pad "H3" smd circle
			(at -13.499998 -8.500008 180)
			(size 0.508 0.508)
			(layers "F.Cu" "F.Mask" "F.Paste")
			(net "_NC_DDR0_32B_DQ23")
		)
		(pad "H4" smd circle
			(at -12.5 -8.500008 180)
			(size 0.508 0.508)
			(layers "F.Cu" "F.Mask" "F.Paste")
			(net "_NC_DDR0_32B_DQ19")
		)
		(pad "H5" smd circle
			(at -11.500002 -8.500008 180)
			(size 0.508 0.508)
			(layers "F.Cu" "F.Mask" "F.Paste")
			(net "_NC_DDR0_32B_DQ16")
		)
		(pad "H6" smd circle
			(at -10.500004 -8.500008 180)
			(size 0.508 0.508)
			(layers "F.Cu" "F.Mask" "F.Paste")
			(net "_NC_DDR0_32B_CK1_P")
		)
		(pad "H7" smd circle
			(at -9.500006 -8.500008 180)
			(size 0.508 0.508)
			(layers "F.Cu" "F.Mask" "F.Paste")
			(net "_NC_DDR0_32B_BA2")
		)
		(pad "H8" smd circle
			(at -8.500008 -8.500008 180)
			(size 0.508 0.508)
			(layers "F.Cu" "F.Mask" "F.Paste")
			(net "_NC_B_DZQ0")
		)
		(pad "H9" smd circle
			(at -7.50001 -8.500008 180)
			(size 0.508 0.508)
			(layers "F.Cu" "F.Mask" "F.Paste")
			(net "_NC_DDR0_32B_CKE1")
		)
		(pad "H10" smd circle
			(at -6.500012 -8.500008 180)
			(size 0.508 0.508)
			(layers "F.Cu" "F.Mask" "F.Paste")
			(net "DDR_VDDQ")
		)
		(pad "H11" smd circle
			(at -5.499989 -8.500008 180)
			(size 0.508 0.508)
			(layers "F.Cu" "F.Mask" "F.Paste")
			(net "GND")
		)
		(pad "H12" smd circle
			(at -4.499991 -8.500008 180)
			(size 0.508 0.508)
			(layers "F.Cu" "F.Mask" "F.Paste")
			(net "VDD_CORE")
		)
		(pad "H13" smd circle
			(at -3.499993 -8.500008 180)
			(size 0.508 0.508)
			(layers "F.Cu" "F.Mask" "F.Paste")
			(net "GND")
		)
		(pad "H14" smd circle
			(at -2.499995 -8.500008 180)
			(size 0.508 0.508)
			(layers "F.Cu" "F.Mask" "F.Paste")
			(net "VDD_CORE")
		)
		(pad "H15" smd circle
			(at -1.499997 -8.500008 180)
			(size 0.508 0.508)
			(layers "F.Cu" "F.Mask" "F.Paste")
			(net "GND")
		)
		(pad "H16" smd circle
			(at -0.499999 -8.500008 180)
			(size 0.508 0.508)
			(layers "F.Cu" "F.Mask" "F.Paste")
			(net "VDD_CORE")
		)
		(pad "H17" smd circle
			(at 0.499999 -8.500008 180)
			(size 0.508 0.508)
			(layers "F.Cu" "F.Mask" "F.Paste")
			(net "GND")
		)
		(pad "H18" smd circle
			(at 1.499997 -8.500008 180)
			(size 0.508 0.508)
			(layers "F.Cu" "F.Mask" "F.Paste")
			(net "VDD_CORE")
		)
		(pad "H19" smd circle
			(at 2.499995 -8.500008 180)
			(size 0.508 0.508)
			(layers "F.Cu" "F.Mask" "F.Paste")
			(net "GND")
		)
		(pad "H20" smd circle
			(at 3.499993 -8.500008 180)
			(size 0.508 0.508)
			(layers "F.Cu" "F.Mask" "F.Paste")
			(net "VDD_CORE")
		)
		(pad "H21" smd circle
			(at 4.499991 -8.500008 180)
			(size 0.508 0.508)
			(layers "F.Cu" "F.Mask" "F.Paste")
			(net "GND")
		)
		(pad "H22" smd circle
			(at 5.499989 -8.500008 180)
			(size 0.508 0.508)
			(layers "F.Cu" "F.Mask" "F.Paste")
			(net "VDD_CORE")
		)
		(pad "H23" smd circle
			(at 6.500012 -8.500008 180)
			(size 0.508 0.508)
			(layers "F.Cu" "F.Mask" "F.Paste")
			(net "GND")
		)
		(pad "H24" smd circle
			(at 7.50001 -8.500008 180)
			(size 0.508 0.508)
			(layers "F.Cu" "F.Mask" "F.Paste")
			(net "VDD_CORE")
		)
		(pad "H25" smd circle
			(at 8.500008 -8.500008 180)
			(size 0.508 0.508)
			(layers "F.Cu" "F.Mask" "F.Paste")
			(net "GND")
		)
		(pad "H26" smd circle
			(at 9.500006 -8.500008 180)
			(size 0.508 0.508)
			(layers "F.Cu" "F.Mask" "F.Paste")
			(net "VDD_CORE")
		)
		(pad "H27" smd circle
			(at 10.500004 -8.500008 180)
			(size 0.508 0.508)
			(layers "F.Cu" "F.Mask" "F.Paste")
			(net "GND")
		)
		(pad "H28" smd circle
			(at 11.500002 -8.500008 180)
			(size 0.508 0.508)
			(layers "F.Cu" "F.Mask" "F.Paste")
			(net "_NC_TEST_SCAN_0_OUT7")
		)
		(pad "H29" smd circle
			(at 12.5 -8.500008 180)
			(size 0.508 0.508)
			(layers "F.Cu" "F.Mask" "F.Paste")
			(net "_NC_TEST_SCAN_0_OUT6")
		)
		(pad "H30" smd circle
			(at 13.499998 -8.500008 180)
			(size 0.508 0.508)
			(layers "F.Cu" "F.Mask" "F.Paste")
			(net "_NC_TEST_SCAN_0_OUT8")
		)
		(pad "H31" smd circle
			(at 14.499996 -8.500008 180)
			(size 0.508 0.508)
			(layers "F.Cu" "F.Mask" "F.Paste")
			(net "_NC_TEST_SCAN_0_OUT5")
		)
		(pad "H32" smd circle
			(at 15.499994 -8.500008 180)
			(size 0.508 0.508)
			(layers "F.Cu" "F.Mask" "F.Paste")
			(net "_NC_TEST_SCAN_0_OUT9")
		)
		(pad "J1" smd circle
			(at -15.499994 -7.50001 180)
			(size 0.508 0.508)
			(layers "F.Cu" "F.Mask" "F.Paste")
			(net "_NC_DDR0_32B_DQS2_P")
		)
		(pad "J2" smd circle
			(at -14.499996 -7.50001 180)
			(size 0.508 0.508)
			(layers "F.Cu" "F.Mask" "F.Paste")
			(net "_NC_DDR0_32B_DQS2_N")
		)
		(pad "J3" smd circle
			(at -13.499998 -7.50001 180)
			(size 0.508 0.508)
			(layers "F.Cu" "F.Mask" "F.Paste")
			(net "DDR_VDDQ")
		)
		(pad "J4" smd circle
			(at -12.5 -7.50001 180)
			(size 0.508 0.508)
			(layers "F.Cu" "F.Mask" "F.Paste")
			(net "_NC_DDR0_32B_DQ22")
		)
		(pad "J5" smd circle
			(at -11.500002 -7.50001 180)
			(size 0.508 0.508)
			(layers "F.Cu" "F.Mask" "F.Paste")
			(net "_NC_DDR0_32B_DQ18")
		)
		(pad "J6" smd circle
			(at -10.500004 -7.50001 180)
			(size 0.508 0.508)
			(layers "F.Cu" "F.Mask" "F.Paste")
			(net "DDR_VDDQ")
		)
		(pad "J7" smd circle
			(at -9.500006 -7.50001 180)
			(size 0.508 0.508)
			(layers "F.Cu" "F.Mask" "F.Paste")
			(net "_NC_DDR0_32B_A4")
		)
		(pad "J8" smd circle
			(at -8.500008 -7.50001 180)
			(size 0.508 0.508)
			(layers "F.Cu" "F.Mask" "F.Paste")
			(net "_NC_DDR0_32B_RAS_L")
		)
		(pad "J9" smd circle
			(at -7.50001 -7.50001 180)
			(size 0.508 0.508)
			(layers "F.Cu" "F.Mask" "F.Paste")
			(net "_NC_DDR0_32B_CS1_L")
		)
		(pad "J10" smd circle
			(at -6.500012 -7.50001 180)
			(size 0.508 0.508)
			(layers "F.Cu" "F.Mask" "F.Paste")
			(net "_NC_B_DZQ1")
		)
		(pad "J11" smd circle
			(at -5.499989 -7.50001 180)
			(size 0.508 0.508)
			(layers "F.Cu" "F.Mask" "F.Paste")
			(net "VDD_CORE")
		)
		(pad "J12" smd circle
			(at -4.499991 -7.50001 180)
			(size 0.508 0.508)
			(layers "F.Cu" "F.Mask" "F.Paste")
			(net "GND")
		)
		(pad "J13" smd circle
			(at -3.499993 -7.50001 180)
			(size 0.508 0.508)
			(layers "F.Cu" "F.Mask" "F.Paste")
			(net "VDD_CORE")
		)
		(pad "J14" smd circle
			(at -2.499995 -7.50001 180)
			(size 0.508 0.508)
			(layers "F.Cu" "F.Mask" "F.Paste")
			(net "GND")
		)
		(pad "J15" smd circle
			(at -1.499997 -7.50001 180)
			(size 0.508 0.508)
			(layers "F.Cu" "F.Mask" "F.Paste")
			(net "VDD_CORE")
		)
		(pad "J16" smd circle
			(at -0.499999 -7.50001 180)
			(size 0.508 0.508)
			(layers "F.Cu" "F.Mask" "F.Paste")
			(net "GND")
		)
		(pad "J17" smd circle
			(at 0.499999 -7.50001 180)
			(size 0.508 0.508)
			(layers "F.Cu" "F.Mask" "F.Paste")
			(net "VDD_CORE")
		)
		(pad "J18" smd circle
			(at 1.499997 -7.50001 180)
			(size 0.508 0.508)
			(layers "F.Cu" "F.Mask" "F.Paste")
			(net "GND")
		)
		(pad "J19" smd circle
			(at 2.499995 -7.50001 180)
			(size 0.508 0.508)
			(layers "F.Cu" "F.Mask" "F.Paste")
			(net "VDD_CORE")
		)
		(pad "J20" smd circle
			(at 3.499993 -7.50001 180)
			(size 0.508 0.508)
			(layers "F.Cu" "F.Mask" "F.Paste")
			(net "GND")
		)
		(pad "J21" smd circle
			(at 4.499991 -7.50001 180)
			(size 0.508 0.508)
			(layers "F.Cu" "F.Mask" "F.Paste")
			(net "VDD_CORE")
		)
		(pad "J22" smd circle
			(at 5.499989 -7.50001 180)
			(size 0.508 0.508)
			(layers "F.Cu" "F.Mask" "F.Paste")
			(net "GND")
		)
		(pad "J23" smd circle
			(at 6.500012 -7.50001 180)
			(size 0.508 0.508)
			(layers "F.Cu" "F.Mask" "F.Paste")
			(net "VDD_CORE")
		)
		(pad "J24" smd circle
			(at 7.50001 -7.50001 180)
			(size 0.508 0.508)
			(layers "F.Cu" "F.Mask" "F.Paste")
			(net "GND")
		)
		(pad "J25" smd circle
			(at 8.500008 -7.50001 180)
			(size 0.508 0.508)
			(layers "F.Cu" "F.Mask" "F.Paste")
			(net "VDD_CORE")
		)
		(pad "J26" smd circle
			(at 9.500006 -7.50001 180)
			(size 0.508 0.508)
			(layers "F.Cu" "F.Mask" "F.Paste")
			(net "GND")
		)
		(pad "J27" smd circle
			(at 10.500004 -7.50001 180)
			(size 0.508 0.508)
			(layers "F.Cu" "F.Mask" "F.Paste")
			(net "_NC_VDDQ_TEST_SCAN_0_OUT_3")
		)
		(pad "J28" smd circle
			(at 11.500002 -7.50001 180)
			(size 0.508 0.508)
			(layers "F.Cu" "F.Mask" "F.Paste")
			(net "_NC_TEST_SCAN_0_OUT4")
		)
		(pad "J29" smd circle
			(at 12.5 -7.50001 180)
			(size 0.508 0.508)
			(layers "F.Cu" "F.Mask" "F.Paste")
			(net "_NC_TEST_SCAN_0_OUT3")
		)
		(pad "J30" smd circle
			(at 13.499998 -7.50001 180)
			(size 0.508 0.508)
			(layers "F.Cu" "F.Mask" "F.Paste")
			(net "_NC_TEST_SCAN_0_OUT2")
		)
		(pad "J31" smd circle
			(at 14.499996 -7.50001 180)
			(size 0.508 0.508)
			(layers "F.Cu" "F.Mask" "F.Paste")
			(net "_NC_TEST_SCAN_0_OUT1")
		)
		(pad "J32" smd circle
			(at 15.499994 -7.50001 180)
			(size 0.508 0.508)
			(layers "F.Cu" "F.Mask" "F.Paste")
			(net "_NC_TEST_SCAN_0_OUT0")
		)
		(pad "K1" smd circle
			(at -15.499994 -6.500012 180)
			(size 0.508 0.508)
			(layers "F.Cu" "F.Mask" "F.Paste")
			(net "_NC_DDR0_32B_DQ21")
		)
		(pad "K2" smd circle
			(at -14.499996 -6.500012 180)
			(size 0.508 0.508)
			(layers "F.Cu" "F.Mask" "F.Paste")
			(net "_NC_DDR0_32B_DQ20")
		)
		(pad "K3" smd circle
			(at -13.499998 -6.500012 180)
			(size 0.508 0.508)
			(layers "F.Cu" "F.Mask" "F.Paste")
			(net "GND")
		)
		(pad "K4" smd circle
			(at -12.5 -6.500012 180)
			(size 0.508 0.508)
			(layers "F.Cu" "F.Mask" "F.Paste")
			(net "_NC_DDR0_32B_DQ14")
		)
		(pad "K5" smd circle
			(at -11.500002 -6.500012 180)
			(size 0.508 0.508)
			(layers "F.Cu" "F.Mask" "F.Paste")
			(net "_NC_DDR0_32B_DQ8")
		)
		(pad "K6" smd circle
			(at -10.500004 -6.500012 180)
			(size 0.508 0.508)
			(layers "F.Cu" "F.Mask" "F.Paste")
			(net "GND")
		)
		(pad "K7" smd circle
			(at -9.500006 -6.500012 180)
			(size 0.508 0.508)
			(layers "F.Cu" "F.Mask" "F.Paste")
			(net "_NC_DDR0_32B_A1")
		)
		(pad "K8" smd circle
			(at -8.500008 -6.500012 180)
			(size 0.508 0.508)
			(layers "F.Cu" "F.Mask" "F.Paste")
			(net "_NC_DDR0_32B_A6")
		)
		(pad "K9" smd circle
			(at -7.50001 -6.500012 180)
			(size 0.508 0.508)
			(layers "F.Cu" "F.Mask" "F.Paste")
			(net "_NC_DDR0_32B_CAS_L")
		)
		(pad "K10" smd circle
			(at -6.500012 -6.500012 180)
			(size 0.508 0.508)
			(layers "F.Cu" "F.Mask" "F.Paste")
			(net "A_DZQ1")
		)
		(pad "K11" smd circle
			(at -5.499989 -6.500012 180)
			(size 0.508 0.508)
			(layers "F.Cu" "F.Mask" "F.Paste")
			(net "GND")
		)
		(pad "K12" smd circle
			(at -4.499991 -6.500012 180)
			(size 0.508 0.508)
			(layers "F.Cu" "F.Mask" "F.Paste")
			(net "VDD_CORE")
		)
		(pad "K13" smd circle
			(at -3.499993 -6.500012 180)
			(size 0.508 0.508)
			(layers "F.Cu" "F.Mask" "F.Paste")
			(net "GND")
		)
		(pad "K14" smd circle
			(at -2.499995 -6.500012 180)
			(size 0.508 0.508)
			(layers "F.Cu" "F.Mask" "F.Paste")
			(net "VDD_CORE")
		)
		(pad "K15" smd circle
			(at -1.499997 -6.500012 180)
			(size 0.508 0.508)
			(layers "F.Cu" "F.Mask" "F.Paste")
			(net "GND")
		)
		(pad "K16" smd circle
			(at -0.499999 -6.500012 180)
			(size 0.508 0.508)
			(layers "F.Cu" "F.Mask" "F.Paste")
			(net "VDD_CORE")
		)
		(pad "K17" smd circle
			(at 0.499999 -6.500012 180)
			(size 0.508 0.508)
			(layers "F.Cu" "F.Mask" "F.Paste")
			(net "GND")
		)
		(pad "K18" smd circle
			(at 1.499997 -6.500012 180)
			(size 0.508 0.508)
			(layers "F.Cu" "F.Mask" "F.Paste")
			(net "VDD_CORE")
		)
		(pad "K19" smd circle
			(at 2.499995 -6.500012 180)
			(size 0.508 0.508)
			(layers "F.Cu" "F.Mask" "F.Paste")
			(net "GND")
		)
		(pad "K20" smd circle
			(at 3.499993 -6.500012 180)
			(size 0.508 0.508)
			(layers "F.Cu" "F.Mask" "F.Paste")
			(net "VDD_CORE")
		)
		(pad "K21" smd circle
			(at 4.499991 -6.500012 180)
			(size 0.508 0.508)
			(layers "F.Cu" "F.Mask" "F.Paste")
			(net "GND")
		)
		(pad "K22" smd circle
			(at 5.499989 -6.500012 180)
			(size 0.508 0.508)
			(layers "F.Cu" "F.Mask" "F.Paste")
			(net "VDD_CORE")
		)
		(pad "K23" smd circle
			(at 6.500012 -6.500012 180)
			(size 0.508 0.508)
			(layers "F.Cu" "F.Mask" "F.Paste")
			(net "GND")
		)
		(pad "K24" smd circle
			(at 7.50001 -6.500012 180)
			(size 0.508 0.508)
			(layers "F.Cu" "F.Mask" "F.Paste")
			(net "VDD_CORE")
		)
		(pad "K25" smd circle
			(at 8.500008 -6.500012 180)
			(size 0.508 0.508)
			(layers "F.Cu" "F.Mask" "F.Paste")
			(net "GND")
		)
		(pad "K26" smd circle
			(at 9.500006 -6.500012 180)
			(size 0.508 0.508)
			(layers "F.Cu" "F.Mask" "F.Paste")
			(net "VDD_CORE")
		)
		(pad "K27" smd circle
			(at 10.500004 -6.500012 180)
			(size 0.508 0.508)
			(layers "F.Cu" "F.Mask" "F.Paste")
			(net "VDDA_PLL")
		)
		(pad "K28" smd circle
			(at 11.500002 -6.500012 180)
			(size 0.508 0.508)
			(layers "F.Cu" "F.Mask" "F.Paste")
			(net "_NC_NFP_TS_DFTANATP_AQ0")
		)
		(pad "K29" smd circle
			(at 12.5 -6.500012 180)
			(size 0.508 0.508)
			(layers "F.Cu" "F.Mask" "F.Paste")
			(net "_NC_NFP_TD_TDC")
		)
		(pad "K30" smd circle
			(at 13.499998 -6.500012 180)
			(size 0.508 0.508)
			(layers "F.Cu" "F.Mask" "F.Paste")
			(net "_NC_NFP_TD_TDA")
		)
		(pad "K31" smd circle
			(at 14.499996 -6.500012 180)
			(size 0.508 0.508)
			(layers "F.Cu" "F.Mask" "F.Paste")
			(net "GND")
		)
		(pad "K32" smd circle
			(at 15.499994 -6.500012 180)
			(size 0.508 0.508)
			(layers "F.Cu" "F.Mask" "F.Paste")
			(net "_NC_NFP_TS_TDC")
		)
		(pad "L1" smd circle
			(at -15.499994 -5.499989 180)
			(size 0.508 0.508)
			(layers "F.Cu" "F.Mask" "F.Paste")
			(net "_NC_DDR0_32B_DM1")
		)
		(pad "L2" smd circle
			(at -14.499996 -5.499989 180)
			(size 0.508 0.508)
			(layers "F.Cu" "F.Mask" "F.Paste")
			(net "_NC_DDR0_32B_DQS1_P")
		)
		(pad "L3" smd circle
			(at -13.499998 -5.499989 180)
			(size 0.508 0.508)
			(layers "F.Cu" "F.Mask" "F.Paste")
			(net "_NC_DDR0_32B_DQS1_N")
		)
		(pad "L4" smd circle
			(at -12.5 -5.499989 180)
			(size 0.508 0.508)
			(layers "F.Cu" "F.Mask" "F.Paste")
			(net "_NC_DDR0_32B_DQ10")
		)
		(pad "L5" smd circle
			(at -11.500002 -5.499989 180)
			(size 0.508 0.508)
			(layers "F.Cu" "F.Mask" "F.Paste")
			(net "_NC_DDR0_32B_DQ13")
		)
		(pad "L6" smd circle
			(at -10.500004 -5.499989 180)
			(size 0.508 0.508)
			(layers "F.Cu" "F.Mask" "F.Paste")
			(net "_NC_DDR0_32B_WE_L")
		)
		(pad "L7" smd circle
			(at -9.500006 -5.499989 180)
			(size 0.508 0.508)
			(layers "F.Cu" "F.Mask" "F.Paste")
			(net "_NC_DDR0_32B_A11")
		)
		(pad "L8" smd circle
			(at -8.500008 -5.499989 180)
			(size 0.508 0.508)
			(layers "F.Cu" "F.Mask" "F.Paste")
			(net "_NC_DDR0_32B_A8")
		)
		(pad "L9" smd circle
			(at -7.50001 -5.499989 180)
			(size 0.508 0.508)
			(layers "F.Cu" "F.Mask" "F.Paste")
			(net "_NC_DDR0_32B_ODT0")
		)
		(pad "L10" smd circle
			(at -6.500012 -5.499989 180)
			(size 0.508 0.508)
			(layers "F.Cu" "F.Mask" "F.Paste")
			(net "_NC_B_AZQ")
		)
		(pad "L11" smd circle
			(at -5.499989 -5.499989 180)
			(size 0.508 0.508)
			(layers "F.Cu" "F.Mask" "F.Paste")
			(net "VDD_CORE")
		)
		(pad "L12" smd circle
			(at -4.499991 -5.499989 180)
			(size 0.508 0.508)
			(layers "F.Cu" "F.Mask" "F.Paste")
			(net "GND")
		)
		(pad "L13" smd circle
			(at -3.499993 -5.499989 180)
			(size 0.508 0.508)
			(layers "F.Cu" "F.Mask" "F.Paste")
			(net "VDD_CORE")
		)
		(pad "L14" smd circle
			(at -2.499995 -5.499989 180)
			(size 0.508 0.508)
			(layers "F.Cu" "F.Mask" "F.Paste")
			(net "GND")
		)
		(pad "L15" smd circle
			(at -1.499997 -5.499989 180)
			(size 0.508 0.508)
			(layers "F.Cu" "F.Mask" "F.Paste")
			(net "VDD_CORE")
		)
		(pad "L16" smd circle
			(at -0.499999 -5.499989 180)
			(size 0.508 0.508)
			(layers "F.Cu" "F.Mask" "F.Paste")
			(net "GND")
		)
		(pad "L17" smd circle
			(at 0.499999 -5.499989 180)
			(size 0.508 0.508)
			(layers "F.Cu" "F.Mask" "F.Paste")
			(net "VDD_CORE")
		)
		(pad "L18" smd circle
			(at 1.499997 -5.499989 180)
			(size 0.508 0.508)
			(layers "F.Cu" "F.Mask" "F.Paste")
			(net "GND")
		)
		(pad "L19" smd circle
			(at 2.499995 -5.499989 180)
			(size 0.508 0.508)
			(layers "F.Cu" "F.Mask" "F.Paste")
			(net "VDD_CORE")
		)
		(pad "L20" smd circle
			(at 3.499993 -5.499989 180)
			(size 0.508 0.508)
			(layers "F.Cu" "F.Mask" "F.Paste")
			(net "GND")
		)
		(pad "L21" smd circle
			(at 4.499991 -5.499989 180)
			(size 0.508 0.508)
			(layers "F.Cu" "F.Mask" "F.Paste")
			(net "VDD_CORE")
		)
		(pad "L22" smd circle
			(at 5.499989 -5.499989 180)
			(size 0.508 0.508)
			(layers "F.Cu" "F.Mask" "F.Paste")
			(net "GND")
		)
		(pad "L23" smd circle
			(at 6.500012 -5.499989 180)
			(size 0.508 0.508)
			(layers "F.Cu" "F.Mask" "F.Paste")
			(net "VDD_CORE")
		)
		(pad "L24" smd circle
			(at 7.50001 -5.499989 180)
			(size 0.508 0.508)
			(layers "F.Cu" "F.Mask" "F.Paste")
			(net "GND")
		)
		(pad "L25" smd circle
			(at 8.500008 -5.499989 180)
			(size 0.508 0.508)
			(layers "F.Cu" "F.Mask" "F.Paste")
			(net "VDD_CORE")
		)
		(pad "L26" smd circle
			(at 9.500006 -5.499989 180)
			(size 0.508 0.508)
			(layers "F.Cu" "F.Mask" "F.Paste")
			(net "GND")
		)
		(pad "L27" smd circle
			(at 10.500004 -5.499989 180)
			(size 0.508 0.508)
			(layers "F.Cu" "F.Mask" "F.Paste")
			(net "GND")
		)
		(pad "L28" smd circle
			(at 11.500002 -5.499989 180)
			(size 0.508 0.508)
			(layers "F.Cu" "F.Mask" "F.Paste")
			(net "_NC_NFP_TS_DFTANATP_AQ1")
		)
		(pad "L29" smd circle
			(at 12.5 -5.499989 180)
			(size 0.508 0.508)
			(layers "F.Cu" "F.Mask" "F.Paste")
			(net "VDD_CORE")
		)
		(pad "L30" smd circle
			(at 13.499998 -5.499989 180)
			(size 0.508 0.508)
			(layers "F.Cu" "F.Mask" "F.Paste")
			(net "VDD_CORE")
		)
		(pad "L31" smd circle
			(at 14.499996 -5.499989 180)
			(size 0.508 0.508)
			(layers "F.Cu" "F.Mask" "F.Paste")
			(net "VDD_CORE")
		)
		(pad "L32" smd circle
			(at 15.499994 -5.499989 180)
			(size 0.508 0.508)
			(layers "F.Cu" "F.Mask" "F.Paste")
			(net "_NC_NFP_TS_TDA")
		)
		(pad "M1" smd circle
			(at -15.499994 -4.499991 180)
			(size 0.508 0.508)
			(layers "F.Cu" "F.Mask" "F.Paste")
			(net "_NC_DDR0_32B_DQ11")
		)
		(pad "M2" smd circle
			(at -14.499996 -4.499991 180)
			(size 0.508 0.508)
			(layers "F.Cu" "F.Mask" "F.Paste")
			(net "_NC_DDR0_32B_DQ12")
		)
		(pad "M3" smd circle
			(at -13.499998 -4.499991 180)
			(size 0.508 0.508)
			(layers "F.Cu" "F.Mask" "F.Paste")
			(net "_NC_DDR0_32B_DQ9")
		)
		(pad "M4" smd circle
			(at -12.5 -4.499991 180)
			(size 0.508 0.508)
			(layers "F.Cu" "F.Mask" "F.Paste")
			(net "_NC_DDR0_32B_DQ15")
		)
		(pad "M5" smd circle
			(at -11.500002 -4.499991 180)
			(size 0.508 0.508)
			(layers "F.Cu" "F.Mask" "F.Paste")
			(net "_NC_DDR0_32B_DQ3")
		)
		(pad "M6" smd circle
			(at -10.500004 -4.499991 180)
			(size 0.508 0.508)
			(layers "F.Cu" "F.Mask" "F.Paste")
			(net "_NC_DDR0_32B_A3")
		)
		(pad "M7" smd circle
			(at -9.500006 -4.499991 180)
			(size 0.508 0.508)
			(layers "F.Cu" "F.Mask" "F.Paste")
			(net "_NC_DDR0_32B_A5")
		)
		(pad "M8" smd circle
			(at -8.500008 -4.499991 180)
			(size 0.508 0.508)
			(layers "F.Cu" "F.Mask" "F.Paste")
			(net "_NC_DDR0_32B_BA0")
		)
		(pad "M9" smd circle
			(at -7.50001 -4.499991 180)
			(size 0.508 0.508)
			(layers "F.Cu" "F.Mask" "F.Paste")
			(net "_NC_DDR0_32B_CS0_L")
		)
		(pad "M10" smd circle
			(at -6.500012 -4.499991 180)
			(size 0.508 0.508)
			(layers "F.Cu" "F.Mask" "F.Paste")
			(net "_NC_NFP_DDR0_32B_PLL_ATO")
		)
		(pad "M11" smd circle
			(at -5.499989 -4.499991 180)
			(size 0.508 0.508)
			(layers "F.Cu" "F.Mask" "F.Paste")
			(net "GND")
		)
		(pad "M12" smd circle
			(at -4.499991 -4.499991 180)
			(size 0.508 0.508)
			(layers "F.Cu" "F.Mask" "F.Paste")
			(net "VDD_CORE")
		)
		(pad "M13" smd circle
			(at -3.499993 -4.499991 180)
			(size 0.508 0.508)
			(layers "F.Cu" "F.Mask" "F.Paste")
			(net "GND")
		)
		(pad "M14" smd circle
			(at -2.499995 -4.499991 180)
			(size 0.508 0.508)
			(layers "F.Cu" "F.Mask" "F.Paste")
			(net "VDD_CORE")
		)
		(pad "M15" smd circle
			(at -1.499997 -4.499991 180)
			(size 0.508 0.508)
			(layers "F.Cu" "F.Mask" "F.Paste")
			(net "GND")
		)
		(pad "M16" smd circle
			(at -0.499999 -4.499991 180)
			(size 0.508 0.508)
			(layers "F.Cu" "F.Mask" "F.Paste")
			(net "VDD_CORE")
		)
		(pad "M17" smd circle
			(at 0.499999 -4.499991 180)
			(size 0.508 0.508)
			(layers "F.Cu" "F.Mask" "F.Paste")
			(net "GND")
		)
		(pad "M18" smd circle
			(at 1.499997 -4.499991 180)
			(size 0.508 0.508)
			(layers "F.Cu" "F.Mask" "F.Paste")
			(net "VDD_CORE")
		)
		(pad "M19" smd circle
			(at 2.499995 -4.499991 180)
			(size 0.508 0.508)
			(layers "F.Cu" "F.Mask" "F.Paste")
			(net "GND")
		)
		(pad "M20" smd circle
			(at 3.499993 -4.499991 180)
			(size 0.508 0.508)
			(layers "F.Cu" "F.Mask" "F.Paste")
			(net "VDD_CORE")
		)
		(pad "M21" smd circle
			(at 4.499991 -4.499991 180)
			(size 0.508 0.508)
			(layers "F.Cu" "F.Mask" "F.Paste")
			(net "GND")
		)
		(pad "M22" smd circle
			(at 5.499989 -4.499991 180)
			(size 0.508 0.508)
			(layers "F.Cu" "F.Mask" "F.Paste")
			(net "VDD_CORE")
		)
		(pad "M23" smd circle
			(at 6.500012 -4.499991 180)
			(size 0.508 0.508)
			(layers "F.Cu" "F.Mask" "F.Paste")
			(net "GND")
		)
		(pad "M24" smd circle
			(at 7.50001 -4.499991 180)
			(size 0.508 0.508)
			(layers "F.Cu" "F.Mask" "F.Paste")
			(net "VDD_CORE")
		)
		(pad "M25" smd circle
			(at 8.500008 -4.499991 180)
			(size 0.508 0.508)
			(layers "F.Cu" "F.Mask" "F.Paste")
			(net "GND")
		)
		(pad "M26" smd circle
			(at 9.500006 -4.499991 180)
			(size 0.508 0.508)
			(layers "F.Cu" "F.Mask" "F.Paste")
			(net "VDD_CORE")
		)
		(pad "M27" smd circle
			(at 10.500004 -4.499991 180)
			(size 0.508 0.508)
			(layers "F.Cu" "F.Mask" "F.Paste")
			(net "VDDA_PLL")
		)
		(pad "M28" smd circle
			(at 11.500002 -4.499991 180)
			(size 0.508 0.508)
			(layers "F.Cu" "F.Mask" "F.Paste")
			(net "NFP_CLK_NRESET_L")
		)
		(pad "M29" smd circle
			(at 12.5 -4.499991 180)
			(size 0.508 0.508)
			(layers "F.Cu" "F.Mask" "F.Paste")
			(net "NFP_SRESET_L")
		)
		(pad "M30" smd circle
			(at 13.499998 -4.499991 180)
			(size 0.508 0.508)
			(layers "F.Cu" "F.Mask" "F.Paste")
			(net "VDD_CORE")
		)
		(pad "M31" smd circle
			(at 14.499996 -4.499991 180)
			(size 0.508 0.508)
			(layers "F.Cu" "F.Mask" "F.Paste")
			(net "NFP_CLK_NRESET_OUT_L")
		)
		(pad "M32" smd circle
			(at 15.499994 -4.499991 180)
			(size 0.508 0.508)
			(layers "F.Cu" "F.Mask" "F.Paste")
			(net "VDDA_TS0")
		)
		(pad "N1" smd circle
			(at -15.499994 -3.499993 180)
			(size 0.508 0.508)
			(layers "F.Cu" "F.Mask" "F.Paste")
			(net "_NC_DDR0_32B_DQ7")
		)
		(pad "N2" smd circle
			(at -14.499996 -3.499993 180)
			(size 0.508 0.508)
			(layers "F.Cu" "F.Mask" "F.Paste")
			(net "DDR_VDDQ")
		)
		(pad "N3" smd circle
			(at -13.499998 -3.499993 180)
			(size 0.508 0.508)
			(layers "F.Cu" "F.Mask" "F.Paste")
			(net "_NC_DDR0_32B_DQS0_P")
		)
		(pad "N4" smd circle
			(at -12.5 -3.499993 180)
			(size 0.508 0.508)
			(layers "F.Cu" "F.Mask" "F.Paste")
			(net "_NC_DDR0_32B_DQ6")
		)
		(pad "N5" smd circle
			(at -11.500002 -3.499993 180)
			(size 0.508 0.508)
			(layers "F.Cu" "F.Mask" "F.Paste")
			(net "DDR_VDDQ")
		)
		(pad "N6" smd circle
			(at -10.500004 -3.499993 180)
			(size 0.508 0.508)
			(layers "F.Cu" "F.Mask" "F.Paste")
			(net "_NC_DDR0_32B_A14")
		)
		(pad "N7" smd circle
			(at -9.500006 -3.499993 180)
			(size 0.508 0.508)
			(layers "F.Cu" "F.Mask" "F.Paste")
			(net "_NC_DDR0_32B_A7")
		)
		(pad "N8" smd circle
			(at -8.500008 -3.499993 180)
			(size 0.508 0.508)
			(layers "F.Cu" "F.Mask" "F.Paste")
			(net "DDR_VDDQ")
		)
		(pad "N9" smd circle
			(at -7.50001 -3.499993 180)
			(size 0.508 0.508)
			(layers "F.Cu" "F.Mask" "F.Paste")
			(net "_NC_DDR0_32A_PAR_OUT")
		)
		(pad "N10" smd circle
			(at -6.500012 -3.499993 180)
			(size 0.508 0.508)
			(layers "F.Cu" "F.Mask" "F.Paste")
			(net "A_DZQ0")
		)
		(pad "N11" smd circle
			(at -5.499989 -3.499993 180)
			(size 0.508 0.508)
			(layers "F.Cu" "F.Mask" "F.Paste")
			(net "VDD_CORE")
		)
		(pad "N12" smd circle
			(at -4.499991 -3.499993 180)
			(size 0.508 0.508)
			(layers "F.Cu" "F.Mask" "F.Paste")
			(net "GND")
		)
		(pad "N13" smd circle
			(at -3.499993 -3.499993 180)
			(size 0.508 0.508)
			(layers "F.Cu" "F.Mask" "F.Paste")
			(net "VDD_CORE")
		)
		(pad "N14" smd circle
			(at -2.499995 -3.499993 180)
			(size 0.508 0.508)
			(layers "F.Cu" "F.Mask" "F.Paste")
			(net "GND")
		)
		(pad "N15" smd circle
			(at -1.499997 -3.499993 180)
			(size 0.508 0.508)
			(layers "F.Cu" "F.Mask" "F.Paste")
			(net "VDD_CORE")
		)
		(pad "N16" smd circle
			(at -0.499999 -3.499993 180)
			(size 0.508 0.508)
			(layers "F.Cu" "F.Mask" "F.Paste")
			(net "GND")
		)
		(pad "N17" smd circle
			(at 0.499999 -3.499993 180)
			(size 0.508 0.508)
			(layers "F.Cu" "F.Mask" "F.Paste")
			(net "VDD_CORE")
		)
		(pad "N18" smd circle
			(at 1.499997 -3.499993 180)
			(size 0.508 0.508)
			(layers "F.Cu" "F.Mask" "F.Paste")
			(net "GND")
		)
		(pad "N19" smd circle
			(at 2.499995 -3.499993 180)
			(size 0.508 0.508)
			(layers "F.Cu" "F.Mask" "F.Paste")
			(net "VDD_CORE")
		)
		(pad "N20" smd circle
			(at 3.499993 -3.499993 180)
			(size 0.508 0.508)
			(layers "F.Cu" "F.Mask" "F.Paste")
			(net "GND")
		)
		(pad "N21" smd circle
			(at 4.499991 -3.499993 180)
			(size 0.508 0.508)
			(layers "F.Cu" "F.Mask" "F.Paste")
			(net "VDD_CORE")
		)
		(pad "N22" smd circle
			(at 5.499989 -3.499993 180)
			(size 0.508 0.508)
			(layers "F.Cu" "F.Mask" "F.Paste")
			(net "GND")
		)
		(pad "N23" smd circle
			(at 6.500012 -3.499993 180)
			(size 0.508 0.508)
			(layers "F.Cu" "F.Mask" "F.Paste")
			(net "VDD_CORE")
		)
		(pad "N24" smd circle
			(at 7.50001 -3.499993 180)
			(size 0.508 0.508)
			(layers "F.Cu" "F.Mask" "F.Paste")
			(net "GND")
		)
		(pad "N25" smd circle
			(at 8.500008 -3.499993 180)
			(size 0.508 0.508)
			(layers "F.Cu" "F.Mask" "F.Paste")
			(net "VDD_CORE")
		)
		(pad "N26" smd circle
			(at 9.500006 -3.499993 180)
			(size 0.508 0.508)
			(layers "F.Cu" "F.Mask" "F.Paste")
			(net "GND")
		)
		(pad "N27" smd circle
			(at 10.500004 -3.499993 180)
			(size 0.508 0.508)
			(layers "F.Cu" "F.Mask" "F.Paste")
			(net "VDDA_PLL")
		)
		(pad "N28" smd circle
			(at 11.500002 -3.499993 180)
			(size 0.508 0.508)
			(layers "F.Cu" "F.Mask" "F.Paste")
			(net "VDD_CORE_PGOOD")
		)
		(pad "N29" smd circle
			(at 12.5 -3.499993 180)
			(size 0.508 0.508)
			(layers "F.Cu" "F.Mask" "F.Paste")
			(net "GND")
		)
		(pad "N30" smd circle
			(at 13.499998 -3.499993 180)
			(size 0.508 0.508)
			(layers "F.Cu" "F.Mask" "F.Paste")
			(net "_NFP_PCIE0_RESET_OUT_L")
		)
		(pad "N31" smd circle
			(at 14.499996 -3.499993 180)
			(size 0.508 0.508)
			(layers "F.Cu" "F.Mask" "F.Paste")
			(net "NFP_UART_SR_RX")
		)
		(pad "N32" smd circle
			(at 15.499994 -3.499993 180)
			(size 0.508 0.508)
			(layers "F.Cu" "F.Mask" "F.Paste")
			(net "_NFP_UART_SR_TX")
		)
		(pad "P1" smd circle
			(at -15.499994 -2.499995 180)
			(size 0.508 0.508)
			(layers "F.Cu" "F.Mask" "F.Paste")
			(net "_NC_DDR0_32B_DM0")
		)
		(pad "P2" smd circle
			(at -14.499996 -2.499995 180)
			(size 0.508 0.508)
			(layers "F.Cu" "F.Mask" "F.Paste")
			(net "GND")
		)
		(pad "P3" smd circle
			(at -13.499998 -2.499995 180)
			(size 0.508 0.508)
			(layers "F.Cu" "F.Mask" "F.Paste")
			(net "_NC_DDR0_32B_DQS0_N")
		)
		(pad "P4" smd circle
			(at -12.5 -2.499995 180)
			(size 0.508 0.508)
			(layers "F.Cu" "F.Mask" "F.Paste")
			(net "_NC_DDR0_32B_DQ4")
		)
		(pad "P5" smd circle
			(at -11.500002 -2.499995 180)
			(size 0.508 0.508)
			(layers "F.Cu" "F.Mask" "F.Paste")
			(net "GND")
		)
		(pad "P6" smd circle
			(at -10.500004 -2.499995 180)
			(size 0.508 0.508)
			(layers "F.Cu" "F.Mask" "F.Paste")
			(net "_NC_DDR0_32B_DRAMRST_L")
		)
		(pad "P7" smd circle
			(at -9.500006 -2.499995 180)
			(size 0.508 0.508)
			(layers "F.Cu" "F.Mask" "F.Paste")
			(net "6N3961")
		)
		(pad "P8" smd circle
			(at -8.500008 -2.499995 180)
			(size 0.508 0.508)
			(layers "F.Cu" "F.Mask" "F.Paste")
			(net "GND")
		)
		(pad "P9" smd circle
			(at -7.50001 -2.499995 180)
			(size 0.508 0.508)
			(layers "F.Cu" "F.Mask" "F.Paste")
			(net "6N3963")
		)
		(pad "P10" smd circle
			(at -6.500012 -2.499995 180)
			(size 0.508 0.508)
			(layers "F.Cu" "F.Mask" "F.Paste")
			(net "_NC_NFP_DDR0_32A_PLL_DTO0")
		)
		(pad "P11" smd circle
			(at -5.499989 -2.499995 180)
			(size 0.508 0.508)
			(layers "F.Cu" "F.Mask" "F.Paste")
			(net "GND")
		)
		(pad "P12" smd circle
			(at -4.499991 -2.499995 180)
			(size 0.508 0.508)
			(layers "F.Cu" "F.Mask" "F.Paste")
			(net "VDD_CORE")
		)
		(pad "P13" smd circle
			(at -3.499993 -2.499995 180)
			(size 0.508 0.508)
			(layers "F.Cu" "F.Mask" "F.Paste")
			(net "GND")
		)
		(pad "P14" smd circle
			(at -2.499995 -2.499995 180)
			(size 0.508 0.508)
			(layers "F.Cu" "F.Mask" "F.Paste")
			(net "VDD_CORE")
		)
		(pad "P15" smd circle
			(at -1.499997 -2.499995 180)
			(size 0.508 0.508)
			(layers "F.Cu" "F.Mask" "F.Paste")
			(net "GND")
		)
		(pad "P16" smd circle
			(at -0.499999 -2.499995 180)
			(size 0.508 0.508)
			(layers "F.Cu" "F.Mask" "F.Paste")
			(net "VDD_CORE")
		)
		(pad "P17" smd circle
			(at 0.499999 -2.499995 180)
			(size 0.508 0.508)
			(layers "F.Cu" "F.Mask" "F.Paste")
			(net "GND")
		)
		(pad "P18" smd circle
			(at 1.499997 -2.499995 180)
			(size 0.508 0.508)
			(layers "F.Cu" "F.Mask" "F.Paste")
			(net "VDD_CORE")
		)
		(pad "P19" smd circle
			(at 2.499995 -2.499995 180)
			(size 0.508 0.508)
			(layers "F.Cu" "F.Mask" "F.Paste")
			(net "GND")
		)
		(pad "P20" smd circle
			(at 3.499993 -2.499995 180)
			(size 0.508 0.508)
			(layers "F.Cu" "F.Mask" "F.Paste")
			(net "VDD_CORE")
		)
		(pad "P21" smd circle
			(at 4.499991 -2.499995 180)
			(size 0.508 0.508)
			(layers "F.Cu" "F.Mask" "F.Paste")
			(net "GND")
		)
		(pad "P22" smd circle
			(at 5.499989 -2.499995 180)
			(size 0.508 0.508)
			(layers "F.Cu" "F.Mask" "F.Paste")
			(net "VDD_CORE")
		)
		(pad "P23" smd circle
			(at 6.500012 -2.499995 180)
			(size 0.508 0.508)
			(layers "F.Cu" "F.Mask" "F.Paste")
			(net "GND")
		)
		(pad "P24" smd circle
			(at 7.50001 -2.499995 180)
			(size 0.508 0.508)
			(layers "F.Cu" "F.Mask" "F.Paste")
			(net "VDD_CORE")
		)
		(pad "P25" smd circle
			(at 8.500008 -2.499995 180)
			(size 0.508 0.508)
			(layers "F.Cu" "F.Mask" "F.Paste")
			(net "GND")
		)
		(pad "P26" smd circle
			(at 9.500006 -2.499995 180)
			(size 0.508 0.508)
			(layers "F.Cu" "F.Mask" "F.Paste")
			(net "VDD_CORE")
		)
		(pad "P27" smd circle
			(at 10.500004 -2.499995 180)
			(size 0.508 0.508)
			(layers "F.Cu" "F.Mask" "F.Paste")
			(net "GND")
		)
		(pad "P28" smd circle
			(at 11.500002 -2.499995 180)
			(size 0.508 0.508)
			(layers "F.Cu" "F.Mask" "F.Paste")
			(net "VDD_CORE_PGOOD")
		)
		(pad "P29" smd circle
			(at 12.5 -2.499995 180)
			(size 0.508 0.508)
			(layers "F.Cu" "F.Mask" "F.Paste")
			(net "NFP_ARM_SPI_FLASH_MISO")
		)
		(pad "P30" smd circle
			(at 13.499998 -2.499995 180)
			(size 0.508 0.508)
			(layers "F.Cu" "F.Mask" "F.Paste")
			(net "PCIE0_RST_L")
		)
		(pad "P31" smd circle
			(at 14.499996 -2.499995 180)
			(size 0.508 0.508)
			(layers "F.Cu" "F.Mask" "F.Paste")
			(net "GND")
		)
		(pad "P32" smd circle
			(at 15.499994 -2.499995 180)
			(size 0.508 0.508)
			(layers "F.Cu" "F.Mask" "F.Paste")
			(net "_NFP_PCIE1_RESET_OUT_L")
		)
		(pad "R1" smd circle
			(at -15.499994 -1.499997 180)
			(size 0.508 0.508)
			(layers "F.Cu" "F.Mask" "F.Paste")
			(net "_NC_DDR0_32B_DQ2")
		)
		(pad "R2" smd circle
			(at -14.499996 -1.499997 180)
			(size 0.508 0.508)
			(layers "F.Cu" "F.Mask" "F.Paste")
			(net "_NC_DDR0_32B_DQ5")
		)
		(pad "R3" smd circle
			(at -13.499998 -1.499997 180)
			(size 0.508 0.508)
			(layers "F.Cu" "F.Mask" "F.Paste")
			(net "_NC_DDR0_32B_DQ1")
		)
		(pad "R4" smd circle
			(at -12.5 -1.499997 180)
			(size 0.508 0.508)
			(layers "F.Cu" "F.Mask" "F.Paste")
			(net "_NC_DDR0_32B_DQ0")
		)
		(pad "R5" smd circle
			(at -11.500002 -1.499997 180)
			(size 0.508 0.508)
			(layers "F.Cu" "F.Mask" "F.Paste")
			(net "DDR0_32A_CB5")
		)
		(pad "R6" smd circle
			(at -10.500004 -1.499997 180)
			(size 0.508 0.508)
			(layers "F.Cu" "F.Mask" "F.Paste")
			(net "DDR0_32A_DM4")
		)
		(pad "R7" smd circle
			(at -9.500006 -1.499997 180)
			(size 0.508 0.508)
			(layers "F.Cu" "F.Mask" "F.Paste")
			(net "DDR0_32A_A14")
		)
		(pad "R8" smd circle
			(at -8.500008 -1.499997 180)
			(size 0.508 0.508)
			(layers "F.Cu" "F.Mask" "F.Paste")
			(net "DDR0_32A_A11")
		)
		(pad "R9" smd circle
			(at -7.50001 -1.499997 180)
			(size 0.508 0.508)
			(layers "F.Cu" "F.Mask" "F.Paste")
			(net "DDR0_32A_A7")
		)
		(pad "R10" smd circle
			(at -6.500012 -1.499997 180)
			(size 0.508 0.508)
			(layers "F.Cu" "F.Mask" "F.Paste")
			(net "_NC_NFP_DDR0_32A_PLL_DTO1")
		)
		(pad "R11" smd circle
			(at -5.499989 -1.499997 180)
			(size 0.508 0.508)
			(layers "F.Cu" "F.Mask" "F.Paste")
			(net "VDD_CORE")
		)
		(pad "R12" smd circle
			(at -4.499991 -1.499997 180)
			(size 0.508 0.508)
			(layers "F.Cu" "F.Mask" "F.Paste")
			(net "GND")
		)
		(pad "R13" smd circle
			(at -3.499993 -1.499997 180)
			(size 0.508 0.508)
			(layers "F.Cu" "F.Mask" "F.Paste")
			(net "VDD_CORE")
		)
		(pad "R14" smd circle
			(at -2.499995 -1.499997 180)
			(size 0.508 0.508)
			(layers "F.Cu" "F.Mask" "F.Paste")
			(net "GND")
		)
		(pad "R15" smd circle
			(at -1.499997 -1.499997 180)
			(size 0.508 0.508)
			(layers "F.Cu" "F.Mask" "F.Paste")
			(net "VDD_CORE")
		)
		(pad "R16" smd circle
			(at -0.499999 -1.499997 180)
			(size 0.508 0.508)
			(layers "F.Cu" "F.Mask" "F.Paste")
			(net "GND")
		)
		(pad "R17" smd circle
			(at 0.499999 -1.499997 180)
			(size 0.508 0.508)
			(layers "F.Cu" "F.Mask" "F.Paste")
			(net "VDD_CORE")
		)
		(pad "R18" smd circle
			(at 1.499997 -1.499997 180)
			(size 0.508 0.508)
			(layers "F.Cu" "F.Mask" "F.Paste")
			(net "GND")
		)
		(pad "R19" smd circle
			(at 2.499995 -1.499997 180)
			(size 0.508 0.508)
			(layers "F.Cu" "F.Mask" "F.Paste")
			(net "VDD_CORE")
		)
		(pad "R20" smd circle
			(at 3.499993 -1.499997 180)
			(size 0.508 0.508)
			(layers "F.Cu" "F.Mask" "F.Paste")
			(net "GND")
		)
		(pad "R21" smd circle
			(at 4.499991 -1.499997 180)
			(size 0.508 0.508)
			(layers "F.Cu" "F.Mask" "F.Paste")
			(net "VDD_CORE")
		)
		(pad "R22" smd circle
			(at 5.499989 -1.499997 180)
			(size 0.508 0.508)
			(layers "F.Cu" "F.Mask" "F.Paste")
			(net "GND")
		)
		(pad "R23" smd circle
			(at 6.500012 -1.499997 180)
			(size 0.508 0.508)
			(layers "F.Cu" "F.Mask" "F.Paste")
			(net "VDD_CORE")
		)
		(pad "R24" smd circle
			(at 7.50001 -1.499997 180)
			(size 0.508 0.508)
			(layers "F.Cu" "F.Mask" "F.Paste")
			(net "GND")
		)
		(pad "R25" smd circle
			(at 8.500008 -1.499997 180)
			(size 0.508 0.508)
			(layers "F.Cu" "F.Mask" "F.Paste")
			(net "VDD_CORE")
		)
		(pad "R26" smd circle
			(at 9.500006 -1.499997 180)
			(size 0.508 0.508)
			(layers "F.Cu" "F.Mask" "F.Paste")
			(net "GND")
		)
		(pad "R27" smd circle
			(at 10.500004 -1.499997 180)
			(size 0.508 0.508)
			(layers "F.Cu" "F.Mask" "F.Paste")
			(net "NFP_CLK_REF_P")
		)
		(pad "R28" smd circle
			(at 11.500002 -1.499997 180)
			(size 0.508 0.508)
			(layers "F.Cu" "F.Mask" "F.Paste")
			(net "NFP_PGOOD4")
		)
		(pad "R29" smd circle
			(at 12.5 -1.499997 180)
			(size 0.508 0.508)
			(layers "F.Cu" "F.Mask" "F.Paste")
			(net "_NFP_ARM_SPI_FLASH_SCK")
		)
		(pad "R30" smd circle
			(at 13.499998 -1.499997 180)
			(size 0.508 0.508)
			(layers "F.Cu" "F.Mask" "F.Paste")
			(net "_NC_SPIX_D3")
		)
		(pad "R31" smd circle
			(at 14.499996 -1.499997 180)
			(size 0.508 0.508)
			(layers "F.Cu" "F.Mask" "F.Paste")
			(net "GND")
		)
		(pad "R32" smd circle
			(at 15.499994 -1.499997 180)
			(size 0.508 0.508)
			(layers "F.Cu" "F.Mask" "F.Paste")
			(net "_NC_NFP_SPIX_SEL3")
		)
		(pad "T1" smd circle
			(at -15.499994 -0.499999 180)
			(size 0.508 0.508)
			(layers "F.Cu" "F.Mask" "F.Paste")
			(net "DDR0_32A_DQS4_N")
		)
		(pad "T2" smd circle
			(at -14.499996 -0.499999 180)
			(size 0.508 0.508)
			(layers "F.Cu" "F.Mask" "F.Paste")
			(net "DDR0_32A_DQS4_P")
		)
		(pad "T3" smd circle
			(at -13.499998 -0.499999 180)
			(size 0.508 0.508)
			(layers "F.Cu" "F.Mask" "F.Paste")
			(net "DDR0_32A_CB7")
		)
		(pad "T4" smd circle
			(at -12.5 -0.499999 180)
			(size 0.508 0.508)
			(layers "F.Cu" "F.Mask" "F.Paste")
			(net "DDR0_32A_CB1")
		)
		(pad "T5" smd circle
			(at -11.500002 -0.499999 180)
			(size 0.508 0.508)
			(layers "F.Cu" "F.Mask" "F.Paste")
			(net "DDR0_32A_CB3")
		)
		(pad "T6" smd circle
			(at -10.500004 -0.499999 180)
			(size 0.508 0.508)
			(layers "F.Cu" "F.Mask" "F.Paste")
			(net "DDR0_32A_CB4")
		)
		(pad "T7" smd circle
			(at -9.500006 -0.499999 180)
			(size 0.508 0.508)
			(layers "F.Cu" "F.Mask" "F.Paste")
			(net "DDR0_32A_A1")
		)
		(pad "T8" smd circle
			(at -8.500008 -0.499999 180)
			(size 0.508 0.508)
			(layers "F.Cu" "F.Mask" "F.Paste")
			(net "DDR0_32A_A3")
		)
		(pad "T9" smd circle
			(at -7.50001 -0.499999 180)
			(size 0.508 0.508)
			(layers "F.Cu" "F.Mask" "F.Paste")
			(net "DDR0_32A_A5")
		)
		(pad "T10" smd circle
			(at -6.500012 -0.499999 180)
			(size 0.508 0.508)
			(layers "F.Cu" "F.Mask" "F.Paste")
			(net "DDR_VDDQ")
		)
		(pad "T11" smd circle
			(at -5.499989 -0.499999 180)
			(size 0.508 0.508)
			(layers "F.Cu" "F.Mask" "F.Paste")
			(net "GND")
		)
		(pad "T12" smd circle
			(at -4.499991 -0.499999 180)
			(size 0.508 0.508)
			(layers "F.Cu" "F.Mask" "F.Paste")
			(net "VDD_CORE")
		)
		(pad "T13" smd circle
			(at -3.499993 -0.499999 180)
			(size 0.508 0.508)
			(layers "F.Cu" "F.Mask" "F.Paste")
			(net "GND")
		)
		(pad "T14" smd circle
			(at -2.499995 -0.499999 180)
			(size 0.508 0.508)
			(layers "F.Cu" "F.Mask" "F.Paste")
			(net "VDD_CORE")
		)
		(pad "T15" smd circle
			(at -1.499997 -0.499999 180)
			(size 0.508 0.508)
			(layers "F.Cu" "F.Mask" "F.Paste")
			(net "GND")
		)
		(pad "T16" smd circle
			(at -0.499999 -0.499999 180)
			(size 0.508 0.508)
			(layers "F.Cu" "F.Mask" "F.Paste")
			(net "VDD_CORE")
		)
		(pad "T17" smd circle
			(at 0.499999 -0.499999 180)
			(size 0.508 0.508)
			(layers "F.Cu" "F.Mask" "F.Paste")
			(net "GND")
		)
		(pad "T18" smd circle
			(at 1.499997 -0.499999 180)
			(size 0.508 0.508)
			(layers "F.Cu" "F.Mask" "F.Paste")
			(net "VDD_CORE")
		)
		(pad "T19" smd circle
			(at 2.499995 -0.499999 180)
			(size 0.508 0.508)
			(layers "F.Cu" "F.Mask" "F.Paste")
			(net "GND")
		)
		(pad "T20" smd circle
			(at 3.499993 -0.499999 180)
			(size 0.508 0.508)
			(layers "F.Cu" "F.Mask" "F.Paste")
			(net "VDD_CORE")
		)
		(pad "T21" smd circle
			(at 4.499991 -0.499999 180)
			(size 0.508 0.508)
			(layers "F.Cu" "F.Mask" "F.Paste")
			(net "GND")
		)
		(pad "T22" smd circle
			(at 5.499989 -0.499999 180)
			(size 0.508 0.508)
			(layers "F.Cu" "F.Mask" "F.Paste")
			(net "VDD_CORE")
		)
		(pad "T23" smd circle
			(at 6.500012 -0.499999 180)
			(size 0.508 0.508)
			(layers "F.Cu" "F.Mask" "F.Paste")
			(net "GND")
		)
		(pad "T24" smd circle
			(at 7.50001 -0.499999 180)
			(size 0.508 0.508)
			(layers "F.Cu" "F.Mask" "F.Paste")
			(net "VDD_CORE")
		)
		(pad "T25" smd circle
			(at 8.500008 -0.499999 180)
			(size 0.508 0.508)
			(layers "F.Cu" "F.Mask" "F.Paste")
			(net "GND")
		)
		(pad "T26" smd circle
			(at 9.500006 -0.499999 180)
			(size 0.508 0.508)
			(layers "F.Cu" "F.Mask" "F.Paste")
			(net "VDD_CORE")
		)
		(pad "T27" smd circle
			(at 10.500004 -0.499999 180)
			(size 0.508 0.508)
			(layers "F.Cu" "F.Mask" "F.Paste")
			(net "NFP_CLK_REF_N")
		)
		(pad "T28" smd circle
			(at 11.500002 -0.499999 180)
			(size 0.508 0.508)
			(layers "F.Cu" "F.Mask" "F.Paste")
			(net "GND")
		)
		(pad "T29" smd circle
			(at 12.5 -0.499999 180)
			(size 0.508 0.508)
			(layers "F.Cu" "F.Mask" "F.Paste")
			(net "_NFP_SPI2_SCK")
		)
		(pad "T30" smd circle
			(at 13.499998 -0.499999 180)
			(size 0.508 0.508)
			(layers "F.Cu" "F.Mask" "F.Paste")
			(net "_NC_NFP_SPI3_MOSI")
		)
		(pad "T31" smd circle
			(at 14.499996 -0.499999 180)
			(size 0.508 0.508)
			(layers "F.Cu" "F.Mask" "F.Paste")
			(net "_NFP_CFG_SPI_FLASH_SCK")
		)
		(pad "T32" smd circle
			(at 15.499994 -0.499999 180)
			(size 0.508 0.508)
			(layers "F.Cu" "F.Mask" "F.Paste")
			(net "_NFP_CFG_SPI_FLASH_SEL")
		)
		(pad "U1" smd circle
			(at -15.499994 0.499999 180)
			(size 0.508 0.508)
			(layers "F.Cu" "F.Mask" "F.Paste")
			(net "DDR0_32A_CB6")
		)
		(pad "U2" smd circle
			(at -14.499996 0.499999 180)
			(size 0.508 0.508)
			(layers "F.Cu" "F.Mask" "F.Paste")
			(net "DDR0_32A_CB0")
		)
		(pad "U3" smd circle
			(at -13.499998 0.499999 180)
			(size 0.508 0.508)
			(layers "F.Cu" "F.Mask" "F.Paste")
			(net "DDR_VDDQ")
		)
		(pad "U4" smd circle
			(at -12.5 0.499999 180)
			(size 0.508 0.508)
			(layers "F.Cu" "F.Mask" "F.Paste")
			(net "DDR0_32A_CB2")
		)
		(pad "U5" smd circle
			(at -11.500002 0.499999 180)
			(size 0.508 0.508)
			(layers "F.Cu" "F.Mask" "F.Paste")
			(net "DDR0_32A_DQ25")
		)
		(pad "U6" smd circle
			(at -10.500004 0.499999 180)
			(size 0.508 0.508)
			(layers "F.Cu" "F.Mask" "F.Paste")
			(net "DDR_VDDQ")
		)
		(pad "U7" smd circle
			(at -9.500006 0.499999 180)
			(size 0.508 0.508)
			(layers "F.Cu" "F.Mask" "F.Paste")
			(net "_NC_DDR0_32A_CK1_P")
		)
		(pad "U8" smd circle
			(at -8.500008 0.499999 180)
			(size 0.508 0.508)
			(layers "F.Cu" "F.Mask" "F.Paste")
			(net "_NC_DDR0_32A_CK1_N")
		)
		(pad "U9" smd circle
			(at -7.50001 0.499999 180)
			(size 0.508 0.508)
			(layers "F.Cu" "F.Mask" "F.Paste")
			(net "DDR0_32A_BA0")
		)
		(pad "U10" smd circle
			(at -6.500012 0.499999 180)
			(size 0.508 0.508)
			(layers "F.Cu" "F.Mask" "F.Paste")
			(net "VDDA_PLL")
		)
		(pad "U11" smd circle
			(at -5.499989 0.499999 180)
			(size 0.508 0.508)
			(layers "F.Cu" "F.Mask" "F.Paste")
			(net "VDD_CORE")
		)
		(pad "U12" smd circle
			(at -4.499991 0.499999 180)
			(size 0.508 0.508)
			(layers "F.Cu" "F.Mask" "F.Paste")
			(net "GND")
		)
		(pad "U13" smd circle
			(at -3.499993 0.499999 180)
			(size 0.508 0.508)
			(layers "F.Cu" "F.Mask" "F.Paste")
			(net "VDD_CORE")
		)
		(pad "U14" smd circle
			(at -2.499995 0.499999 180)
			(size 0.508 0.508)
			(layers "F.Cu" "F.Mask" "F.Paste")
			(net "GND")
		)
		(pad "U15" smd circle
			(at -1.499997 0.499999 180)
			(size 0.508 0.508)
			(layers "F.Cu" "F.Mask" "F.Paste")
			(net "VDD_CORE")
		)
		(pad "U16" smd circle
			(at -0.499999 0.499999 180)
			(size 0.508 0.508)
			(layers "F.Cu" "F.Mask" "F.Paste")
			(net "GND")
		)
		(pad "U17" smd circle
			(at 0.499999 0.499999 180)
			(size 0.508 0.508)
			(layers "F.Cu" "F.Mask" "F.Paste")
			(net "VDD_CORE")
		)
		(pad "U18" smd circle
			(at 1.499997 0.499999 180)
			(size 0.508 0.508)
			(layers "F.Cu" "F.Mask" "F.Paste")
			(net "GND")
		)
		(pad "U19" smd circle
			(at 2.499995 0.499999 180)
			(size 0.508 0.508)
			(layers "F.Cu" "F.Mask" "F.Paste")
			(net "VDD_CORE")
		)
		(pad "U20" smd circle
			(at 3.499993 0.499999 180)
			(size 0.508 0.508)
			(layers "F.Cu" "F.Mask" "F.Paste")
			(net "GND")
		)
		(pad "U21" smd circle
			(at 4.499991 0.499999 180)
			(size 0.508 0.508)
			(layers "F.Cu" "F.Mask" "F.Paste")
			(net "VDD_CORE")
		)
		(pad "U22" smd circle
			(at 5.499989 0.499999 180)
			(size 0.508 0.508)
			(layers "F.Cu" "F.Mask" "F.Paste")
			(net "GND")
		)
		(pad "U23" smd circle
			(at 6.500012 0.499999 180)
			(size 0.508 0.508)
			(layers "F.Cu" "F.Mask" "F.Paste")
			(net "VDD_CORE")
		)
		(pad "U24" smd circle
			(at 7.50001 0.499999 180)
			(size 0.508 0.508)
			(layers "F.Cu" "F.Mask" "F.Paste")
			(net "GND")
		)
		(pad "U25" smd circle
			(at 8.500008 0.499999 180)
			(size 0.508 0.508)
			(layers "F.Cu" "F.Mask" "F.Paste")
			(net "VDD_CORE")
		)
		(pad "U26" smd circle
			(at 9.500006 0.499999 180)
			(size 0.508 0.508)
			(layers "F.Cu" "F.Mask" "F.Paste")
			(net "VDD_1.8V")
		)
		(pad "U27" smd circle
			(at 10.500004 0.499999 180)
			(size 0.508 0.508)
			(layers "F.Cu" "F.Mask" "F.Paste")
			(net "VDD_1.8V")
		)
		(pad "U28" smd circle
			(at 11.500002 0.499999 180)
			(size 0.508 0.508)
			(layers "F.Cu" "F.Mask" "F.Paste")
			(net "_NC_SPI3_SCK")
		)
		(pad "U29" smd circle
			(at 12.5 0.499999 180)
			(size 0.508 0.508)
			(layers "F.Cu" "F.Mask" "F.Paste")
			(net "_NFP_SPI2_MOSI")
		)
		(pad "U30" smd circle
			(at 13.499998 0.499999 180)
			(size 0.508 0.508)
			(layers "F.Cu" "F.Mask" "F.Paste")
			(net "_NFP_CFG_SPI_FLASH_MOSI")
		)
		(pad "U31" smd circle
			(at 14.499996 0.499999 180)
			(size 0.508 0.508)
			(layers "F.Cu" "F.Mask" "F.Paste")
			(net "_NFP_ARM_SPI_FLASH_MOSI")
		)
		(pad "U32" smd circle
			(at 15.499994 0.499999 180)
			(size 0.508 0.508)
			(layers "F.Cu" "F.Mask" "F.Paste")
			(net "_NFP_ARM_SPI_FLASH_SEL")
		)
		(pad "V1" smd circle
			(at -15.499994 1.499997 180)
			(size 0.508 0.508)
			(layers "F.Cu" "F.Mask" "F.Paste")
			(net "DDR0_32A_DQ27")
		)
		(pad "V2" smd circle
			(at -14.499996 1.499997 180)
			(size 0.508 0.508)
			(layers "F.Cu" "F.Mask" "F.Paste")
			(net "DDR0_32A_DQ26")
		)
		(pad "V3" smd circle
			(at -13.499998 1.499997 180)
			(size 0.508 0.508)
			(layers "F.Cu" "F.Mask" "F.Paste")
			(net "GND")
		)
		(pad "V4" smd circle
			(at -12.5 1.499997 180)
			(size 0.508 0.508)
			(layers "F.Cu" "F.Mask" "F.Paste")
			(net "DDR0_32A_DQ28")
		)
		(pad "V5" smd circle
			(at -11.500002 1.499997 180)
			(size 0.508 0.508)
			(layers "F.Cu" "F.Mask" "F.Paste")
			(net "DDR0_32A_DM3")
		)
		(pad "V6" smd circle
			(at -10.500004 1.499997 180)
			(size 0.508 0.508)
			(layers "F.Cu" "F.Mask" "F.Paste")
			(net "GND")
		)
		(pad "V7" smd circle
			(at -9.500006 1.499997 180)
			(size 0.508 0.508)
			(layers "F.Cu" "F.Mask" "F.Paste")
			(net "DDR0_32A_CK0_N")
		)
		(pad "V8" smd circle
			(at -8.500008 1.499997 180)
			(size 0.508 0.508)
			(layers "F.Cu" "F.Mask" "F.Paste")
			(net "DDR0_32A_CK0_P")
		)
		(pad "V9" smd circle
			(at -7.50001 1.499997 180)
			(size 0.508 0.508)
			(layers "F.Cu" "F.Mask" "F.Paste")
			(net "_NC_DDR0_32A_CS1_L")
		)
		(pad "V10" smd circle
			(at -6.500012 1.499997 180)
			(size 0.508 0.508)
			(layers "F.Cu" "F.Mask" "F.Paste")
			(net "DDR0_32A_VREF")
		)
		(pad "V11" smd circle
			(at -5.499989 1.499997 180)
			(size 0.508 0.508)
			(layers "F.Cu" "F.Mask" "F.Paste")
			(net "GND")
		)
		(pad "V12" smd circle
			(at -4.499991 1.499997 180)
			(size 0.508 0.508)
			(layers "F.Cu" "F.Mask" "F.Paste")
			(net "VDD_CORE")
		)
		(pad "V13" smd circle
			(at -3.499993 1.499997 180)
			(size 0.508 0.508)
			(layers "F.Cu" "F.Mask" "F.Paste")
			(net "GND")
		)
		(pad "V14" smd circle
			(at -2.499995 1.499997 180)
			(size 0.508 0.508)
			(layers "F.Cu" "F.Mask" "F.Paste")
			(net "VDD_CORE")
		)
		(pad "V15" smd circle
			(at -1.499997 1.499997 180)
			(size 0.508 0.508)
			(layers "F.Cu" "F.Mask" "F.Paste")
			(net "GND")
		)
		(pad "V16" smd circle
			(at -0.499999 1.499997 180)
			(size 0.508 0.508)
			(layers "F.Cu" "F.Mask" "F.Paste")
			(net "VDD_CORE")
		)
		(pad "V17" smd circle
			(at 0.499999 1.499997 180)
			(size 0.508 0.508)
			(layers "F.Cu" "F.Mask" "F.Paste")
			(net "GND")
		)
		(pad "V18" smd circle
			(at 1.499997 1.499997 180)
			(size 0.508 0.508)
			(layers "F.Cu" "F.Mask" "F.Paste")
			(net "VDD_CORE")
		)
		(pad "V19" smd circle
			(at 2.499995 1.499997 180)
			(size 0.508 0.508)
			(layers "F.Cu" "F.Mask" "F.Paste")
			(net "GND")
		)
		(pad "V20" smd circle
			(at 3.499993 1.499997 180)
			(size 0.508 0.508)
			(layers "F.Cu" "F.Mask" "F.Paste")
			(net "VDD_CORE")
		)
		(pad "V21" smd circle
			(at 4.499991 1.499997 180)
			(size 0.508 0.508)
			(layers "F.Cu" "F.Mask" "F.Paste")
			(net "GND")
		)
		(pad "V22" smd circle
			(at 5.499989 1.499997 180)
			(size 0.508 0.508)
			(layers "F.Cu" "F.Mask" "F.Paste")
			(net "VDD_CORE")
		)
		(pad "V23" smd circle
			(at 6.500012 1.499997 180)
			(size 0.508 0.508)
			(layers "F.Cu" "F.Mask" "F.Paste")
			(net "GND")
		)
		(pad "V24" smd circle
			(at 7.50001 1.499997 180)
			(size 0.508 0.508)
			(layers "F.Cu" "F.Mask" "F.Paste")
			(net "VDD_CORE")
		)
		(pad "V25" smd circle
			(at 8.500008 1.499997 180)
			(size 0.508 0.508)
			(layers "F.Cu" "F.Mask" "F.Paste")
			(net "GND")
		)
		(pad "V26" smd circle
			(at 9.500006 1.499997 180)
			(size 0.508 0.508)
			(layers "F.Cu" "F.Mask" "F.Paste")
			(net "GND")
		)
		(pad "V27" smd circle
			(at 10.500004 1.499997 180)
			(size 0.508 0.508)
			(layers "F.Cu" "F.Mask" "F.Paste")
			(net "VDD_3.3V")
		)
		(pad "V28" smd circle
			(at 11.500002 1.499997 180)
			(size 0.508 0.508)
			(layers "F.Cu" "F.Mask" "F.Paste")
			(net "GND")
		)
		(pad "V29" smd circle
			(at 12.5 1.499997 180)
			(size 0.508 0.508)
			(layers "F.Cu" "F.Mask" "F.Paste")
			(net "GND")
		)
		(pad "V30" smd circle
			(at 13.499998 1.499997 180)
			(size 0.508 0.508)
			(layers "F.Cu" "F.Mask" "F.Paste")
			(net "NFP_CFG_SPI_FLASH_MISO")
		)
		(pad "V31" smd circle
			(at 14.499996 1.499997 180)
			(size 0.508 0.508)
			(layers "F.Cu" "F.Mask" "F.Paste")
			(net "NFP_SPI2_MISO")
		)
		(pad "V32" smd circle
			(at 15.499994 1.499997 180)
			(size 0.508 0.508)
			(layers "F.Cu" "F.Mask" "F.Paste")
			(net "_NC_SPIX_HOLD_L")
		)
		(pad "W1" smd circle
			(at -15.499994 2.499995 180)
			(size 0.508 0.508)
			(layers "F.Cu" "F.Mask" "F.Paste")
			(net "DDR0_32A_DQS3_P")
		)
		(pad "W2" smd circle
			(at -14.499996 2.499995 180)
			(size 0.508 0.508)
			(layers "F.Cu" "F.Mask" "F.Paste")
			(net "DDR0_32A_DQS3_N")
		)
		(pad "W3" smd circle
			(at -13.499998 2.499995 180)
			(size 0.508 0.508)
			(layers "F.Cu" "F.Mask" "F.Paste")
			(net "DDR0_32A_DQ29")
		)
		(pad "W4" smd circle
			(at -12.5 2.499995 180)
			(size 0.508 0.508)
			(layers "F.Cu" "F.Mask" "F.Paste")
			(net "DDR0_32A_DQ30")
		)
		(pad "W5" smd circle
			(at -11.500002 2.499995 180)
			(size 0.508 0.508)
			(layers "F.Cu" "F.Mask" "F.Paste")
			(net "DDR0_32A_DQ24")
		)
		(pad "W6" smd circle
			(at -10.500004 2.499995 180)
			(size 0.508 0.508)
			(layers "F.Cu" "F.Mask" "F.Paste")
			(net "DDR0_32A_DQ31")
		)
		(pad "W7" smd circle
			(at -9.500006 2.499995 180)
			(size 0.508 0.508)
			(layers "F.Cu" "F.Mask" "F.Paste")
			(net "_NC_DDR0_32A_A15")
		)
		(pad "W8" smd circle
			(at -8.500008 2.499995 180)
			(size 0.508 0.508)
			(layers "F.Cu" "F.Mask" "F.Paste")
			(net "_NC_DDR0_32A_CKE1")
		)
		(pad "W9" smd circle
			(at -7.50001 2.499995 180)
			(size 0.508 0.508)
			(layers "F.Cu" "F.Mask" "F.Paste")
			(net "DDR0_32A_CS0_L")
		)
		(pad "W10" smd circle
			(at -6.500012 2.499995 180)
			(size 0.508 0.508)
			(layers "F.Cu" "F.Mask" "F.Paste")
			(net "DDR0_32A_VREF")
		)
		(pad "W11" smd circle
			(at -5.499989 2.499995 180)
			(size 0.508 0.508)
			(layers "F.Cu" "F.Mask" "F.Paste")
			(net "VDD_CORE")
		)
		(pad "W12" smd circle
			(at -4.499991 2.499995 180)
			(size 0.508 0.508)
			(layers "F.Cu" "F.Mask" "F.Paste")
			(net "GND")
		)
		(pad "W13" smd circle
			(at -3.499993 2.499995 180)
			(size 0.508 0.508)
			(layers "F.Cu" "F.Mask" "F.Paste")
			(net "VDD_CORE")
		)
		(pad "W14" smd circle
			(at -2.499995 2.499995 180)
			(size 0.508 0.508)
			(layers "F.Cu" "F.Mask" "F.Paste")
			(net "GND")
		)
		(pad "W15" smd circle
			(at -1.499997 2.499995 180)
			(size 0.508 0.508)
			(layers "F.Cu" "F.Mask" "F.Paste")
			(net "VDD_CORE")
		)
		(pad "W16" smd circle
			(at -0.499999 2.499995 180)
			(size 0.508 0.508)
			(layers "F.Cu" "F.Mask" "F.Paste")
			(net "GND")
		)
		(pad "W17" smd circle
			(at 0.499999 2.499995 180)
			(size 0.508 0.508)
			(layers "F.Cu" "F.Mask" "F.Paste")
			(net "VDD_CORE")
		)
		(pad "W18" smd circle
			(at 1.499997 2.499995 180)
			(size 0.508 0.508)
			(layers "F.Cu" "F.Mask" "F.Paste")
			(net "GND")
		)
		(pad "W19" smd circle
			(at 2.499995 2.499995 180)
			(size 0.508 0.508)
			(layers "F.Cu" "F.Mask" "F.Paste")
			(net "VDD_CORE")
		)
		(pad "W20" smd circle
			(at 3.499993 2.499995 180)
			(size 0.508 0.508)
			(layers "F.Cu" "F.Mask" "F.Paste")
			(net "GND")
		)
		(pad "W21" smd circle
			(at 4.499991 2.499995 180)
			(size 0.508 0.508)
			(layers "F.Cu" "F.Mask" "F.Paste")
			(net "VDD_CORE")
		)
		(pad "W22" smd circle
			(at 5.499989 2.499995 180)
			(size 0.508 0.508)
			(layers "F.Cu" "F.Mask" "F.Paste")
			(net "GND")
		)
		(pad "W23" smd circle
			(at 6.500012 2.499995 180)
			(size 0.508 0.508)
			(layers "F.Cu" "F.Mask" "F.Paste")
			(net "VDD_CORE")
		)
		(pad "W24" smd circle
			(at 7.50001 2.499995 180)
			(size 0.508 0.508)
			(layers "F.Cu" "F.Mask" "F.Paste")
			(net "GND")
		)
		(pad "W25" smd circle
			(at 8.500008 2.499995 180)
			(size 0.508 0.508)
			(layers "F.Cu" "F.Mask" "F.Paste")
			(net "VDD_CORE")
		)
		(pad "W26" smd circle
			(at 9.500006 2.499995 180)
			(size 0.508 0.508)
			(layers "F.Cu" "F.Mask" "F.Paste")
			(net "VDD_3.3V")
		)
		(pad "W27" smd circle
			(at 10.500004 2.499995 180)
			(size 0.508 0.508)
			(layers "F.Cu" "F.Mask" "F.Paste")
			(net "GND")
		)
		(pad "W28" smd circle
			(at 11.500002 2.499995 180)
			(size 0.508 0.508)
			(layers "F.Cu" "F.Mask" "F.Paste")
			(net "MUX_NFP_GPIO1_NWK0_I2C_SDA")
		)
		(pad "W29" smd circle
			(at 12.5 2.499995 180)
			(size 0.508 0.508)
			(layers "F.Cu" "F.Mask" "F.Paste")
			(net "MUX_NFP_GPIO3_NWK1_I2C_SDA")
		)
		(pad "W30" smd circle
			(at 13.499998 2.499995 180)
			(size 0.508 0.508)
			(layers "F.Cu" "F.Mask" "F.Paste")
			(net "GND")
		)
		(pad "W31" smd circle
			(at 14.499996 2.499995 180)
			(size 0.508 0.508)
			(layers "F.Cu" "F.Mask" "F.Paste")
			(net "NFP_SPI2_CS")
		)
		(pad "W32" smd circle
			(at 15.499994 2.499995 180)
			(size 0.508 0.508)
			(layers "F.Cu" "F.Mask" "F.Paste")
			(net "_NC_NFP_SPIX_SEL1")
		)
		(pad "Y1" smd circle
			(at -15.499994 3.499993 180)
			(size 0.508 0.508)
			(layers "F.Cu" "F.Mask" "F.Paste")
			(net "DDR0_32A_DQ23")
		)
		(pad "Y2" smd circle
			(at -14.499996 3.499993 180)
			(size 0.508 0.508)
			(layers "F.Cu" "F.Mask" "F.Paste")
			(net "DDR0_32A_DQ22")
		)
		(pad "Y3" smd circle
			(at -13.499998 3.499993 180)
			(size 0.508 0.508)
			(layers "F.Cu" "F.Mask" "F.Paste")
			(net "DDR0_32A_DQS2_P")
		)
		(pad "Y4" smd circle
			(at -12.5 3.499993 180)
			(size 0.508 0.508)
			(layers "F.Cu" "F.Mask" "F.Paste")
			(net "DDR0_32A_DQS2_N")
		)
		(pad "Y5" smd circle
			(at -11.500002 3.499993 180)
			(size 0.508 0.508)
			(layers "F.Cu" "F.Mask" "F.Paste")
			(net "DDR0_32A_DM2")
		)
		(pad "Y6" smd circle
			(at -10.500004 3.499993 180)
			(size 0.508 0.508)
			(layers "F.Cu" "F.Mask" "F.Paste")
			(net "DDR0_32A_DQ20")
		)
		(pad "Y7" smd circle
			(at -9.500006 3.499993 180)
			(size 0.508 0.508)
			(layers "F.Cu" "F.Mask" "F.Paste")
			(net "DDR0_32A_A10")
		)
		(pad "Y8" smd circle
			(at -8.500008 3.499993 180)
			(size 0.508 0.508)
			(layers "F.Cu" "F.Mask" "F.Paste")
			(net "DDR0_32A_A12")
		)
		(pad "Y9" smd circle
			(at -7.50001 3.499993 180)
			(size 0.508 0.508)
			(layers "F.Cu" "F.Mask" "F.Paste")
			(net "_NC_DDR0_32A_ODT1")
		)
		(pad "Y10" smd circle
			(at -6.500012 3.499993 180)
			(size 0.508 0.508)
			(layers "F.Cu" "F.Mask" "F.Paste")
			(net "VDDA_DDR0_32B")
		)
		(pad "Y11" smd circle
			(at -5.499989 3.499993 180)
			(size 0.508 0.508)
			(layers "F.Cu" "F.Mask" "F.Paste")
			(net "GND")
		)
		(pad "Y12" smd circle
			(at -4.499991 3.499993 180)
			(size 0.508 0.508)
			(layers "F.Cu" "F.Mask" "F.Paste")
			(net "VDD_CORE")
		)
		(pad "Y13" smd circle
			(at -3.499993 3.499993 180)
			(size 0.508 0.508)
			(layers "F.Cu" "F.Mask" "F.Paste")
			(net "GND")
		)
		(pad "Y14" smd circle
			(at -2.499995 3.499993 180)
			(size 0.508 0.508)
			(layers "F.Cu" "F.Mask" "F.Paste")
			(net "VDD_CORE")
		)
		(pad "Y15" smd circle
			(at -1.499997 3.499993 180)
			(size 0.508 0.508)
			(layers "F.Cu" "F.Mask" "F.Paste")
			(net "GND")
		)
		(pad "Y16" smd circle
			(at -0.499999 3.499993 180)
			(size 0.508 0.508)
			(layers "F.Cu" "F.Mask" "F.Paste")
			(net "VDD_CORE")
		)
		(pad "Y17" smd circle
			(at 0.499999 3.499993 180)
			(size 0.508 0.508)
			(layers "F.Cu" "F.Mask" "F.Paste")
			(net "GND")
		)
		(pad "Y18" smd circle
			(at 1.499997 3.499993 180)
			(size 0.508 0.508)
			(layers "F.Cu" "F.Mask" "F.Paste")
			(net "VDD_CORE")
		)
		(pad "Y19" smd circle
			(at 2.499995 3.499993 180)
			(size 0.508 0.508)
			(layers "F.Cu" "F.Mask" "F.Paste")
			(net "GND")
		)
		(pad "Y20" smd circle
			(at 3.499993 3.499993 180)
			(size 0.508 0.508)
			(layers "F.Cu" "F.Mask" "F.Paste")
			(net "VDD_CORE")
		)
		(pad "Y21" smd circle
			(at 4.499991 3.499993 180)
			(size 0.508 0.508)
			(layers "F.Cu" "F.Mask" "F.Paste")
			(net "GND")
		)
		(pad "Y22" smd circle
			(at 5.499989 3.499993 180)
			(size 0.508 0.508)
			(layers "F.Cu" "F.Mask" "F.Paste")
			(net "VDD_CORE")
		)
		(pad "Y23" smd circle
			(at 6.500012 3.499993 180)
			(size 0.508 0.508)
			(layers "F.Cu" "F.Mask" "F.Paste")
			(net "_NC_VSS_SENSE")
		)
		(pad "Y24" smd circle
			(at 7.50001 3.499993 180)
			(size 0.508 0.508)
			(layers "F.Cu" "F.Mask" "F.Paste")
			(net "_NC_VDD_CORE3_SENSE")
		)
		(pad "Y25" smd circle
			(at 8.500008 3.499993 180)
			(size 0.508 0.508)
			(layers "F.Cu" "F.Mask" "F.Paste")
			(net "GND")
		)
		(pad "Y26" smd circle
			(at 9.500006 3.499993 180)
			(size 0.508 0.508)
			(layers "F.Cu" "F.Mask" "F.Paste")
			(net "VDD_3.3V")
		)
		(pad "Y27" smd circle
			(at 10.500004 3.499993 180)
			(size 0.508 0.508)
			(layers "F.Cu" "F.Mask" "F.Paste")
			(net "GND")
		)
		(pad "Y28" smd circle
			(at 11.500002 3.499993 180)
			(size 0.508 0.508)
			(layers "F.Cu" "F.Mask" "F.Paste")
			(net "MUX_NFP_GPIO0_NWK0_I2C_SCL")
		)
		(pad "Y29" smd circle
			(at 12.5 3.499993 180)
			(size 0.508 0.508)
			(layers "F.Cu" "F.Mask" "F.Paste")
			(net "MUX_NFP_GPIO2_NWK1_I2C_SCL")
		)
		(pad "Y30" smd circle
			(at 13.499998 3.499993 180)
			(size 0.508 0.508)
			(layers "F.Cu" "F.Mask" "F.Paste")
			(net "_NFP_JTAG_ARM_TDO")
		)
		(pad "Y31" smd circle
			(at 14.499996 3.499993 180)
			(size 0.508 0.508)
			(layers "F.Cu" "F.Mask" "F.Paste")
			(net "NFP_JTAG_ARM_TRST_L")
		)
		(pad "Y32" smd circle
			(at 15.499994 3.499993 180)
			(size 0.508 0.508)
			(layers "F.Cu" "F.Mask" "F.Paste")
			(net "NFP_JTAG_ARM_TDI")
		)
		(zone
			(layer "F.Cu")
			(hatch none 0.5)
			(connect_pads
				(clearance 0)
			)
			(min_thickness 0.25)
			(keepout
				(tracks allowed)
				(vias not_allowed)
				(pads allowed)
				(copperpour not_allowed)
				(footprints allowed)
			)
			(placement
				(enabled no)
				(sheetname "")
			)
			(fill
				(thermal_gap 0.5)
				(thermal_bridge_width 0.5)
				(island_removal_mode 0)
			)
			(polygon
				(pts
					(xy 70.936993 19.041999) (xy 55.236999 19.041999) (xy 55.236999 19.05) (xy 54.237001 19.05) (xy 54.237001 19.041999)
					(xy 38.537007 19.041999) (xy 38.537007 18.042001) (xy 54.237001 18.042001) (xy 54.237001 11.938)
					(xy 55.236999 11.938) (xy 55.236999 18.042001) (xy 70.936993 18.042001)
				)
			)
		)
		(zone
			(layer "F.Cu")
			(hatch none 0.5)
			(connect_pads
				(clearance 0)
			)
			(min_thickness 0.25)
			(keepout
				(tracks not_allowed)
				(vias allowed)
				(pads allowed)
				(copperpour not_allowed)
				(footprints allowed)
			)
			(placement
				(enabled no)
				(sheetname "")
			)
			(fill
				(thermal_gap 0.5)
				(thermal_bridge_width 0.5)
				(island_removal_mode 0)
			)
			(polygon
				(pts
					(arc
						(start 43.18 36.322)
						(mid 41.148 36.322)
						(end 43.18 36.322)
					)
				)
			)
		)
		(zone
			(layer "F.Cu")
			(hatch none 0.5)
			(connect_pads
				(clearance 0)
			)
			(min_thickness 0.25)
			(keepout
				(tracks not_allowed)
				(vias allowed)
				(pads allowed)
				(copperpour not_allowed)
				(footprints allowed)
			)
			(placement
				(enabled no)
				(sheetname "")
			)
			(fill
				(thermal_gap 0.5)
				(thermal_bridge_width 0.5)
				(island_removal_mode 0)
			)
			(polygon
				(pts
					(arc
						(start 71.628 0.381)
						(mid 69.596 0.381)
						(end 71.628 0.381)
					)
				)
			)
		)
	)
	(footprint ""
		(layer "F.Cu")
		(at 21.971 16.8529)
		(property "Reference" "R21"
			(at 0 0 0)
			(layer "F.SilkS")
			(hide yes)
			(effects
				(font
					(size 1.27 1.27)
				)
			)
		)
		(property "Value" "4.75K"
			(at -0.148158 1.3462 90)
			(unlocked yes)
			(layer "F.Fab")
			(hide yes)
			(effects
				(font
					(size 1.27 0.9652)
					(thickness 0.000001)
				)
				(justify left)
			)
		)
		(property "Device Type" "REST4024"
			(at -0.148158 1.3462 90)
			(unlocked yes)
			(layer "F.Fab")
			(hide yes)
			(effects
				(font
					(size 1.27 0.9652)
					(thickness 0.000001)
				)
				(justify left)
			)
		)
		(duplicate_pad_numbers_are_jumpers no)
		(fp_poly
			(pts
				(xy 0.635 1.0668) (xy 0.635 -1.0668) (xy -0.635 -1.0668) (xy -0.635 1.0668)
			)
			(stroke
				(width 0)
				(type default)
			)
			(fill no)
			(layer "F.CrtYd")
		)
		(fp_line
			(start -0.254 -0.508)
			(end 0.254 -0.508)
			(stroke
				(width 0.0254)
				(type default)
			)
			(layer "F.Fab")
		)
		(fp_line
			(start -0.254 0.508)
			(end -0.254 -0.508)
			(stroke
				(width 0.0254)
				(type default)
			)
			(layer "F.Fab")
		)
		(fp_line
			(start 0.254 -0.508)
			(end 0.254 0.508)
			(stroke
				(width 0.0254)
				(type default)
			)
			(layer "F.Fab")
		)
		(fp_line
			(start 0.254 0.508)
			(end -0.254 0.508)
			(stroke
				(width 0.0254)
				(type default)
			)
			(layer "F.Fab")
		)
		(pad "1" smd rect
			(at 0 -0.4191)
			(size 0.508 0.5334)
			(layers "F.Cu" "F.Mask" "F.Paste")
			(net "VDD_3.3V")
		)
		(pad "2" smd rect
			(at 0 0.4191)
			(size 0.508 0.5334)
			(layers "F.Cu" "F.Mask" "F.Paste")
			(net "3N2521")
		)
		(zone
			(layer "F.Cu")
			(hatch none 0.5)
			(connect_pads
				(clearance 0)
			)
			(min_thickness 0.25)
			(keepout
				(tracks not_allowed)
				(vias allowed)
				(pads allowed)
				(copperpour not_allowed)
				(footprints allowed)
			)
			(placement
				(enabled no)
				(sheetname "")
			)
			(fill
				(thermal_gap 0.5)
				(thermal_bridge_width 0.5)
				(island_removal_mode 0)
			)
			(polygon
				(pts
					(xy 21.9964 16.8275) (xy 21.9964 16.8783) (xy 21.9456 16.8783) (xy 21.9456 16.8275)
				)
			)
		)
	)
	(footprint ""
		(layer "F.Cu")
		(at 16.51 1.397)
		(property "Reference" "R396"
			(at 0.66167 -0.762 90)
			(unlocked yes)
			(layer "F.SilkS")
			(effects
				(font
					(size 0.7874 0.5842)
					(thickness 0.127)
				)
				(justify left)
			)
		)
		(property "Value" "4.75K"
			(at -0.148158 1.3462 90)
			(unlocked yes)
			(layer "F.Fab")
			(hide yes)
			(effects
				(font
					(size 1.27 0.9652)
					(thickness 0.000001)
				)
				(justify left)
			)
		)
		(property "Device Type" "REST4024"
			(at -0.148158 1.3462 90)
			(unlocked yes)
			(layer "F.Fab")
			(hide yes)
			(effects
				(font
					(size 1.27 0.9652)
					(thickness 0.000001)
				)
				(justify left)
			)
		)
		(duplicate_pad_numbers_are_jumpers no)
		(fp_poly
			(pts
				(xy 0.635 1.0668) (xy 0.635 -1.0668) (xy -0.635 -1.0668) (xy -0.635 1.0668)
			)
			(stroke
				(width 0)
				(type default)
			)
			(fill no)
			(layer "F.CrtYd")
		)
		(fp_line
			(start -0.254 -0.508)
			(end 0.254 -0.508)
			(stroke
				(width 0.0254)
				(type default)
			)
			(layer "F.Fab")
		)
		(fp_line
			(start -0.254 0.508)
			(end -0.254 -0.508)
			(stroke
				(width 0.0254)
				(type default)
			)
			(layer "F.Fab")
		)
		(fp_line
			(start 0.254 -0.508)
			(end 0.254 0.508)
			(stroke
				(width 0.0254)
				(type default)
			)
			(layer "F.Fab")
		)
		(fp_line
			(start 0.254 0.508)
			(end -0.254 0.508)
			(stroke
				(width 0.0254)
				(type default)
			)
			(layer "F.Fab")
		)
		(pad "1" smd rect
			(at 0 -0.4191)
			(size 0.508 0.5334)
			(layers "F.Cu" "F.Mask" "F.Paste")
			(net "EXT_3.3V")
		)
		(pad "2" smd rect
			(at 0 0.4191)
			(size 0.508 0.5334)
			(layers "F.Cu" "F.Mask" "F.Paste")
			(net "CPLD_NIC_MEZZ_ID0")
		)
		(zone
			(layer "F.Cu")
			(hatch none 0.5)
			(connect_pads
				(clearance 0)
			)
			(min_thickness 0.25)
			(keepout
				(tracks not_allowed)
				(vias allowed)
				(pads allowed)
				(copperpour not_allowed)
				(footprints allowed)
			)
			(placement
				(enabled no)
				(sheetname "")
			)
			(fill
				(thermal_gap 0.5)
				(thermal_bridge_width 0.5)
				(island_removal_mode 0)
			)
			(polygon
				(pts
					(xy 16.5354 1.3716) (xy 16.5354 1.4224) (xy 16.4846 1.4224) (xy 16.4846 1.3716)
				)
			)
		)
	)
	(footprint ""
		(layer "F.Cu")
		(at 77.051002 19.055994)
		(property "Reference" "V_A-DQ22"
			(at 0 0 0)
			(layer "F.SilkS")
			(hide yes)
			(effects
				(font
					(size 1.27 1.27)
				)
			)
		)
		(property "Value" ""
			(at 0 0 0)
			(layer "F.Fab")
			(effects
				(font
					(size 1.27 1.27)
				)
			)
		)
		(duplicate_pad_numbers_are_jumpers no)
		(pad "1" thru_hole circle
			(at 0 0)
			(size 0.762 0.762)
			(drill 0.20574)
			(layers "*.Cu" "*.Mask")
			(remove_unused_layers no)
			(net "DDR0_32A_DQ22")
			(clearance 0.127)
			(thermal_gap 0.127)
			(padstack
				(mode front_inner_back)
				(layer "Inner"
					(shape circle)
					(size 0.4572 0.4572)
					(clearance 0.1143)
				)
				(layer "B.Cu"
					(shape circle)
					(size 0.4572 0.4572)
					(clearance 0.1143)
				)
			)
		)
	)
	(footprint ""
		(layer "F.Cu")
		(at 77.597 10.922 180)
		(property "Reference" "C263"
			(at -0.15367 -3.81 90)
			(unlocked yes)
			(layer "F.SilkS")
			(effects
				(font
					(size 0.7874 0.5842)
					(thickness 0.127)
				)
				(justify left)
			)
		)
		(property "Value" "1UF"
			(at -0.091846 0.2921 270)
			(unlocked yes)
			(layer "F.Fab")
			(hide yes)
			(effects
				(font
					(size 0.7874 0.5842)
					(thickness 0.2032)
				)
				(justify left)
			)
		)
		(property "Device Type" "CAPC0028"
			(at -0.091846 0.2921 270)
			(unlocked yes)
			(layer "F.Fab")
			(hide yes)
			(effects
				(font
					(size 0.7874 0.5842)
					(thickness 0.2032)
				)
				(justify left)
			)
		)
		(duplicate_pad_numbers_are_jumpers no)
		(fp_poly
			(pts
				(xy 0.635 1.0668) (xy 0.635 -1.0668) (xy -0.635 -1.0668) (xy -0.635 1.0668)
			)
			(stroke
				(width 0)
				(type default)
			)
			(fill no)
			(layer "F.CrtYd")
		)
		(fp_line
			(start 0.254 0.508)
			(end -0.254 0.508)
			(stroke
				(width 0.0254)
				(type default)
			)
			(layer "F.Fab")
		)
		(fp_line
			(start 0.254 -0.508)
			(end 0.254 0.508)
			(stroke
				(width 0.0254)
				(type default)
			)
			(layer "F.Fab")
		)
		(fp_line
			(start -0.254 0.508)
			(end -0.254 -0.508)
			(stroke
				(width 0.0254)
				(type default)
			)
			(layer "F.Fab")
		)
		(fp_line
			(start -0.254 -0.508)
			(end 0.254 -0.508)
			(stroke
				(width 0.0254)
				(type default)
			)
			(layer "F.Fab")
		)
		(pad "1" smd rect
			(at 0 -0.4191 180)
			(size 0.508 0.5334)
			(layers "F.Cu" "F.Mask" "F.Paste")
			(net "DDR0_32A_VREF1B")
		)
		(pad "2" smd rect
			(at 0 0.4191 180)
			(size 0.508 0.5334)
			(layers "F.Cu" "F.Mask" "F.Paste")
			(net "GND")
		)
		(zone
			(layer "F.Cu")
			(hatch none 0.5)
			(connect_pads
				(clearance 0)
			)
			(min_thickness 0.25)
			(keepout
				(tracks not_allowed)
				(vias allowed)
				(pads allowed)
				(copperpour not_allowed)
				(footprints allowed)
			)
			(placement
				(enabled no)
				(sheetname "")
			)
			(fill
				(thermal_gap 0.5)
				(thermal_bridge_width 0.5)
				(island_removal_mode 0)
			)
			(polygon
				(pts
					(xy 77.5716 10.9474) (xy 77.5716 10.8966) (xy 77.6224 10.8966) (xy 77.6224 10.9474)
				)
			)
		)
	)
	(footprint ""
		(layer "F.Cu")
		(at 78.994 4.191 90)
		(property "Reference" "R289"
			(at -0.78867 -1.524 0)
			(unlocked yes)
			(layer "F.SilkS")
			(effects
				(font
					(size 0.7874 0.5842)
					(thickness 0.127)
				)
				(justify left)
			)
		)
		(property "Value" "100"
			(at -0.148158 1.3462 180)
			(unlocked yes)
			(layer "F.Fab")
			(hide yes)
			(effects
				(font
					(size 1.27 0.9652)
					(thickness 0.000001)
				)
				(justify left)
			)
		)
		(property "Device Type" "REST4030"
			(at -0.148158 1.3462 180)
			(unlocked yes)
			(layer "F.Fab")
			(hide yes)
			(effects
				(font
					(size 1.27 0.9652)
					(thickness 0.000001)
				)
				(justify left)
			)
		)
		(duplicate_pad_numbers_are_jumpers no)
		(fp_poly
			(pts
				(xy 0.635 1.0668) (xy 0.635 -1.0668) (xy -0.635 -1.0668) (xy -0.635 1.0668)
			)
			(stroke
				(width 0)
				(type default)
			)
			(fill no)
			(layer "F.CrtYd")
		)
		(fp_line
			(start 0.254 -0.508)
			(end 0.254 0.508)
			(stroke
				(width 0.0254)
				(type default)
			)
			(layer "F.Fab")
		)
		(fp_line
			(start -0.254 -0.508)
			(end 0.254 -0.508)
			(stroke
				(width 0.0254)
				(type default)
			)
			(layer "F.Fab")
		)
		(fp_line
			(start 0.254 0.508)
			(end -0.254 0.508)
			(stroke
				(width 0.0254)
				(type default)
			)
			(layer "F.Fab")
		)
		(fp_line
			(start -0.254 0.508)
			(end -0.254 -0.508)
			(stroke
				(width 0.0254)
				(type default)
			)
			(layer "F.Fab")
		)
		(pad "1" smd rect
			(at 0 -0.4191 90)
			(size 0.508 0.5334)
			(layers "F.Cu" "F.Mask" "F.Paste")
			(net "GND")
		)
		(pad "2" smd rect
			(at 0 0.4191 90)
			(size 0.508 0.5334)
			(layers "F.Cu" "F.Mask" "F.Paste")
			(net "DDR0_32A_VREF0B")
		)
		(zone
			(layer "F.Cu")
			(hatch none 0.5)
			(connect_pads
				(clearance 0)
			)
			(min_thickness 0.25)
			(keepout
				(tracks not_allowed)
				(vias allowed)
				(pads allowed)
				(copperpour not_allowed)
				(footprints allowed)
			)
			(placement
				(enabled no)
				(sheetname "")
			)
			(fill
				(thermal_gap 0.5)
				(thermal_bridge_width 0.5)
				(island_removal_mode 0)
			)
			(polygon
				(pts
					(xy 78.9686 4.1656) (xy 79.0194 4.1656) (xy 79.0194 4.2164) (xy 78.9686 4.2164)
				)
			)
		)
	)
	(footprint ""
		(layer "F.Cu")
		(at 35.941 7.493 90)
		(property "Reference" "R132"
			(at 0 0 90)
			(layer "F.SilkS")
			(hide yes)
			(effects
				(font
					(size 1.27 1.27)
				)
			)
		)
		(property "Value" "0"
			(at -0.148158 1.3462 180)
			(unlocked yes)
			(layer "F.Fab")
			(hide yes)
			(effects
				(font
					(size 1.27 0.9652)
					(thickness 0.000001)
				)
				(justify left)
			)
		)
		(property "Device Type" "REST1111"
			(at -0.148158 1.3462 180)
			(unlocked yes)
			(layer "F.Fab")
			(hide yes)
			(effects
				(font
					(size 1.27 0.9652)
					(thickness 0.000001)
				)
				(justify left)
			)
		)
		(duplicate_pad_numbers_are_jumpers no)
		(fp_poly
			(pts
				(xy 0.635 1.0668) (xy 0.635 -1.0668) (xy -0.635 -1.0668) (xy -0.635 1.0668)
			)
			(stroke
				(width 0)
				(type default)
			)
			(fill no)
			(layer "F.CrtYd")
		)
		(fp_line
			(start 0.254 -0.508)
			(end 0.254 0.508)
			(stroke
				(width 0.0254)
				(type default)
			)
			(layer "F.Fab")
		)
		(fp_line
			(start -0.254 -0.508)
			(end 0.254 -0.508)
			(stroke
				(width 0.0254)
				(type default)
			)
			(layer "F.Fab")
		)
		(fp_line
			(start 0.254 0.508)
			(end -0.254 0.508)
			(stroke
				(width 0.0254)
				(type default)
			)
			(layer "F.Fab")
		)
		(fp_line
			(start -0.254 0.508)
			(end -0.254 -0.508)
			(stroke
				(width 0.0254)
				(type default)
			)
			(layer "F.Fab")
		)
		(pad "1" smd rect
			(at 0 -0.4191 90)
			(size 0.508 0.5334)
			(layers "F.Cu" "F.Mask" "F.Paste")
			(net "3N2290")
		)
		(pad "2" smd rect
			(at 0 0.4191 90)
			(size 0.508 0.5334)
			(layers "F.Cu" "F.Mask" "F.Paste")
			(net "NFP_SERDES012_SYSCLK_IN_N")
		)
		(zone
			(layer "F.Cu")
			(hatch none 0.5)
			(connect_pads
				(clearance 0)
			)
			(min_thickness 0.25)
			(keepout
				(tracks not_allowed)
				(vias allowed)
				(pads allowed)
				(copperpour not_allowed)
				(footprints allowed)
			)
			(placement
				(enabled no)
				(sheetname "")
			)
			(fill
				(thermal_gap 0.5)
				(thermal_bridge_width 0.5)
				(island_removal_mode 0)
			)
			(polygon
				(pts
					(xy 35.9156 7.4676) (xy 35.9664 7.4676) (xy 35.9664 7.5184) (xy 35.9156 7.5184)
				)
			)
		)
	)
	(footprint ""
		(layer "F.Cu")
		(at 74.2442 42.164 -90)
		(property "Reference" "TP53"
			(at -1.016 0.35433 90)
			(unlocked yes)
			(layer "F.SilkS")
			(effects
				(font
					(size 0.7874 0.5842)
					(thickness 0.127)
				)
				(justify left)
			)
		)
		(property "Value" "*"
			(at -0.4826 -0.14732 270)
			(unlocked yes)
			(layer "F.Fab")
			(hide yes)
			(effects
				(font
					(size 1.27 0.9652)
					(thickness 0.000001)
				)
				(justify left)
			)
		)
		(property "Device Type" "TP_SMALL"
			(at -0.4826 -0.14732 270)
			(unlocked yes)
			(layer "F.Fab")
			(hide yes)
			(effects
				(font
					(size 1.27 0.9652)
					(thickness 0.000001)
				)
				(justify left)
			)
		)
		(duplicate_pad_numbers_are_jumpers no)
		(fp_line
			(start -0.8636 0.8636)
			(end 0.8636 0.8636)
			(stroke
				(width 0.1524)
				(type default)
			)
			(layer "F.SilkS")
		)
		(fp_line
			(start 0.8636 0.8636)
			(end 0.8636 -0.8636)
			(stroke
				(width 0.1524)
				(type default)
			)
			(layer "F.SilkS")
		)
		(fp_line
			(start -0.8636 -0.8636)
			(end -0.8636 0.8636)
			(stroke
				(width 0.1524)
				(type default)
			)
			(layer "F.SilkS")
		)
		(fp_line
			(start 0.8636 -0.8636)
			(end -0.8636 -0.8636)
			(stroke
				(width 0.1524)
				(type default)
			)
			(layer "F.SilkS")
		)
		(fp_poly
			(pts
				(xy -0.635 -0.635) (xy -0.635 0.635) (xy 0.635 0.635) (xy 0.635 -0.635)
			)
			(stroke
				(width 0)
				(type default)
			)
			(fill no)
			(layer "F.CrtYd")
		)
		(pad "1" smd rect
			(at 0 0 270)
			(size 1.27 1.27)
			(layers "F.Cu" "F.Mask" "F.Paste")
			(net "GND")
		)
	)
	(footprint ""
		(layer "F.Cu")
		(at 26.67 43.561)
		(property "Reference" "C81"
			(at 0 0 0)
			(layer "F.SilkS")
			(hide yes)
			(effects
				(font
					(size 1.27 1.27)
				)
			)
		)
		(property "Value" "680PF"
			(at -0.091846 0.2921 90)
			(unlocked yes)
			(layer "F.Fab")
			(hide yes)
			(effects
				(font
					(size 0.7874 0.5842)
					(thickness 0.2032)
				)
				(justify left)
			)
		)
		(property "Device Type" "CAPC0012"
			(at -0.091846 0.2921 90)
			(unlocked yes)
			(layer "F.Fab")
			(hide yes)
			(effects
				(font
					(size 0.7874 0.5842)
					(thickness 0.2032)
				)
				(justify left)
			)
		)
		(duplicate_pad_numbers_are_jumpers no)
		(fp_poly
			(pts
				(xy 0.635 1.0668) (xy 0.635 -1.0668) (xy -0.635 -1.0668) (xy -0.635 1.0668)
			)
			(stroke
				(width 0)
				(type default)
			)
			(fill no)
			(layer "F.CrtYd")
		)
		(fp_line
			(start -0.254 -0.508)
			(end 0.254 -0.508)
			(stroke
				(width 0.0254)
				(type default)
			)
			(layer "F.Fab")
		)
		(fp_line
			(start -0.254 0.508)
			(end -0.254 -0.508)
			(stroke
				(width 0.0254)
				(type default)
			)
			(layer "F.Fab")
		)
		(fp_line
			(start 0.254 -0.508)
			(end 0.254 0.508)
			(stroke
				(width 0.0254)
				(type default)
			)
			(layer "F.Fab")
		)
		(fp_line
			(start 0.254 0.508)
			(end -0.254 0.508)
			(stroke
				(width 0.0254)
				(type default)
			)
			(layer "F.Fab")
		)
		(pad "1" smd rect
			(at 0 -0.4191)
			(size 0.508 0.5334)
			(layers "F.Cu" "F.Mask" "F.Paste")
			(net "10N2383")
		)
		(pad "2" smd rect
			(at 0 0.4191)
			(size 0.508 0.5334)
			(layers "F.Cu" "F.Mask" "F.Paste")
			(net "GND")
		)
		(zone
			(layer "F.Cu")
			(hatch none 0.5)
			(connect_pads
				(clearance 0)
			)
			(min_thickness 0.25)
			(keepout
				(tracks not_allowed)
				(vias allowed)
				(pads allowed)
				(copperpour not_allowed)
				(footprints allowed)
			)
			(placement
				(enabled no)
				(sheetname "")
			)
			(fill
				(thermal_gap 0.5)
				(thermal_bridge_width 0.5)
				(island_removal_mode 0)
			)
			(polygon
				(pts
					(xy 26.6954 43.5356) (xy 26.6954 43.5864) (xy 26.6446 43.5864) (xy 26.6446 43.5356)
				)
			)
		)
	)
	(footprint ""
		(layer "F.Cu")
		(at 49.53 50.038 180)
		(property "Reference" "R121"
			(at 0 0 180)
			(layer "F.SilkS")
			(hide yes)
			(effects
				(font
					(size 1.27 1.27)
				)
			)
		)
		(property "Value" "100K"
			(at -0.148158 1.3462 270)
			(unlocked yes)
			(layer "F.Fab")
			(hide yes)
			(effects
				(font
					(size 1.27 0.9652)
					(thickness 0.000001)
				)
				(justify left)
			)
		)
		(property "Device Type" "REST0001"
			(at -0.148158 1.3462 270)
			(unlocked yes)
			(layer "F.Fab")
			(hide yes)
			(effects
				(font
					(size 1.27 0.9652)
					(thickness 0.000001)
				)
				(justify left)
			)
		)
		(duplicate_pad_numbers_are_jumpers no)
		(fp_poly
			(pts
				(xy 0.635 1.0668) (xy 0.635 -1.0668) (xy -0.635 -1.0668) (xy -0.635 1.0668)
			)
			(stroke
				(width 0)
				(type default)
			)
			(fill no)
			(layer "F.CrtYd")
		)
		(fp_line
			(start 0.254 0.508)
			(end -0.254 0.508)
			(stroke
				(width 0.0254)
				(type default)
			)
			(layer "F.Fab")
		)
		(fp_line
			(start 0.254 -0.508)
			(end 0.254 0.508)
			(stroke
				(width 0.0254)
				(type default)
			)
			(layer "F.Fab")
		)
		(fp_line
			(start -0.254 0.508)
			(end -0.254 -0.508)
			(stroke
				(width 0.0254)
				(type default)
			)
			(layer "F.Fab")
		)
		(fp_line
			(start -0.254 -0.508)
			(end 0.254 -0.508)
			(stroke
				(width 0.0254)
				(type default)
			)
			(layer "F.Fab")
		)
		(pad "1" smd rect
			(at 0 -0.4191 180)
			(size 0.508 0.5334)
			(layers "F.Cu" "F.Mask" "F.Paste")
			(net "EXT_3.3V_THRESHOLD")
		)
		(pad "2" smd rect
			(at 0 0.4191 180)
			(size 0.508 0.5334)
			(layers "F.Cu" "F.Mask" "F.Paste")
			(net "EXT_3.3V_PGOOD")
		)
		(zone
			(layer "F.Cu")
			(hatch none 0.5)
			(connect_pads
				(clearance 0)
			)
			(min_thickness 0.25)
			(keepout
				(tracks not_allowed)
				(vias allowed)
				(pads allowed)
				(copperpour not_allowed)
				(footprints allowed)
			)
			(placement
				(enabled no)
				(sheetname "")
			)
			(fill
				(thermal_gap 0.5)
				(thermal_bridge_width 0.5)
				(island_removal_mode 0)
			)
			(polygon
				(pts
					(xy 49.5046 50.0634) (xy 49.5046 50.0126) (xy 49.5554 50.0126) (xy 49.5554 50.0634)
				)
			)
		)
	)
	(footprint ""
		(layer "F.Cu")
		(at 30.48 44.323 180)
		(property "Reference" "C49"
			(at 0 0 180)
			(layer "F.SilkS")
			(hide yes)
			(effects
				(font
					(size 1.27 1.27)
				)
			)
		)
		(property "Value" "1000PF"
			(at -0.091846 0.2921 270)
			(unlocked yes)
			(layer "F.Fab")
			(hide yes)
			(effects
				(font
					(size 0.7874 0.5842)
					(thickness 0.2032)
				)
				(justify left)
			)
		)
		(property "Device Type" "CAPC0083"
			(at -0.091846 0.2921 270)
			(unlocked yes)
			(layer "F.Fab")
			(hide yes)
			(effects
				(font
					(size 0.7874 0.5842)
					(thickness 0.2032)
				)
				(justify left)
			)
		)
		(duplicate_pad_numbers_are_jumpers no)
		(fp_poly
			(pts
				(xy 0.635 1.0668) (xy 0.635 -1.0668) (xy -0.635 -1.0668) (xy -0.635 1.0668)
			)
			(stroke
				(width 0)
				(type default)
			)
			(fill no)
			(layer "F.CrtYd")
		)
		(fp_line
			(start 0.254 0.508)
			(end -0.254 0.508)
			(stroke
				(width 0.0254)
				(type default)
			)
			(layer "F.Fab")
		)
		(fp_line
			(start 0.254 -0.508)
			(end 0.254 0.508)
			(stroke
				(width 0.0254)
				(type default)
			)
			(layer "F.Fab")
		)
		(fp_line
			(start -0.254 0.508)
			(end -0.254 -0.508)
			(stroke
				(width 0.0254)
				(type default)
			)
			(layer "F.Fab")
		)
		(fp_line
			(start -0.254 -0.508)
			(end 0.254 -0.508)
			(stroke
				(width 0.0254)
				(type default)
			)
			(layer "F.Fab")
		)
		(pad "1" smd rect
			(at 0 -0.4191 180)
			(size 0.508 0.5334)
			(layers "F.Cu" "F.Mask" "F.Paste")
			(net "10N2504")
		)
		(pad "2" smd rect
			(at 0 0.4191 180)
			(size 0.508 0.5334)
			(layers "F.Cu" "F.Mask" "F.Paste")
			(net "10N2385")
		)
		(zone
			(layer "F.Cu")
			(hatch none 0.5)
			(connect_pads
				(clearance 0)
			)
			(min_thickness 0.25)
			(keepout
				(tracks not_allowed)
				(vias allowed)
				(pads allowed)
				(copperpour not_allowed)
				(footprints allowed)
			)
			(placement
				(enabled no)
				(sheetname "")
			)
			(fill
				(thermal_gap 0.5)
				(thermal_bridge_width 0.5)
				(island_removal_mode 0)
			)
			(polygon
				(pts
					(xy 30.4546 44.3484) (xy 30.4546 44.2976) (xy 30.5054 44.2976) (xy 30.5054 44.3484)
				)
			)
		)
	)
	(footprint ""
		(layer "F.Cu")
		(at 73.914 45.72 180)
		(property "Reference" "R152"
			(at 0 0 180)
			(layer "F.SilkS")
			(hide yes)
			(effects
				(font
					(size 1.27 1.27)
				)
			)
		)
		(property "Value" "0"
			(at -0.148158 1.3462 270)
			(unlocked yes)
			(layer "F.Fab")
			(hide yes)
			(effects
				(font
					(size 1.27 0.9652)
					(thickness 0.000001)
				)
				(justify left)
			)
		)
		(property "Device Type" "REST1111"
			(at -0.148158 1.3462 270)
			(unlocked yes)
			(layer "F.Fab")
			(hide yes)
			(effects
				(font
					(size 1.27 0.9652)
					(thickness 0.000001)
				)
				(justify left)
			)
		)
		(duplicate_pad_numbers_are_jumpers no)
		(fp_poly
			(pts
				(xy 0.635 1.0668) (xy 0.635 -1.0668) (xy -0.635 -1.0668) (xy -0.635 1.0668)
			)
			(stroke
				(width 0)
				(type default)
			)
			(fill no)
			(layer "F.CrtYd")
		)
		(fp_line
			(start 0.254 0.508)
			(end -0.254 0.508)
			(stroke
				(width 0.0254)
				(type default)
			)
			(layer "F.Fab")
		)
		(fp_line
			(start 0.254 -0.508)
			(end 0.254 0.508)
			(stroke
				(width 0.0254)
				(type default)
			)
			(layer "F.Fab")
		)
		(fp_line
			(start -0.254 0.508)
			(end -0.254 -0.508)
			(stroke
				(width 0.0254)
				(type default)
			)
			(layer "F.Fab")
		)
		(fp_line
			(start -0.254 -0.508)
			(end 0.254 -0.508)
			(stroke
				(width 0.0254)
				(type default)
			)
			(layer "F.Fab")
		)
		(pad "1" smd rect
			(at 0 -0.4191 180)
			(size 0.508 0.5334)
			(layers "F.Cu" "F.Mask" "F.Paste")
			(net "MH_1")
		)
		(pad "2" smd rect
			(at 0 0.4191 180)
			(size 0.508 0.5334)
			(layers "F.Cu" "F.Mask" "F.Paste")
			(net "GND")
		)
		(zone
			(layer "F.Cu")
			(hatch none 0.5)
			(connect_pads
				(clearance 0)
			)
			(min_thickness 0.25)
			(keepout
				(tracks not_allowed)
				(vias allowed)
				(pads allowed)
				(copperpour not_allowed)
				(footprints allowed)
			)
			(placement
				(enabled no)
				(sheetname "")
			)
			(fill
				(thermal_gap 0.5)
				(thermal_bridge_width 0.5)
				(island_removal_mode 0)
			)
			(polygon
				(pts
					(xy 73.8886 45.7454) (xy 73.8886 45.6946) (xy 73.9394 45.6946) (xy 73.9394 45.7454)
				)
			)
		)
	)
	(footprint ""
		(layer "F.Cu")
		(at 73.05101 14.256004)
		(property "Reference" "V_A-DQ30"
			(at 0 0 0)
			(layer "F.SilkS")
			(hide yes)
			(effects
				(font
					(size 1.27 1.27)
				)
			)
		)
		(property "Value" ""
			(at 0 0 0)
			(layer "F.Fab")
			(effects
				(font
					(size 1.27 1.27)
				)
			)
		)
		(duplicate_pad_numbers_are_jumpers no)
		(pad "1" thru_hole circle
			(at 0 0)
			(size 0.762 0.762)
			(drill 0.20574)
			(layers "*.Cu" "*.Mask")
			(remove_unused_layers no)
			(net "DDR0_32A_DQ30")
			(clearance 0.127)
			(thermal_gap 0.127)
			(padstack
				(mode front_inner_back)
				(layer "Inner"
					(shape circle)
					(size 0.4572 0.4572)
					(clearance 0.1143)
				)
				(layer "B.Cu"
					(shape circle)
					(size 0.4572 0.4572)
					(clearance 0.1143)
				)
			)
		)
	)
	(footprint ""
		(layer "F.Cu")
		(at 45.847 49.022)
		(property "Reference" "U4"
			(at -4.191 1.67767 0)
			(unlocked yes)
			(layer "F.SilkS")
			(effects
				(font
					(size 0.7874 0.5842)
					(thickness 0.127)
				)
				(justify left)
			)
		)
		(property "Value" "*"
			(at -0.4826 0.486918 0)
			(unlocked yes)
			(layer "F.Fab")
			(hide yes)
			(effects
				(font
					(size 1.27 0.9652)
					(thickness 0.000001)
				)
				(justify left)
			)
		)
		(property "Device Type" "ICSO0127"
			(at -0.4826 0.486918 0)
			(unlocked yes)
			(layer "F.Fab")
			(hide yes)
			(effects
				(font
					(size 1.27 0.9652)
					(thickness 0.000001)
				)
				(justify left)
			)
		)
		(duplicate_pad_numbers_are_jumpers no)
		(fp_line
			(start -1.905 -1.905)
			(end 0.6096 -1.905)
			(stroke
				(width 0.2032)
				(type default)
			)
			(layer "F.SilkS")
		)
		(fp_line
			(start -1.905 -1.905)
			(end 1.905 -1.905)
			(stroke
				(width 0.2032)
				(type default)
			)
			(layer "F.SilkS")
		)
		(fp_line
			(start -1.905 -1.524)
			(end -1.905 -1.905)
			(stroke
				(width 0.2032)
				(type default)
			)
			(layer "F.SilkS")
		)
		(fp_line
			(start -1.905 1.524)
			(end -1.905 1.905)
			(stroke
				(width 0.2032)
				(type default)
			)
			(layer "F.SilkS")
		)
		(fp_line
			(start -1.905 1.905)
			(end 1.905 1.905)
			(stroke
				(width 0.2032)
				(type default)
			)
			(layer "F.SilkS")
		)
		(fp_line
			(start -0.508 -1.27)
			(end -0.508 -1.905)
			(stroke
				(width 0.2032)
				(type default)
			)
			(layer "F.SilkS")
		)
		(fp_line
			(start 0.508 -1.905)
			(end 0.508 -1.27)
			(stroke
				(width 0.2032)
				(type default)
			)
			(layer "F.SilkS")
		)
		(fp_line
			(start 0.508 -1.27)
			(end -0.508 -1.27)
			(stroke
				(width 0.2032)
				(type default)
			)
			(layer "F.SilkS")
		)
		(fp_line
			(start 0.7366 1.905)
			(end 1.604848 1.905)
			(stroke
				(width 0.2032)
				(type default)
			)
			(layer "F.SilkS")
		)
		(fp_line
			(start 1.905 -1.905)
			(end 1.905 -1.524)
			(stroke
				(width 0.2032)
				(type default)
			)
			(layer "F.SilkS")
		)
		(fp_line
			(start 1.905 1.905)
			(end 1.905 1.524)
			(stroke
				(width 0.2032)
				(type default)
			)
			(layer "F.SilkS")
		)
		(fp_arc
			(start -2.588666 -1.944776)
			(mid -2.552041 -1.953028)
			(end -2.5146 -1.9558)
			(stroke
				(width 0.2032)
				(type default)
			)
			(layer "F.SilkS")
		)
		(fp_arc
			(start -2.5146 -1.9558)
			(mid -2.334995 -1.881405)
			(end -2.2606 -1.7018)
			(stroke
				(width 0.2032)
				(type default)
			)
			(layer "F.SilkS")
		)
		(fp_arc
			(start -2.2606 -1.7018)
			(mid -2.276949 -1.612226)
			(end -2.323821 -1.53416)
			(stroke
				(width 0.2032)
				(type default)
			)
			(layer "F.SilkS")
		)
		(fp_circle
			(center -2.5146 -1.7018)
			(end -2.2606 -1.7018)
			(stroke
				(width 0.2032)
				(type default)
			)
			(fill no)
			(layer "F.SilkS")
		)
		(fp_poly
			(pts
				(xy -2.159 -2.159) (xy 2.159 -2.159) (xy 2.159 -1.778) (xy 3.429 -1.778) (xy 3.429 1.778) (xy 2.159 1.778)
				(xy 2.159 2.159) (xy -2.159 2.159) (xy -2.159 1.778) (xy -3.429 1.778) (xy -3.429 -1.778) (xy -2.159 -1.778)
			)
			(stroke
				(width 0)
				(type default)
			)
			(fill no)
			(layer "F.CrtYd")
		)
		(fp_line
			(start -1.6002 -1.6002)
			(end -1.6002 1.6002)
			(stroke
				(width 0.2032)
				(type default)
			)
			(layer "F.Fab")
		)
		(fp_line
			(start -1.6002 1.6002)
			(end 1.6002 1.6002)
			(stroke
				(width 0.2032)
				(type default)
			)
			(layer "F.Fab")
		)
		(fp_line
			(start -0.508 -1.524)
			(end -0.508 -1.016)
			(stroke
				(width 0.2032)
				(type default)
			)
			(layer "F.Fab")
		)
		(fp_line
			(start -0.508 -1.016)
			(end 0.508 -1.016)
			(stroke
				(width 0.2032)
				(type default)
			)
			(layer "F.Fab")
		)
		(fp_line
			(start 0.508 -1.016)
			(end 0.508 -1.524)
			(stroke
				(width 0.2032)
				(type default)
			)
			(layer "F.Fab")
		)
		(fp_line
			(start 1.6002 -1.6002)
			(end -1.6002 -1.6002)
			(stroke
				(width 0.2032)
				(type default)
			)
			(layer "F.Fab")
		)
		(fp_line
			(start 1.6002 1.6002)
			(end 1.6002 -1.6002)
			(stroke
				(width 0.2032)
				(type default)
			)
			(layer "F.Fab")
		)
		(fp_circle
			(center -1.143 -1.143)
			(end -0.889 -1.143)
			(stroke
				(width 0.2032)
				(type default)
			)
			(fill no)
			(layer "F.Fab")
		)
		(pad "1" smd rect
			(at -2.159 -0.97536)
			(size 1.524 0.4064)
			(layers "F.Cu" "F.Mask" "F.Paste")
			(net "EXT_12.0V_PGOOD")
		)
		(pad "2" smd rect
			(at -2.159 -0.32512)
			(size 1.524 0.4064)
			(layers "F.Cu" "F.Mask" "F.Paste")
			(net "0.7V_REF")
		)
		(pad "3" smd rect
			(at -2.159 0.32512)
			(size 1.524 0.4064)
			(layers "F.Cu" "F.Mask" "F.Paste")
			(net "EXT_12.0V_THRESHOLD")
		)
		(pad "4" smd rect
			(at -2.159 0.97536)
			(size 1.524 0.4064)
			(layers "F.Cu" "F.Mask" "F.Paste")
			(net "GND")
		)
		(pad "5" smd rect
			(at 2.159 0.97536)
			(size 1.524 0.4064)
			(layers "F.Cu" "F.Mask" "F.Paste")
			(net "EXT_3.3V_THRESHOLD")
		)
		(pad "6" smd rect
			(at 2.159 0.32512)
			(size 1.524 0.4064)
			(layers "F.Cu" "F.Mask" "F.Paste")
			(net "0.7V_REF")
		)
		(pad "7" smd rect
			(at 2.159 -0.32512)
			(size 1.524 0.4064)
			(layers "F.Cu" "F.Mask" "F.Paste")
			(net "EXT_3.3V_PGOOD")
		)
		(pad "8" smd rect
			(at 2.159 -0.97536)
			(size 1.524 0.4064)
			(layers "F.Cu" "F.Mask" "F.Paste")
			(net "EXT_3.3V")
		)
	)
	(footprint ""
		(layer "F.Cu")
		(at 75.8952 44.577 -90)
		(property "Reference" "TP51"
			(at 0 0 270)
			(layer "F.SilkS")
			(hide yes)
			(effects
				(font
					(size 1.27 1.27)
				)
			)
		)
		(property "Value" "*"
			(at -0.4826 -0.14732 270)
			(unlocked yes)
			(layer "F.Fab")
			(hide yes)
			(effects
				(font
					(size 1.27 0.9652)
					(thickness 0.000001)
				)
				(justify left)
			)
		)
		(property "Device Type" "TP_SMALL"
			(at -0.4826 -0.14732 270)
			(unlocked yes)
			(layer "F.Fab")
			(hide yes)
			(effects
				(font
					(size 1.27 0.9652)
					(thickness 0.000001)
				)
				(justify left)
			)
		)
		(duplicate_pad_numbers_are_jumpers no)
		(fp_line
			(start -0.8636 0.8636)
			(end 0.8636 0.8636)
			(stroke
				(width 0.1524)
				(type default)
			)
			(layer "F.SilkS")
		)
		(fp_line
			(start 0.8636 0.8636)
			(end 0.8636 -0.8636)
			(stroke
				(width 0.1524)
				(type default)
			)
			(layer "F.SilkS")
		)
		(fp_line
			(start -0.8636 -0.8636)
			(end -0.8636 0.8636)
			(stroke
				(width 0.1524)
				(type default)
			)
			(layer "F.SilkS")
		)
		(fp_line
			(start 0.8636 -0.8636)
			(end -0.8636 -0.8636)
			(stroke
				(width 0.1524)
				(type default)
			)
			(layer "F.SilkS")
		)
		(fp_poly
			(pts
				(xy -0.635 -0.635) (xy -0.635 0.635) (xy 0.635 0.635) (xy 0.635 -0.635)
			)
			(stroke
				(width 0)
				(type default)
			)
			(fill no)
			(layer "F.CrtYd")
		)
		(pad "1" smd rect
			(at 0 0 270)
			(size 1.27 1.27)
			(layers "F.Cu" "F.Mask" "F.Paste")
			(net "GND")
		)
	)
	(footprint ""
		(layer "F.Cu")
		(at 28.575 8.255 90)
		(property "Reference" "R268"
			(at 0 0 90)
			(layer "F.SilkS")
			(hide yes)
			(effects
				(font
					(size 1.27 1.27)
				)
			)
		)
		(property "Value" "240"
			(at -0.148158 1.3462 180)
			(unlocked yes)
			(layer "F.Fab")
			(hide yes)
			(effects
				(font
					(size 1.27 0.9652)
					(thickness 0.000001)
				)
				(justify left)
			)
		)
		(property "Device Type" "REST0009"
			(at -0.148158 1.3462 180)
			(unlocked yes)
			(layer "F.Fab")
			(hide yes)
			(effects
				(font
					(size 1.27 0.9652)
					(thickness 0.000001)
				)
				(justify left)
			)
		)
		(duplicate_pad_numbers_are_jumpers no)
		(fp_poly
			(pts
				(xy 0.635 1.0668) (xy 0.635 -1.0668) (xy -0.635 -1.0668) (xy -0.635 1.0668)
			)
			(stroke
				(width 0)
				(type default)
			)
			(fill no)
			(layer "F.CrtYd")
		)
		(fp_line
			(start 0.254 -0.508)
			(end 0.254 0.508)
			(stroke
				(width 0.0254)
				(type default)
			)
			(layer "F.Fab")
		)
		(fp_line
			(start -0.254 -0.508)
			(end 0.254 -0.508)
			(stroke
				(width 0.0254)
				(type default)
			)
			(layer "F.Fab")
		)
		(fp_line
			(start 0.254 0.508)
			(end -0.254 0.508)
			(stroke
				(width 0.0254)
				(type default)
			)
			(layer "F.Fab")
		)
		(fp_line
			(start -0.254 0.508)
			(end -0.254 -0.508)
			(stroke
				(width 0.0254)
				(type default)
			)
			(layer "F.Fab")
		)
		(pad "1" smd rect
			(at 0 -0.4191 90)
			(size 0.508 0.5334)
			(layers "F.Cu" "F.Mask" "F.Paste")
			(net "NFP_REF_CLK_100M_EN")
		)
		(pad "2" smd rect
			(at 0 0.4191 90)
			(size 0.508 0.5334)
			(layers "F.Cu" "F.Mask" "F.Paste")
			(net "3N2284")
		)
		(zone
			(layer "F.Cu")
			(hatch none 0.5)
			(connect_pads
				(clearance 0)
			)
			(min_thickness 0.25)
			(keepout
				(tracks not_allowed)
				(vias allowed)
				(pads allowed)
				(copperpour not_allowed)
				(footprints allowed)
			)
			(placement
				(enabled no)
				(sheetname "")
			)
			(fill
				(thermal_gap 0.5)
				(thermal_bridge_width 0.5)
				(island_removal_mode 0)
			)
			(polygon
				(pts
					(xy 28.5496 8.2296) (xy 28.6004 8.2296) (xy 28.6004 8.2804) (xy 28.5496 8.2804)
				)
			)
		)
	)
	(footprint ""
		(layer "F.Cu")
		(at 16.256 33.3375 90)
		(property "Reference" "C141"
			(at -3.429 1.16967 90)
			(unlocked yes)
			(layer "F.SilkS")
			(effects
				(font
					(size 0.7874 0.5842)
					(thickness 0.127)
				)
				(justify left)
			)
		)
		(property "Value" "10UF"
			(at -0.148158 1.7526 180)
			(unlocked yes)
			(layer "F.Fab")
			(hide yes)
			(effects
				(font
					(size 1.27 0.9652)
					(thickness 0.000001)
				)
				(justify left)
			)
		)
		(property "Device Type" "CAPC0058"
			(at -0.148158 1.7526 180)
			(unlocked yes)
			(layer "F.Fab")
			(hide yes)
			(effects
				(font
					(size 1.27 0.9652)
					(thickness 0.000001)
				)
				(justify left)
			)
		)
		(duplicate_pad_numbers_are_jumpers no)
		(fp_circle
			(center 0 0)
			(end 0 0.127)
			(stroke
				(width 0.2032)
				(type default)
			)
			(fill no)
			(layer "F.SilkS")
		)
		(fp_poly
			(pts
				(xy 0.7874 -1.6637) (xy -0.7874 -1.6637) (xy -0.7874 1.6637) (xy 0.7874 1.6637)
			)
			(stroke
				(width 0)
				(type default)
			)
			(fill no)
			(layer "F.CrtYd")
		)
		(fp_line
			(start 0.4064 -0.7874)
			(end 0.4064 0.8128)
			(stroke
				(width 0.0254)
				(type default)
			)
			(layer "F.Fab")
		)
		(fp_line
			(start -0.4064 -0.7874)
			(end 0.4064 -0.7874)
			(stroke
				(width 0.0254)
				(type default)
			)
			(layer "F.Fab")
		)
		(fp_line
			(start 0.4064 0.8128)
			(end -0.4064 0.8128)
			(stroke
				(width 0.0254)
				(type default)
			)
			(layer "F.Fab")
		)
		(fp_line
			(start -0.4064 0.8128)
			(end -0.4064 -0.7874)
			(stroke
				(width 0.0254)
				(type default)
			)
			(layer "F.Fab")
		)
		(pad "1" smd rect
			(at 0 -0.8001 90)
			(size 0.8636 0.9652)
			(layers "F.Cu" "F.Mask" "F.Paste")
			(net "VDD_5.0V")
		)
		(pad "2" smd rect
			(at 0 0.8001 90)
			(size 0.8636 0.9652)
			(layers "F.Cu" "F.Mask" "F.Paste")
			(net "GND")
		)
	)
	(footprint ""
		(layer "F.Cu")
		(at 44.831 43.307)
		(property "Reference" "C59"
			(at 0.28067 -2.794 90)
			(unlocked yes)
			(layer "F.SilkS")
			(effects
				(font
					(size 0.7874 0.5842)
					(thickness 0.127)
				)
				(justify left)
			)
		)
		(property "Value" "100UF"
			(at -0.78232 0.4826 90)
			(unlocked yes)
			(layer "F.Fab")
			(hide yes)
			(effects
				(font
					(size 1.27 0.9652)
					(thickness 0.000001)
				)
				(justify left)
			)
		)
		(property "Device Type" "CAPC0087"
			(at -0.78232 0.4826 90)
			(unlocked yes)
			(layer "F.Fab")
			(hide yes)
			(effects
				(font
					(size 1.27 0.9652)
					(thickness 0.000001)
				)
				(justify left)
			)
		)
		(duplicate_pad_numbers_are_jumpers no)
		(fp_circle
			(center 0 0)
			(end 0.508 0)
			(stroke
				(width 0.2032)
				(type default)
			)
			(fill no)
			(layer "F.SilkS")
		)
		(fp_circle
			(center 0 0)
			(end 0.508 0)
			(stroke
				(width 0.2032)
				(type default)
			)
			(fill no)
			(layer "F.SilkS")
		)
		(fp_poly
			(pts
				(xy -1.27 2.9464) (xy 1.27 2.9464) (xy 1.27 -2.9464) (xy -1.27 -2.9464)
			)
			(stroke
				(width 0)
				(type default)
			)
			(fill no)
			(layer "F.CrtYd")
		)
		(fp_line
			(start -1.016 -2.794)
			(end 1.016 -2.794)
			(stroke
				(width 0.0254)
				(type default)
			)
			(layer "F.Fab")
		)
		(fp_line
			(start -1.016 2.794)
			(end -1.016 -2.794)
			(stroke
				(width 0.0254)
				(type default)
			)
			(layer "F.Fab")
		)
		(fp_line
			(start 1.016 -2.794)
			(end 1.016 2.794)
			(stroke
				(width 0.0254)
				(type default)
			)
			(layer "F.Fab")
		)
		(fp_line
			(start 1.016 2.794)
			(end -1.016 2.794)
			(stroke
				(width 0.0254)
				(type default)
			)
			(layer "F.Fab")
		)
		(pad "1" smd rect
			(at 0 -1.6764)
			(size 1.524 1.524)
			(layers "F.Cu" "F.Mask" "F.Paste")
			(net "VDD_CORE")
		)
		(pad "2" smd rect
			(at 0 1.6764)
			(size 1.524 1.524)
			(layers "F.Cu" "F.Mask" "F.Paste")
			(net "GND")
		)
		(zone
			(layer "F.Cu")
			(hatch none 0.5)
			(connect_pads
				(clearance 0)
			)
			(min_thickness 0.25)
			(keepout
				(tracks not_allowed)
				(vias allowed)
				(pads allowed)
				(copperpour not_allowed)
				(footprints allowed)
			)
			(placement
				(enabled no)
				(sheetname "")
			)
			(fill
				(thermal_gap 0.5)
				(thermal_bridge_width 0.5)
				(island_removal_mode 0)
			)
			(polygon
				(pts
					(xy 44.0436 42.418) (xy 45.6184 42.418) (xy 45.6184 42.5704) (xy 44.0436 42.5704)
				)
			)
		)
		(zone
			(layer "F.Cu")
			(hatch none 0.5)
			(connect_pads
				(clearance 0)
			)
			(min_thickness 0.25)
			(keepout
				(tracks not_allowed)
				(vias allowed)
				(pads allowed)
				(copperpour not_allowed)
				(footprints allowed)
			)
			(placement
				(enabled no)
				(sheetname "")
			)
			(fill
				(thermal_gap 0.5)
				(thermal_bridge_width 0.5)
				(island_removal_mode 0)
			)
			(polygon
				(pts
					(xy 44.0436 44.0436) (xy 45.6184 44.0436) (xy 45.6184 44.196) (xy 44.0436 44.196)
				)
			)
		)
		(zone
			(layer "F.Cu")
			(hatch none 0.5)
			(connect_pads
				(clearance 0)
			)
			(min_thickness 0.25)
			(keepout
				(tracks allowed)
				(vias not_allowed)
				(pads allowed)
				(copperpour not_allowed)
				(footprints allowed)
			)
			(placement
				(enabled no)
				(sheetname "")
			)
			(fill
				(thermal_gap 0.5)
				(thermal_bridge_width 0.5)
				(island_removal_mode 0)
			)
			(polygon
				(pts
					(xy 44.0436 44.9072) (xy 45.6184 44.9072) (xy 45.6184 41.7068) (xy 44.0436 41.7068)
				)
			)
		)
	)
	(footprint ""
		(layer "F.Cu")
		(at 22.987 37.592 -90)
		(property "Reference" "C142"
			(at 0.78867 5.08 0)
			(unlocked yes)
			(layer "F.SilkS")
			(effects
				(font
					(size 0.7874 0.5842)
					(thickness 0.127)
				)
				(justify left)
			)
		)
		(property "Value" "4.7UF"
			(at -0.783158 2.3876 0)
			(unlocked yes)
			(layer "F.Fab")
			(hide yes)
			(effects
				(font
					(size 1.27 0.9652)
					(thickness 0.000001)
				)
				(justify left)
			)
		)
		(property "Device Type" "CAPC0029"
			(at -0.783158 2.3876 0)
			(unlocked yes)
			(layer "F.Fab")
			(hide yes)
			(effects
				(font
					(size 1.27 0.9652)
					(thickness 0.000001)
				)
				(justify left)
			)
		)
		(duplicate_pad_numbers_are_jumpers no)
		(fp_arc
			(start -0.156058 0.0889)
			(mid -0.173617 0.045983)
			(end -0.179603 0)
			(stroke
				(width 0.2032)
				(type default)
			)
			(layer "F.SilkS")
		)
		(fp_arc
			(start -0.179603 0)
			(mid -0.173617 -0.045983)
			(end -0.156058 -0.0889)
			(stroke
				(width 0.2032)
				(type default)
			)
			(layer "F.SilkS")
		)
		(fp_arc
			(start 0.179603 0)
			(mid 0.173617 0.045983)
			(end 0.156058 0.0889)
			(stroke
				(width 0.2032)
				(type default)
			)
			(layer "F.SilkS")
		)
		(fp_arc
			(start 0.156058 -0.0889)
			(mid 0.173617 -0.045983)
			(end 0.179603 0)
			(stroke
				(width 0.2032)
				(type default)
			)
			(layer "F.SilkS")
		)
		(fp_circle
			(center 0 0)
			(end 0 -0.179603)
			(stroke
				(width 0.2032)
				(type default)
			)
			(fill no)
			(layer "F.SilkS")
		)
		(fp_poly
			(pts
				(xy -1.2192 2.3495) (xy 1.2192 2.3495) (xy 1.2192 -2.3495) (xy -1.2192 -2.3495)
			)
			(stroke
				(width 0)
				(type default)
			)
			(fill no)
			(layer "F.CrtYd")
		)
		(fp_line
			(start -0.762 1.143)
			(end -0.762 -1.143)
			(stroke
				(width 0.0254)
				(type default)
			)
			(layer "F.Fab")
		)
		(fp_line
			(start 0.762 1.143)
			(end -0.762 1.143)
			(stroke
				(width 0.0254)
				(type default)
			)
			(layer "F.Fab")
		)
		(fp_line
			(start -0.762 -1.143)
			(end 0.762 -1.143)
			(stroke
				(width 0.0254)
				(type default)
			)
			(layer "F.Fab")
		)
		(fp_line
			(start 0.762 -1.143)
			(end 0.762 1.143)
			(stroke
				(width 0.0254)
				(type default)
			)
			(layer "F.Fab")
		)
		(pad "1" smd rect
			(at 0 -1.143 270)
			(size 1.4224 1.397)
			(layers "F.Cu" "F.Mask" "F.Paste")
			(net "10N2412")
		)
		(pad "2" smd rect
			(at 0 1.143 270)
			(size 1.4224 1.397)
			(layers "F.Cu" "F.Mask" "F.Paste")
			(net "GND")
		)
		(zone
			(layer "F.Cu")
			(hatch none 0.5)
			(connect_pads
				(clearance 0)
			)
			(min_thickness 0.25)
			(keepout
				(tracks allowed)
				(vias not_allowed)
				(pads allowed)
				(copperpour not_allowed)
				(footprints allowed)
			)
			(placement
				(enabled no)
				(sheetname "")
			)
			(fill
				(thermal_gap 0.5)
				(thermal_bridge_width 0.5)
				(island_removal_mode 0)
			)
			(polygon
				(pts
					(xy 23.368 36.957) (xy 23.368 38.227) (xy 22.606 38.227) (xy 22.606 36.957)
				)
			)
		)
	)
	(footprint ""
		(layer "F.Cu")
		(at 32.639 6.35 90)
		(property "Reference" "U14"
			(at 1.016 -2.64033 90)
			(unlocked yes)
			(layer "F.SilkS")
			(effects
				(font
					(size 0.7874 0.5842)
					(thickness 0.127)
				)
				(justify left)
			)
		)
		(property "Value" "*"
			(at -0.4826 0.867842 90)
			(unlocked yes)
			(layer "F.Fab")
			(hide yes)
			(effects
				(font
					(size 1.27 0.9652)
					(thickness 0.000001)
				)
				(justify left)
			)
		)
		(property "Device Type" "ICSO0125"
			(at -0.4826 0.867893 90)
			(unlocked yes)
			(layer "F.Fab")
			(hide yes)
			(effects
				(font
					(size 1.27 0.9652)
					(thickness 0.000001)
				)
				(justify left)
			)
		)
		(duplicate_pad_numbers_are_jumpers no)
		(fp_line
			(start 2.794 -1.905)
			(end 2.794 -1.27)
			(stroke
				(width 0.1524)
				(type default)
			)
			(layer "F.SilkS")
		)
		(fp_line
			(start 2.794 -1.905)
			(end 2.794 -1.27)
			(stroke
				(width 0.1524)
				(type default)
			)
			(layer "F.SilkS")
		)
		(fp_line
			(start 1.778 -1.905)
			(end 2.794 -1.905)
			(stroke
				(width 0.1524)
				(type default)
			)
			(layer "F.SilkS")
		)
		(fp_line
			(start 1.778 -1.905)
			(end 2.794 -1.905)
			(stroke
				(width 0.1524)
				(type default)
			)
			(layer "F.SilkS")
		)
		(fp_line
			(start -1.778 -1.905)
			(end -2.794 -1.905)
			(stroke
				(width 0.1524)
				(type default)
			)
			(layer "F.SilkS")
		)
		(fp_line
			(start -1.778 -1.905)
			(end -2.794 -1.905)
			(stroke
				(width 0.1524)
				(type default)
			)
			(layer "F.SilkS")
		)
		(fp_line
			(start -2.413 -1.905)
			(end -2.794 -1.524)
			(stroke
				(width 0.1524)
				(type default)
			)
			(layer "F.SilkS")
		)
		(fp_line
			(start -2.794 -1.905)
			(end -2.794 -1.27)
			(stroke
				(width 0.1524)
				(type default)
			)
			(layer "F.SilkS")
		)
		(fp_line
			(start -2.794 -1.905)
			(end -2.794 -1.27)
			(stroke
				(width 0.1524)
				(type default)
			)
			(layer "F.SilkS")
		)
		(fp_line
			(start 2.794 1.905)
			(end 2.794 1.27)
			(stroke
				(width 0.1524)
				(type default)
			)
			(layer "F.SilkS")
		)
		(fp_line
			(start 2.794 1.905)
			(end 2.794 1.27)
			(stroke
				(width 0.1524)
				(type default)
			)
			(layer "F.SilkS")
		)
		(fp_line
			(start 1.778 1.905)
			(end 2.794 1.905)
			(stroke
				(width 0.1524)
				(type default)
			)
			(layer "F.SilkS")
		)
		(fp_line
			(start 1.778 1.905)
			(end 2.794 1.905)
			(stroke
				(width 0.1524)
				(type default)
			)
			(layer "F.SilkS")
		)
		(fp_line
			(start -1.778 1.905)
			(end -2.794 1.905)
			(stroke
				(width 0.1524)
				(type default)
			)
			(layer "F.SilkS")
		)
		(fp_line
			(start -1.778 1.905)
			(end -2.794 1.905)
			(stroke
				(width 0.1524)
				(type default)
			)
			(layer "F.SilkS")
		)
		(fp_line
			(start -2.794 1.905)
			(end -2.794 1.27)
			(stroke
				(width 0.1524)
				(type default)
			)
			(layer "F.SilkS")
		)
		(fp_line
			(start -2.794 1.905)
			(end -2.794 1.27)
			(stroke
				(width 0.1524)
				(type default)
			)
			(layer "F.SilkS")
		)
		(fp_arc
			(start -3.2258 -1.4732)
			(mid -3.046446 -1.399056)
			(end -2.971775 -1.219911)
			(stroke
				(width 0.1524)
				(type default)
			)
			(layer "F.SilkS")
		)
		(fp_arc
			(start -3.4798 -1.2192)
			(mid -3.405405 -1.398805)
			(end -3.2258 -1.4732)
			(stroke
				(width 0.1524)
				(type default)
			)
			(layer "F.SilkS")
		)
		(fp_arc
			(start -3.1877 -0.96807)
			(mid -3.206696 -0.965917)
			(end -3.2258 -0.9652)
			(stroke
				(width 0.1524)
				(type default)
			)
			(layer "F.SilkS")
		)
		(fp_arc
			(start -3.2258 -0.9652)
			(mid -3.405405 -1.039595)
			(end -3.4798 -1.2192)
			(stroke
				(width 0.1524)
				(type default)
			)
			(layer "F.SilkS")
		)
		(fp_circle
			(center -3.2258 -1.2192)
			(end -3.2258 -0.9652)
			(stroke
				(width 0.1524)
				(type default)
			)
			(fill no)
			(layer "F.SilkS")
		)
		(fp_poly
			(pts
				(xy 1.7526 -0.8636) (xy 1.7526 -0.1524) (xy 0.1524 -0.1524) (xy 0.1524 -0.8636)
			)
			(stroke
				(width 0)
				(type default)
			)
			(fill yes)
			(layer "F.Paste")
		)
		(fp_poly
			(pts
				(xy -1.7526 -0.8636) (xy -1.7526 -0.1524) (xy -0.1524 -0.1524) (xy -0.1524 -0.8636)
			)
			(stroke
				(width 0)
				(type default)
			)
			(fill yes)
			(layer "F.Paste")
		)
		(fp_poly
			(pts
				(xy 1.7526 0.8636) (xy 1.7526 0.1524) (xy 0.1524 0.1524) (xy 0.1524 0.8636)
			)
			(stroke
				(width 0)
				(type default)
			)
			(fill yes)
			(layer "F.Paste")
		)
		(fp_poly
			(pts
				(xy -1.7526 0.8636) (xy -1.7526 0.1524) (xy -0.1524 0.1524) (xy -0.1524 0.8636)
			)
			(stroke
				(width 0)
				(type default)
			)
			(fill yes)
			(layer "F.Paste")
		)
		(fp_poly
			(pts
				(xy -3.429 -2.54) (xy -3.429 2.54) (xy 3.429 2.54) (xy 3.429 -1.810487) (xy 1.859432 -1.810487)
				(xy 1.129919 -2.54)
			)
			(stroke
				(width 0)
				(type default)
			)
			(fill no)
			(layer "F.CrtYd")
		)
		(fp_line
			(start 2.5527 -1.651)
			(end -2.5527 -1.651)
			(stroke
				(width 0.1524)
				(type default)
			)
			(layer "F.Fab")
		)
		(fp_line
			(start -2.5527 -1.651)
			(end -2.5527 1.651)
			(stroke
				(width 0.1524)
				(type default)
			)
			(layer "F.Fab")
		)
		(fp_line
			(start -1.9177 -1.6383)
			(end -2.5527 -1.0033)
			(stroke
				(width 0.1524)
				(type default)
			)
			(layer "F.Fab")
		)
		(fp_line
			(start 2.5527 1.651)
			(end 2.5527 -1.651)
			(stroke
				(width 0.1524)
				(type default)
			)
			(layer "F.Fab")
		)
		(fp_line
			(start -2.5527 1.651)
			(end 2.5527 1.651)
			(stroke
				(width 0.1524)
				(type default)
			)
			(layer "F.Fab")
		)
		(fp_circle
			(center -1.9304 -0.889)
			(end -1.9304 -0.605003)
			(stroke
				(width 0.1524)
				(type default)
			)
			(fill no)
			(layer "F.Fab")
		)
		(pad "1" smd rect
			(at -2.5273 -0.750011 180)
			(size 0.2794 0.6604)
			(layers "F.Cu" "F.Mask" "F.Paste")
			(net "3N2284")
		)
		(pad "2" smd rect
			(at -2.5273 -0.250012 180)
			(size 0.2794 0.6604)
			(layers "F.Cu" "F.Mask" "F.Paste")
			(net "_NC_CLK_NC1")
		)
		(pad "3" smd rect
			(at -2.5273 0.250012 180)
			(size 0.2794 0.6604)
			(layers "F.Cu" "F.Mask" "F.Paste")
			(net "GND")
		)
		(pad "4" smd rect
			(at -2.5273 0.750011 180)
			(size 0.2794 0.6604)
			(layers "F.Cu" "F.Mask" "F.Paste")
			(net "GND")
		)
		(pad "5" smd rect
			(at -1.25001 1.6256 90)
			(size 0.2794 0.6604)
			(layers "F.Cu" "F.Mask" "F.Paste")
			(net "3N2301")
		)
		(pad "6" smd rect
			(at -0.750011 1.6256 90)
			(size 0.2794 0.6604)
			(layers "F.Cu" "F.Mask" "F.Paste")
			(net "3N2302")
		)
		(pad "7" smd rect
			(at -0.250012 1.6256 90)
			(size 0.2794 0.6604)
			(layers "F.Cu" "F.Mask" "F.Paste")
			(net "3N2290")
		)
		(pad "8" smd rect
			(at 0.250012 1.6256 90)
			(size 0.2794 0.6604)
			(layers "F.Cu" "F.Mask" "F.Paste")
			(net "3N2291")
		)
		(pad "9" smd rect
			(at 0.750011 1.6256 90)
			(size 0.2794 0.6604)
			(layers "F.Cu" "F.Mask" "F.Paste")
			(net "EXT_3.3V")
		)
		(pad "10" smd rect
			(at 1.25001 1.6256 90)
			(size 0.2794 0.6604)
			(layers "F.Cu" "F.Mask" "F.Paste")
			(net "3N2287")
		)
		(pad "11" smd rect
			(at 2.5273 0.750011 180)
			(size 0.2794 0.6604)
			(layers "F.Cu" "F.Mask" "F.Paste")
			(net "3N2285")
		)
		(pad "12" smd rect
			(at 2.5273 0.250012 180)
			(size 0.2794 0.6604)
			(layers "F.Cu" "F.Mask" "F.Paste")
			(net "_NC_CLK_NC2")
		)
		(pad "13" smd rect
			(at 2.5273 -0.250012 180)
			(size 0.2794 0.6604)
			(layers "F.Cu" "F.Mask" "F.Paste")
			(net "GND")
		)
		(pad "14" smd rect
			(at 2.5273 -0.750011 180)
			(size 0.2794 0.6604)
			(layers "F.Cu" "F.Mask" "F.Paste")
			(net "GND")
		)
		(pad "15" smd rect
			(at 1.25001 -1.6256 90)
			(size 0.2794 0.6604)
			(layers "F.Cu" "F.Mask" "F.Paste")
			(net "_NC_156M_N")
		)
		(pad "16" smd rect
			(at 0.750011 -1.6256 90)
			(size 0.2794 0.6604)
			(layers "F.Cu" "F.Mask" "F.Paste")
			(net "_NC_156M_P")
		)
		(pad "17" smd rect
			(at 0.250012 -1.6256 90)
			(size 0.2794 0.6604)
			(layers "F.Cu" "F.Mask" "F.Paste")
			(net "_NC_CLK_NC3")
		)
		(pad "18" smd rect
			(at -0.250012 -1.6256 90)
			(size 0.2794 0.6604)
			(layers "F.Cu" "F.Mask" "F.Paste")
			(net "_NC_CLK_NC4")
		)
		(pad "19" smd rect
			(at -0.750011 -1.6256 90)
			(size 0.2794 0.6604)
			(layers "F.Cu" "F.Mask" "F.Paste")
			(net "EXT_3.3V")
		)
		(pad "20" smd rect
			(at -1.25001 -1.6256 90)
			(size 0.2794 0.6604)
			(layers "F.Cu" "F.Mask" "F.Paste")
			(net "3N2286")
		)
		(pad "21" smd rect
			(at 0 0 90)
			(size 3.7846 1.9812)
			(layers "F.Cu" "F.Mask" "F.Paste")
			(net "GND")
		)
		(zone
			(layer "F.Cu")
			(hatch none 0.5)
			(connect_pads
				(clearance 0)
			)
			(min_thickness 0.25)
			(keepout
				(tracks allowed)
				(vias not_allowed)
				(pads allowed)
				(copperpour not_allowed)
				(footprints allowed)
			)
			(placement
				(enabled no)
				(sheetname "")
			)
			(fill
				(thermal_gap 0.5)
				(thermal_bridge_width 0.5)
				(island_removal_mode 0)
			)
			(polygon
				(pts
					(arc
						(start 31.75 9.5758)
						(mid 31.0896 9.5758)
						(end 31.75 9.5758)
					)
				)
			)
		)
	)
	(footprint ""
		(layer "F.Cu")
		(at 36.322 38.1 90)
		(property "Reference" "R110"
			(at 0 0 90)
			(layer "F.SilkS")
			(hide yes)
			(effects
				(font
					(size 1.27 1.27)
				)
			)
		)
		(property "Value" "10"
			(at -0.148158 1.3462 180)
			(unlocked yes)
			(layer "F.Fab")
			(hide yes)
			(effects
				(font
					(size 1.27 0.9652)
					(thickness 0.000001)
				)
				(justify left)
			)
		)
		(property "Device Type" "REST0076"
			(at -0.148158 1.3462 180)
			(unlocked yes)
			(layer "F.Fab")
			(hide yes)
			(effects
				(font
					(size 1.27 0.9652)
					(thickness 0.000001)
				)
				(justify left)
			)
		)
		(duplicate_pad_numbers_are_jumpers no)
		(fp_poly
			(pts
				(xy 0.635 1.0668) (xy 0.635 -1.0668) (xy -0.635 -1.0668) (xy -0.635 1.0668)
			)
			(stroke
				(width 0)
				(type default)
			)
			(fill no)
			(layer "F.CrtYd")
		)
		(fp_line
			(start 0.254 -0.508)
			(end 0.254 0.508)
			(stroke
				(width 0.0254)
				(type default)
			)
			(layer "F.Fab")
		)
		(fp_line
			(start -0.254 -0.508)
			(end 0.254 -0.508)
			(stroke
				(width 0.0254)
				(type default)
			)
			(layer "F.Fab")
		)
		(fp_line
			(start 0.254 0.508)
			(end -0.254 0.508)
			(stroke
				(width 0.0254)
				(type default)
			)
			(layer "F.Fab")
		)
		(fp_line
			(start -0.254 0.508)
			(end -0.254 -0.508)
			(stroke
				(width 0.0254)
				(type default)
			)
			(layer "F.Fab")
		)
		(pad "1" smd rect
			(at 0 -0.4191 90)
			(size 0.508 0.5334)
			(layers "F.Cu" "F.Mask" "F.Paste")
			(net "10N2410")
		)
		(pad "2" smd rect
			(at 0 0.4191 90)
			(size 0.508 0.5334)
			(layers "F.Cu" "F.Mask" "F.Paste")
			(net "NFP_VDD_CORE_ISEN1_N")
		)
		(zone
			(layer "F.Cu")
			(hatch none 0.5)
			(connect_pads
				(clearance 0)
			)
			(min_thickness 0.25)
			(keepout
				(tracks not_allowed)
				(vias allowed)
				(pads allowed)
				(copperpour not_allowed)
				(footprints allowed)
			)
			(placement
				(enabled no)
				(sheetname "")
			)
			(fill
				(thermal_gap 0.5)
				(thermal_bridge_width 0.5)
				(island_removal_mode 0)
			)
			(polygon
				(pts
					(xy 36.2966 38.0746) (xy 36.3474 38.0746) (xy 36.3474 38.1254) (xy 36.2966 38.1254)
				)
			)
		)
	)
	(footprint ""
		(layer "F.Cu")
		(at 83.82 35.306)
		(property "Reference" "TP60"
			(at -2.286 -1.37033 0)
			(unlocked yes)
			(layer "F.SilkS")
			(effects
				(font
					(size 0.7874 0.5842)
					(thickness 0.127)
				)
				(justify left)
			)
		)
		(property "Value" "*"
			(at -0.4826 -0.14732 0)
			(unlocked yes)
			(layer "F.Fab")
			(hide yes)
			(effects
				(font
					(size 1.27 0.9652)
					(thickness 0.000001)
				)
				(justify left)
			)
		)
		(property "Device Type" "TP_SMALL"
			(at -0.4826 -0.14732 0)
			(unlocked yes)
			(layer "F.Fab")
			(hide yes)
			(effects
				(font
					(size 1.27 0.9652)
					(thickness 0.000001)
				)
				(justify left)
			)
		)
		(duplicate_pad_numbers_are_jumpers no)
		(fp_line
			(start -0.8636 -0.8636)
			(end -0.8636 0.8636)
			(stroke
				(width 0.1524)
				(type default)
			)
			(layer "F.SilkS")
		)
		(fp_line
			(start -0.8636 0.8636)
			(end 0.8636 0.8636)
			(stroke
				(width 0.1524)
				(type default)
			)
			(layer "F.SilkS")
		)
		(fp_line
			(start 0.8636 -0.8636)
			(end -0.8636 -0.8636)
			(stroke
				(width 0.1524)
				(type default)
			)
			(layer "F.SilkS")
		)
		(fp_line
			(start 0.8636 0.8636)
			(end 0.8636 -0.8636)
			(stroke
				(width 0.1524)
				(type default)
			)
			(layer "F.SilkS")
		)
		(fp_poly
			(pts
				(xy -0.635 -0.635) (xy -0.635 0.635) (xy 0.635 0.635) (xy 0.635 -0.635)
			)
			(stroke
				(width 0)
				(type default)
			)
			(fill no)
			(layer "F.CrtYd")
		)
		(pad "1" smd rect
			(at 0 0)
			(size 1.27 1.27)
			(layers "F.Cu" "F.Mask" "F.Paste")
			(net "VDDQ_VTT_PGOOD")
		)
	)
	(footprint ""
		(layer "F.Cu")
		(at 80.391 44.069 -90)
		(property "Reference" "R127"
			(at 0 0 270)
			(layer "F.SilkS")
			(hide yes)
			(effects
				(font
					(size 1.27 1.27)
				)
			)
		)
		(property "Value" "10K"
			(at -0.148158 1.3462 0)
			(unlocked yes)
			(layer "F.Fab")
			(hide yes)
			(effects
				(font
					(size 1.27 0.9652)
					(thickness 0.000001)
				)
				(justify left)
			)
		)
		(property "Device Type" "REST0005"
			(at -0.148158 1.3462 0)
			(unlocked yes)
			(layer "F.Fab")
			(hide yes)
			(effects
				(font
					(size 1.27 0.9652)
					(thickness 0.000001)
				)
				(justify left)
			)
		)
		(duplicate_pad_numbers_are_jumpers no)
		(fp_poly
			(pts
				(xy 0.635 1.0668) (xy 0.635 -1.0668) (xy -0.635 -1.0668) (xy -0.635 1.0668)
			)
			(stroke
				(width 0)
				(type default)
			)
			(fill no)
			(layer "F.CrtYd")
		)
		(fp_line
			(start -0.254 0.508)
			(end -0.254 -0.508)
			(stroke
				(width 0.0254)
				(type default)
			)
			(layer "F.Fab")
		)
		(fp_line
			(start 0.254 0.508)
			(end -0.254 0.508)
			(stroke
				(width 0.0254)
				(type default)
			)
			(layer "F.Fab")
		)
		(fp_line
			(start -0.254 -0.508)
			(end 0.254 -0.508)
			(stroke
				(width 0.0254)
				(type default)
			)
			(layer "F.Fab")
		)
		(fp_line
			(start 0.254 -0.508)
			(end 0.254 0.508)
			(stroke
				(width 0.0254)
				(type default)
			)
			(layer "F.Fab")
		)
		(pad "1" smd rect
			(at 0 -0.4191 270)
			(size 0.508 0.5334)
			(layers "F.Cu" "F.Mask" "F.Paste")
			(net "11N2146")
		)
		(pad "2" smd rect
			(at 0 0.4191 270)
			(size 0.508 0.5334)
			(layers "F.Cu" "F.Mask" "F.Paste")
			(net "11N2152")
		)
		(zone
			(layer "F.Cu")
			(hatch none 0.5)
			(connect_pads
				(clearance 0)
			)
			(min_thickness 0.25)
			(keepout
				(tracks not_allowed)
				(vias allowed)
				(pads allowed)
				(copperpour not_allowed)
				(footprints allowed)
			)
			(placement
				(enabled no)
				(sheetname "")
			)
			(fill
				(thermal_gap 0.5)
				(thermal_bridge_width 0.5)
				(island_removal_mode 0)
			)
			(polygon
				(pts
					(xy 80.4164 44.0944) (xy 80.3656 44.0944) (xy 80.3656 44.0436) (xy 80.4164 44.0436)
				)
			)
		)
	)
	(footprint ""
		(layer "F.Cu")
		(at 74.3712 28.575)
		(property "Reference" "C105"
			(at 0 0 0)
			(layer "F.SilkS")
			(hide yes)
			(effects
				(font
					(size 1.27 1.27)
				)
			)
		)
		(property "Value" "0.1UF"
			(at -0.091846 0.2921 90)
			(unlocked yes)
			(layer "F.Fab")
			(hide yes)
			(effects
				(font
					(size 0.7874 0.5842)
					(thickness 0.2032)
				)
				(justify left)
			)
		)
		(property "Device Type" "CAPC0073"
			(at -0.091846 0.2921 90)
			(unlocked yes)
			(layer "F.Fab")
			(hide yes)
			(effects
				(font
					(size 0.7874 0.5842)
					(thickness 0.2032)
				)
				(justify left)
			)
		)
		(duplicate_pad_numbers_are_jumpers no)
		(fp_poly
			(pts
				(xy 0.635 1.0668) (xy 0.635 -1.0668) (xy -0.635 -1.0668) (xy -0.635 1.0668)
			)
			(stroke
				(width 0)
				(type default)
			)
			(fill no)
			(layer "F.CrtYd")
		)
		(fp_line
			(start -0.254 -0.508)
			(end 0.254 -0.508)
			(stroke
				(width 0.0254)
				(type default)
			)
			(layer "F.Fab")
		)
		(fp_line
			(start -0.254 0.508)
			(end -0.254 -0.508)
			(stroke
				(width 0.0254)
				(type default)
			)
			(layer "F.Fab")
		)
		(fp_line
			(start 0.254 -0.508)
			(end 0.254 0.508)
			(stroke
				(width 0.0254)
				(type default)
			)
			(layer "F.Fab")
		)
		(fp_line
			(start 0.254 0.508)
			(end -0.254 0.508)
			(stroke
				(width 0.0254)
				(type default)
			)
			(layer "F.Fab")
		)
		(pad "1" smd rect
			(at 0 -0.4191)
			(size 0.508 0.5334)
			(layers "F.Cu" "F.Mask" "F.Paste")
			(net "6N4748")
		)
		(pad "2" smd rect
			(at 0 0.4191)
			(size 0.508 0.5334)
			(layers "F.Cu" "F.Mask" "F.Paste")
			(net "DDR_VDDQ")
		)
		(zone
			(layer "F.Cu")
			(hatch none 0.5)
			(connect_pads
				(clearance 0)
			)
			(min_thickness 0.25)
			(keepout
				(tracks not_allowed)
				(vias allowed)
				(pads allowed)
				(copperpour not_allowed)
				(footprints allowed)
			)
			(placement
				(enabled no)
				(sheetname "")
			)
			(fill
				(thermal_gap 0.5)
				(thermal_bridge_width 0.5)
				(island_removal_mode 0)
			)
			(polygon
				(pts
					(xy 74.3966 28.5496) (xy 74.3966 28.6004) (xy 74.3458 28.6004) (xy 74.3458 28.5496)
				)
			)
		)
	)
	(footprint ""
		(layer "F.Cu")
		(at 19.05 28.448 90)
		(property "Reference" "R68"
			(at 0 0 90)
			(layer "F.SilkS")
			(hide yes)
			(effects
				(font
					(size 1.27 1.27)
				)
			)
		)
		(property "Value" "4.75K"
			(at -0.148158 1.3462 180)
			(unlocked yes)
			(layer "F.Fab")
			(hide yes)
			(effects
				(font
					(size 1.27 0.9652)
					(thickness 0.000001)
				)
				(justify left)
			)
		)
		(property "Device Type" "REST4024"
			(at -0.148158 1.3462 180)
			(unlocked yes)
			(layer "F.Fab")
			(hide yes)
			(effects
				(font
					(size 1.27 0.9652)
					(thickness 0.000001)
				)
				(justify left)
			)
		)
		(duplicate_pad_numbers_are_jumpers no)
		(fp_poly
			(pts
				(xy 0.635 1.0668) (xy 0.635 -1.0668) (xy -0.635 -1.0668) (xy -0.635 1.0668)
			)
			(stroke
				(width 0)
				(type default)
			)
			(fill no)
			(layer "F.CrtYd")
		)
		(fp_line
			(start 0.254 -0.508)
			(end 0.254 0.508)
			(stroke
				(width 0.0254)
				(type default)
			)
			(layer "F.Fab")
		)
		(fp_line
			(start -0.254 -0.508)
			(end 0.254 -0.508)
			(stroke
				(width 0.0254)
				(type default)
			)
			(layer "F.Fab")
		)
		(fp_line
			(start 0.254 0.508)
			(end -0.254 0.508)
			(stroke
				(width 0.0254)
				(type default)
			)
			(layer "F.Fab")
		)
		(fp_line
			(start -0.254 0.508)
			(end -0.254 -0.508)
			(stroke
				(width 0.0254)
				(type default)
			)
			(layer "F.Fab")
		)
		(pad "1" smd rect
			(at 0 -0.4191 90)
			(size 0.508 0.5334)
			(layers "F.Cu" "F.Mask" "F.Paste")
			(net "VDD_3.3V")
		)
		(pad "2" smd rect
			(at 0 0.4191 90)
			(size 0.508 0.5334)
			(layers "F.Cu" "F.Mask" "F.Paste")
			(net "NFP_CPLD_PRGM_JTAG_TDI")
		)
		(zone
			(layer "F.Cu")
			(hatch none 0.5)
			(connect_pads
				(clearance 0)
			)
			(min_thickness 0.25)
			(keepout
				(tracks not_allowed)
				(vias allowed)
				(pads allowed)
				(copperpour not_allowed)
				(footprints allowed)
			)
			(placement
				(enabled no)
				(sheetname "")
			)
			(fill
				(thermal_gap 0.5)
				(thermal_bridge_width 0.5)
				(island_removal_mode 0)
			)
			(polygon
				(pts
					(xy 19.0246 28.4226) (xy 19.0754 28.4226) (xy 19.0754 28.4734) (xy 19.0246 28.4734)
				)
			)
		)
	)
	(footprint ""
		(layer "F.Cu")
		(at 82.804 26.924)
		(property "Reference" "R208"
			(at 0 0 0)
			(layer "F.SilkS")
			(hide yes)
			(effects
				(font
					(size 1.27 1.27)
				)
			)
		)
		(property "Value" "39.0"
			(at -0.148158 1.3462 90)
			(unlocked yes)
			(layer "F.Fab")
			(hide yes)
			(effects
				(font
					(size 1.27 0.9652)
					(thickness 0.000001)
				)
				(justify left)
			)
		)
		(property "Device Type" "REST0108"
			(at -0.148158 1.3462 90)
			(unlocked yes)
			(layer "F.Fab")
			(hide yes)
			(effects
				(font
					(size 1.27 0.9652)
					(thickness 0.000001)
				)
				(justify left)
			)
		)
		(duplicate_pad_numbers_are_jumpers no)
		(fp_poly
			(pts
				(xy 0.635 1.0668) (xy 0.635 -1.0668) (xy -0.635 -1.0668) (xy -0.635 1.0668)
			)
			(stroke
				(width 0)
				(type default)
			)
			(fill no)
			(layer "F.CrtYd")
		)
		(fp_line
			(start -0.254 -0.508)
			(end 0.254 -0.508)
			(stroke
				(width 0.0254)
				(type default)
			)
			(layer "F.Fab")
		)
		(fp_line
			(start -0.254 0.508)
			(end -0.254 -0.508)
			(stroke
				(width 0.0254)
				(type default)
			)
			(layer "F.Fab")
		)
		(fp_line
			(start 0.254 -0.508)
			(end 0.254 0.508)
			(stroke
				(width 0.0254)
				(type default)
			)
			(layer "F.Fab")
		)
		(fp_line
			(start 0.254 0.508)
			(end -0.254 0.508)
			(stroke
				(width 0.0254)
				(type default)
			)
			(layer "F.Fab")
		)
		(pad "1" smd rect
			(at 0 -0.4191)
			(size 0.508 0.5334)
			(layers "F.Cu" "F.Mask" "F.Paste")
			(net "DDR0_32A_A2")
		)
		(pad "2" smd rect
			(at 0 0.4191)
			(size 0.508 0.5334)
			(layers "F.Cu" "F.Mask" "F.Paste")
			(net "DDR_VTT")
		)
		(zone
			(layer "F.Cu")
			(hatch none 0.5)
			(connect_pads
				(clearance 0)
			)
			(min_thickness 0.25)
			(keepout
				(tracks not_allowed)
				(vias allowed)
				(pads allowed)
				(copperpour not_allowed)
				(footprints allowed)
			)
			(placement
				(enabled no)
				(sheetname "")
			)
			(fill
				(thermal_gap 0.5)
				(thermal_bridge_width 0.5)
				(island_removal_mode 0)
			)
			(polygon
				(pts
					(xy 82.8294 26.8986) (xy 82.8294 26.9494) (xy 82.7786 26.9494) (xy 82.7786 26.8986)
				)
			)
		)
	)
	(footprint ""
		(layer "F.Cu")
		(at 78.8162 28.321 -90)
		(property "Reference" "C109"
			(at 0 0 270)
			(layer "F.SilkS")
			(hide yes)
			(effects
				(font
					(size 1.27 1.27)
				)
			)
		)
		(property "Value" "0.1UF"
			(at -0.091846 0.2921 0)
			(unlocked yes)
			(layer "F.Fab")
			(hide yes)
			(effects
				(font
					(size 0.7874 0.5842)
					(thickness 0.2032)
				)
				(justify left)
			)
		)
		(property "Device Type" "CAPC0073"
			(at -0.091846 0.2921 0)
			(unlocked yes)
			(layer "F.Fab")
			(hide yes)
			(effects
				(font
					(size 0.7874 0.5842)
					(thickness 0.2032)
				)
				(justify left)
			)
		)
		(duplicate_pad_numbers_are_jumpers no)
		(fp_poly
			(pts
				(xy 0.635 1.0668) (xy 0.635 -1.0668) (xy -0.635 -1.0668) (xy -0.635 1.0668)
			)
			(stroke
				(width 0)
				(type default)
			)
			(fill no)
			(layer "F.CrtYd")
		)
		(fp_line
			(start -0.254 0.508)
			(end -0.254 -0.508)
			(stroke
				(width 0.0254)
				(type default)
			)
			(layer "F.Fab")
		)
		(fp_line
			(start 0.254 0.508)
			(end -0.254 0.508)
			(stroke
				(width 0.0254)
				(type default)
			)
			(layer "F.Fab")
		)
		(fp_line
			(start -0.254 -0.508)
			(end 0.254 -0.508)
			(stroke
				(width 0.0254)
				(type default)
			)
			(layer "F.Fab")
		)
		(fp_line
			(start 0.254 -0.508)
			(end 0.254 0.508)
			(stroke
				(width 0.0254)
				(type default)
			)
			(layer "F.Fab")
		)
		(pad "1" smd rect
			(at 0 -0.4191 270)
			(size 0.508 0.5334)
			(layers "F.Cu" "F.Mask" "F.Paste")
			(net "DDR_VTT")
		)
		(pad "2" smd rect
			(at 0 0.4191 270)
			(size 0.508 0.5334)
			(layers "F.Cu" "F.Mask" "F.Paste")
			(net "GND")
		)
		(zone
			(layer "F.Cu")
			(hatch none 0.5)
			(connect_pads
				(clearance 0)
			)
			(min_thickness 0.25)
			(keepout
				(tracks not_allowed)
				(vias allowed)
				(pads allowed)
				(copperpour not_allowed)
				(footprints allowed)
			)
			(placement
				(enabled no)
				(sheetname "")
			)
			(fill
				(thermal_gap 0.5)
				(thermal_bridge_width 0.5)
				(island_removal_mode 0)
			)
			(polygon
				(pts
					(xy 78.8416 28.3464) (xy 78.7908 28.3464) (xy 78.7908 28.2956) (xy 78.8416 28.2956)
				)
			)
		)
	)
	(footprint ""
		(layer "F.Cu")
		(at 51.816 36.957 -90)
		(property "Reference" "R168"
			(at -0.86233 2.032 0)
			(unlocked yes)
			(layer "F.SilkS")
			(effects
				(font
					(size 0.7874 0.5842)
					(thickness 0.127)
				)
				(justify left)
			)
		)
		(property "Value" "0"
			(at -0.148158 1.3462 0)
			(unlocked yes)
			(layer "F.Fab")
			(hide yes)
			(effects
				(font
					(size 1.27 0.9652)
					(thickness 0.000001)
				)
				(justify left)
			)
		)
		(property "Device Type" "REST1111"
			(at -0.148158 1.3462 0)
			(unlocked yes)
			(layer "F.Fab")
			(hide yes)
			(effects
				(font
					(size 1.27 0.9652)
					(thickness 0.000001)
				)
				(justify left)
			)
		)
		(duplicate_pad_numbers_are_jumpers no)
		(fp_poly
			(pts
				(xy 0.635 1.0668) (xy 0.635 -1.0668) (xy -0.635 -1.0668) (xy -0.635 1.0668)
			)
			(stroke
				(width 0)
				(type default)
			)
			(fill no)
			(layer "F.CrtYd")
		)
		(fp_line
			(start -0.254 0.508)
			(end -0.254 -0.508)
			(stroke
				(width 0.0254)
				(type default)
			)
			(layer "F.Fab")
		)
		(fp_line
			(start 0.254 0.508)
			(end -0.254 0.508)
			(stroke
				(width 0.0254)
				(type default)
			)
			(layer "F.Fab")
		)
		(fp_line
			(start -0.254 -0.508)
			(end 0.254 -0.508)
			(stroke
				(width 0.0254)
				(type default)
			)
			(layer "F.Fab")
		)
		(fp_line
			(start 0.254 -0.508)
			(end 0.254 0.508)
			(stroke
				(width 0.0254)
				(type default)
			)
			(layer "F.Fab")
		)
		(pad "1" smd rect
			(at 0 -0.4191 270)
			(size 0.508 0.5334)
			(layers "F.Cu" "F.Mask" "F.Paste")
			(net "L_2_CORE_PHASE")
		)
		(pad "2" smd rect
			(at 0 0.4191 270)
			(size 0.508 0.5334)
			(layers "F.Cu" "F.Mask" "F.Paste")
			(net "NFP_VDD_CORE_ISEN2_P")
		)
		(zone
			(layer "F.Cu")
			(hatch none 0.5)
			(connect_pads
				(clearance 0)
			)
			(min_thickness 0.25)
			(keepout
				(tracks not_allowed)
				(vias allowed)
				(pads allowed)
				(copperpour not_allowed)
				(footprints allowed)
			)
			(placement
				(enabled no)
				(sheetname "")
			)
			(fill
				(thermal_gap 0.5)
				(thermal_bridge_width 0.5)
				(island_removal_mode 0)
			)
			(polygon
				(pts
					(xy 51.8414 36.9824) (xy 51.7906 36.9824) (xy 51.7906 36.9316) (xy 51.8414 36.9316)
				)
			)
		)
	)
	(footprint ""
		(layer "F.Cu")
		(at 33.274 2.286)
		(property "Reference" "R269"
			(at -1.24333 -0.889 90)
			(unlocked yes)
			(layer "F.SilkS")
			(effects
				(font
					(size 0.7874 0.5842)
					(thickness 0.127)
				)
				(justify left)
			)
		)
		(property "Value" "240"
			(at -0.148158 1.3462 90)
			(unlocked yes)
			(layer "F.Fab")
			(hide yes)
			(effects
				(font
					(size 1.27 0.9652)
					(thickness 0.000001)
				)
				(justify left)
			)
		)
		(property "Device Type" "REST0009"
			(at -0.148158 1.3462 90)
			(unlocked yes)
			(layer "F.Fab")
			(hide yes)
			(effects
				(font
					(size 1.27 0.9652)
					(thickness 0.000001)
				)
				(justify left)
			)
		)
		(duplicate_pad_numbers_are_jumpers no)
		(fp_poly
			(pts
				(xy 0.635 1.0668) (xy 0.635 -1.0668) (xy -0.635 -1.0668) (xy -0.635 1.0668)
			)
			(stroke
				(width 0)
				(type default)
			)
			(fill no)
			(layer "F.CrtYd")
		)
		(fp_line
			(start -0.254 -0.508)
			(end 0.254 -0.508)
			(stroke
				(width 0.0254)
				(type default)
			)
			(layer "F.Fab")
		)
		(fp_line
			(start -0.254 0.508)
			(end -0.254 -0.508)
			(stroke
				(width 0.0254)
				(type default)
			)
			(layer "F.Fab")
		)
		(fp_line
			(start 0.254 -0.508)
			(end 0.254 0.508)
			(stroke
				(width 0.0254)
				(type default)
			)
			(layer "F.Fab")
		)
		(fp_line
			(start 0.254 0.508)
			(end -0.254 0.508)
			(stroke
				(width 0.0254)
				(type default)
			)
			(layer "F.Fab")
		)
		(pad "1" smd rect
			(at 0 -0.4191)
			(size 0.508 0.5334)
			(layers "F.Cu" "F.Mask" "F.Paste")
			(net "NFP_REF_CLK_156M_EN")
		)
		(pad "2" smd rect
			(at 0 0.4191)
			(size 0.508 0.5334)
			(layers "F.Cu" "F.Mask" "F.Paste")
			(net "3N2285")
		)
		(zone
			(layer "F.Cu")
			(hatch none 0.5)
			(connect_pads
				(clearance 0)
			)
			(min_thickness 0.25)
			(keepout
				(tracks not_allowed)
				(vias allowed)
				(pads allowed)
				(copperpour not_allowed)
				(footprints allowed)
			)
			(placement
				(enabled no)
				(sheetname "")
			)
			(fill
				(thermal_gap 0.5)
				(thermal_bridge_width 0.5)
				(island_removal_mode 0)
			)
			(polygon
				(pts
					(xy 33.2994 2.2606) (xy 33.2994 2.3114) (xy 33.2486 2.3114) (xy 33.2486 2.2606)
				)
			)
		)
	)
	(footprint ""
		(layer "F.Cu")
		(at 27.051 13.97 -90)
		(property "Reference" "R263"
			(at 0 0 270)
			(layer "F.SilkS")
			(hide yes)
			(effects
				(font
					(size 1.27 1.27)
				)
			)
		)
		(property "Value" "39.0"
			(at -0.148158 1.3462 0)
			(unlocked yes)
			(layer "F.Fab")
			(hide yes)
			(effects
				(font
					(size 1.27 0.9652)
					(thickness 0.000001)
				)
				(justify left)
			)
		)
		(property "Device Type" "REST0108"
			(at -0.148158 1.3462 0)
			(unlocked yes)
			(layer "F.Fab")
			(hide yes)
			(effects
				(font
					(size 1.27 0.9652)
					(thickness 0.000001)
				)
				(justify left)
			)
		)
		(duplicate_pad_numbers_are_jumpers no)
		(fp_poly
			(pts
				(xy 0.635 1.0668) (xy 0.635 -1.0668) (xy -0.635 -1.0668) (xy -0.635 1.0668)
			)
			(stroke
				(width 0)
				(type default)
			)
			(fill no)
			(layer "F.CrtYd")
		)
		(fp_line
			(start -0.254 0.508)
			(end -0.254 -0.508)
			(stroke
				(width 0.0254)
				(type default)
			)
			(layer "F.Fab")
		)
		(fp_line
			(start 0.254 0.508)
			(end -0.254 0.508)
			(stroke
				(width 0.0254)
				(type default)
			)
			(layer "F.Fab")
		)
		(fp_line
			(start -0.254 -0.508)
			(end 0.254 -0.508)
			(stroke
				(width 0.0254)
				(type default)
			)
			(layer "F.Fab")
		)
		(fp_line
			(start 0.254 -0.508)
			(end 0.254 0.508)
			(stroke
				(width 0.0254)
				(type default)
			)
			(layer "F.Fab")
		)
		(pad "1" smd rect
			(at 0 -0.4191 270)
			(size 0.508 0.5334)
			(layers "F.Cu" "F.Mask" "F.Paste")
			(net "_NFP_JTAG_ARM_TDO")
		)
		(pad "2" smd rect
			(at 0 0.4191 270)
			(size 0.508 0.5334)
			(layers "F.Cu" "F.Mask" "F.Paste")
			(net "NFP_JTAG_ARM_TDO")
		)
		(zone
			(layer "F.Cu")
			(hatch none 0.5)
			(connect_pads
				(clearance 0)
			)
			(min_thickness 0.25)
			(keepout
				(tracks not_allowed)
				(vias allowed)
				(pads allowed)
				(copperpour not_allowed)
				(footprints allowed)
			)
			(placement
				(enabled no)
				(sheetname "")
			)
			(fill
				(thermal_gap 0.5)
				(thermal_bridge_width 0.5)
				(island_removal_mode 0)
			)
			(polygon
				(pts
					(xy 27.0764 13.9954) (xy 27.0256 13.9954) (xy 27.0256 13.9446) (xy 27.0764 13.9446)
				)
			)
		)
	)
	(footprint ""
		(layer "F.Cu")
		(at 73.152 25.4 180)
		(property "Reference" "R340"
			(at 0.86233 -0.254 90)
			(unlocked yes)
			(layer "F.SilkS")
			(effects
				(font
					(size 0.7874 0.5842)
					(thickness 0.127)
				)
				(justify left)
			)
		)
		(property "Value" "4.75K"
			(at -0.148158 1.3462 270)
			(unlocked yes)
			(layer "F.Fab")
			(hide yes)
			(effects
				(font
					(size 1.27 0.9652)
					(thickness 0.000001)
				)
				(justify left)
			)
		)
		(property "Device Type" "REST4024"
			(at -0.148158 1.3462 270)
			(unlocked yes)
			(layer "F.Fab")
			(hide yes)
			(effects
				(font
					(size 1.27 0.9652)
					(thickness 0.000001)
				)
				(justify left)
			)
		)
		(duplicate_pad_numbers_are_jumpers no)
		(fp_poly
			(pts
				(xy 0.635 1.0668) (xy 0.635 -1.0668) (xy -0.635 -1.0668) (xy -0.635 1.0668)
			)
			(stroke
				(width 0)
				(type default)
			)
			(fill no)
			(layer "F.CrtYd")
		)
		(fp_line
			(start 0.254 0.508)
			(end -0.254 0.508)
			(stroke
				(width 0.0254)
				(type default)
			)
			(layer "F.Fab")
		)
		(fp_line
			(start 0.254 -0.508)
			(end 0.254 0.508)
			(stroke
				(width 0.0254)
				(type default)
			)
			(layer "F.Fab")
		)
		(fp_line
			(start -0.254 0.508)
			(end -0.254 -0.508)
			(stroke
				(width 0.0254)
				(type default)
			)
			(layer "F.Fab")
		)
		(fp_line
			(start -0.254 -0.508)
			(end 0.254 -0.508)
			(stroke
				(width 0.0254)
				(type default)
			)
			(layer "F.Fab")
		)
		(pad "1" smd rect
			(at 0 -0.4191 180)
			(size 0.508 0.5334)
			(layers "F.Cu" "F.Mask" "F.Paste")
			(net "12N3291")
		)
		(pad "2" smd rect
			(at 0 0.4191 180)
			(size 0.508 0.5334)
			(layers "F.Cu" "F.Mask" "F.Paste")
			(net "DDR_VDDQ")
		)
		(zone
			(layer "F.Cu")
			(hatch none 0.5)
			(connect_pads
				(clearance 0)
			)
			(min_thickness 0.25)
			(keepout
				(tracks not_allowed)
				(vias allowed)
				(pads allowed)
				(copperpour not_allowed)
				(footprints allowed)
			)
			(placement
				(enabled no)
				(sheetname "")
			)
			(fill
				(thermal_gap 0.5)
				(thermal_bridge_width 0.5)
				(island_removal_mode 0)
			)
			(polygon
				(pts
					(xy 73.1266 25.4254) (xy 73.1266 25.3746) (xy 73.1774 25.3746) (xy 73.1774 25.4254)
				)
			)
		)
	)
	(footprint ""
		(layer "F.Cu")
		(at 15.621 1.397)
		(property "Reference" "R390"
			(at 0.53467 -0.762 90)
			(unlocked yes)
			(layer "F.SilkS")
			(effects
				(font
					(size 0.7874 0.5842)
					(thickness 0.127)
				)
				(justify left)
			)
		)
		(property "Value" "0"
			(at -0.148158 1.3462 90)
			(unlocked yes)
			(layer "F.Fab")
			(hide yes)
			(effects
				(font
					(size 1.27 0.9652)
					(thickness 0.000001)
				)
				(justify left)
			)
		)
		(property "Device Type" "REST1111"
			(at -0.148158 1.3462 90)
			(unlocked yes)
			(layer "F.Fab")
			(hide yes)
			(effects
				(font
					(size 1.27 0.9652)
					(thickness 0.000001)
				)
				(justify left)
			)
		)
		(duplicate_pad_numbers_are_jumpers no)
		(fp_poly
			(pts
				(xy 0.635 1.0668) (xy 0.635 -1.0668) (xy -0.635 -1.0668) (xy -0.635 1.0668)
			)
			(stroke
				(width 0)
				(type default)
			)
			(fill no)
			(layer "F.CrtYd")
		)
		(fp_line
			(start -0.254 -0.508)
			(end 0.254 -0.508)
			(stroke
				(width 0.0254)
				(type default)
			)
			(layer "F.Fab")
		)
		(fp_line
			(start -0.254 0.508)
			(end -0.254 -0.508)
			(stroke
				(width 0.0254)
				(type default)
			)
			(layer "F.Fab")
		)
		(fp_line
			(start 0.254 -0.508)
			(end 0.254 0.508)
			(stroke
				(width 0.0254)
				(type default)
			)
			(layer "F.Fab")
		)
		(fp_line
			(start 0.254 0.508)
			(end -0.254 0.508)
			(stroke
				(width 0.0254)
				(type default)
			)
			(layer "F.Fab")
		)
		(pad "1" smd rect
			(at 0 -0.4191)
			(size 0.508 0.5334)
			(layers "F.Cu" "F.Mask" "F.Paste")
			(net "CPLD_SMBUS_SCL")
		)
		(pad "2" smd rect
			(at 0 0.4191)
			(size 0.508 0.5334)
			(layers "F.Cu" "F.Mask" "F.Paste")
			(net "SMBUS_SCL")
		)
		(zone
			(layer "F.Cu")
			(hatch none 0.5)
			(connect_pads
				(clearance 0)
			)
			(min_thickness 0.25)
			(keepout
				(tracks not_allowed)
				(vias allowed)
				(pads allowed)
				(copperpour not_allowed)
				(footprints allowed)
			)
			(placement
				(enabled no)
				(sheetname "")
			)
			(fill
				(thermal_gap 0.5)
				(thermal_bridge_width 0.5)
				(island_removal_mode 0)
			)
			(polygon
				(pts
					(xy 15.6464 1.3716) (xy 15.6464 1.4224) (xy 15.5956 1.4224) (xy 15.5956 1.3716)
				)
			)
		)
	)
	(footprint ""
		(layer "F.Cu")
		(at 73.851008 6.698996)
		(property "Reference" "V_A-DQ08"
			(at 0 0 0)
			(layer "F.SilkS")
			(hide yes)
			(effects
				(font
					(size 1.27 1.27)
				)
			)
		)
		(property "Value" ""
			(at 0 0 0)
			(layer "F.Fab")
			(effects
				(font
					(size 1.27 1.27)
				)
			)
		)
		(duplicate_pad_numbers_are_jumpers no)
		(pad "1" thru_hole circle
			(at 0 0)
			(size 0.762 0.762)
			(drill 0.20574)
			(layers "*.Cu" "*.Mask")
			(remove_unused_layers no)
			(net "DDR0_32A_DQ8")
			(clearance 0.127)
			(thermal_gap 0.127)
			(padstack
				(mode front_inner_back)
				(layer "Inner"
					(shape circle)
					(size 0.4572 0.4572)
					(clearance 0.1143)
				)
				(layer "B.Cu"
					(shape circle)
					(size 0.4572 0.4572)
					(clearance 0.1143)
				)
			)
		)
	)
	(footprint ""
		(layer "F.Cu")
		(at 63.5 46.60646)
		(property "Reference" "C127"
			(at 0 0 0)
			(layer "F.SilkS")
			(hide yes)
			(effects
				(font
					(size 1.27 1.27)
				)
			)
		)
		(property "Value" "0.1UF"
			(at -0.091846 0.2921 90)
			(unlocked yes)
			(layer "F.Fab")
			(hide yes)
			(effects
				(font
					(size 0.7874 0.5842)
					(thickness 0.2032)
				)
				(justify left)
			)
		)
		(property "Device Type" "CAPC0073"
			(at -0.091846 0.2921 90)
			(unlocked yes)
			(layer "F.Fab")
			(hide yes)
			(effects
				(font
					(size 0.7874 0.5842)
					(thickness 0.2032)
				)
				(justify left)
			)
		)
		(duplicate_pad_numbers_are_jumpers no)
		(fp_poly
			(pts
				(xy 0.635 1.0668) (xy 0.635 -1.0668) (xy -0.635 -1.0668) (xy -0.635 1.0668)
			)
			(stroke
				(width 0)
				(type default)
			)
			(fill no)
			(layer "F.CrtYd")
		)
		(fp_line
			(start -0.254 -0.508)
			(end 0.254 -0.508)
			(stroke
				(width 0.0254)
				(type default)
			)
			(layer "F.Fab")
		)
		(fp_line
			(start -0.254 0.508)
			(end -0.254 -0.508)
			(stroke
				(width 0.0254)
				(type default)
			)
			(layer "F.Fab")
		)
		(fp_line
			(start 0.254 -0.508)
			(end 0.254 0.508)
			(stroke
				(width 0.0254)
				(type default)
			)
			(layer "F.Fab")
		)
		(fp_line
			(start 0.254 0.508)
			(end -0.254 0.508)
			(stroke
				(width 0.0254)
				(type default)
			)
			(layer "F.Fab")
		)
		(pad "1" smd rect
			(at 0 -0.4191)
			(size 0.508 0.5334)
			(layers "F.Cu" "F.Mask" "F.Paste")
			(net "11N1981")
		)
		(pad "2" smd rect
			(at 0 0.4191)
			(size 0.508 0.5334)
			(layers "F.Cu" "F.Mask" "F.Paste")
			(net "11N1952")
		)
		(zone
			(layer "F.Cu")
			(hatch none 0.5)
			(connect_pads
				(clearance 0)
			)
			(min_thickness 0.25)
			(keepout
				(tracks not_allowed)
				(vias allowed)
				(pads allowed)
				(copperpour not_allowed)
				(footprints allowed)
			)
			(placement
				(enabled no)
				(sheetname "")
			)
			(fill
				(thermal_gap 0.5)
				(thermal_bridge_width 0.5)
				(island_removal_mode 0)
			)
			(polygon
				(pts
					(xy 63.5254 46.58106) (xy 63.5254 46.63186) (xy 63.4746 46.63186) (xy 63.4746 46.58106)
				)
			)
		)
	)
	(footprint ""
		(layer "F.Cu")
		(at 84.6836 42.418)
		(property "Reference" "C129"
			(at 0.81407 1.651 90)
			(unlocked yes)
			(layer "F.SilkS")
			(effects
				(font
					(size 0.7874 0.5842)
					(thickness 0.127)
				)
				(justify left)
			)
		)
		(property "Value" "0.1UF"
			(at -0.091846 0.2921 90)
			(unlocked yes)
			(layer "F.Fab")
			(hide yes)
			(effects
				(font
					(size 0.7874 0.5842)
					(thickness 0.2032)
				)
				(justify left)
			)
		)
		(property "Device Type" "CAPC0073"
			(at -0.091846 0.2921 90)
			(unlocked yes)
			(layer "F.Fab")
			(hide yes)
			(effects
				(font
					(size 0.7874 0.5842)
					(thickness 0.2032)
				)
				(justify left)
			)
		)
		(duplicate_pad_numbers_are_jumpers no)
		(fp_poly
			(pts
				(xy 0.635 1.0668) (xy 0.635 -1.0668) (xy -0.635 -1.0668) (xy -0.635 1.0668)
			)
			(stroke
				(width 0)
				(type default)
			)
			(fill no)
			(layer "F.CrtYd")
		)
		(fp_line
			(start -0.254 -0.508)
			(end 0.254 -0.508)
			(stroke
				(width 0.0254)
				(type default)
			)
			(layer "F.Fab")
		)
		(fp_line
			(start -0.254 0.508)
			(end -0.254 -0.508)
			(stroke
				(width 0.0254)
				(type default)
			)
			(layer "F.Fab")
		)
		(fp_line
			(start 0.254 -0.508)
			(end 0.254 0.508)
			(stroke
				(width 0.0254)
				(type default)
			)
			(layer "F.Fab")
		)
		(fp_line
			(start 0.254 0.508)
			(end -0.254 0.508)
			(stroke
				(width 0.0254)
				(type default)
			)
			(layer "F.Fab")
		)
		(pad "1" smd rect
			(at 0 -0.4191)
			(size 0.508 0.5334)
			(layers "F.Cu" "F.Mask" "F.Paste")
			(net "11N2181")
		)
		(pad "2" smd rect
			(at 0 0.4191)
			(size 0.508 0.5334)
			(layers "F.Cu" "F.Mask" "F.Paste")
			(net "11N2175")
		)
		(zone
			(layer "F.Cu")
			(hatch none 0.5)
			(connect_pads
				(clearance 0)
			)
			(min_thickness 0.25)
			(keepout
				(tracks not_allowed)
				(vias allowed)
				(pads allowed)
				(copperpour not_allowed)
				(footprints allowed)
			)
			(placement
				(enabled no)
				(sheetname "")
			)
			(fill
				(thermal_gap 0.5)
				(thermal_bridge_width 0.5)
				(island_removal_mode 0)
			)
			(polygon
				(pts
					(xy 84.709 42.3926) (xy 84.709 42.4434) (xy 84.6582 42.4434) (xy 84.6582 42.3926)
				)
			)
		)
	)
	(footprint ""
		(layer "F.Cu")
		(at 47.498 46.609 90)
		(property "Reference" "R400"
			(at 0 0 90)
			(layer "F.SilkS")
			(hide yes)
			(effects
				(font
					(size 1.27 1.27)
				)
			)
		)
		(property "Value" "4.75K"
			(at -0.148158 1.3462 180)
			(unlocked yes)
			(layer "F.Fab")
			(hide yes)
			(effects
				(font
					(size 1.27 0.9652)
					(thickness 0.000001)
				)
				(justify left)
			)
		)
		(property "Device Type" "REST4024"
			(at -0.148158 1.3462 180)
			(unlocked yes)
			(layer "F.Fab")
			(hide yes)
			(effects
				(font
					(size 1.27 0.9652)
					(thickness 0.000001)
				)
				(justify left)
			)
		)
		(duplicate_pad_numbers_are_jumpers no)
		(fp_poly
			(pts
				(xy 0.635 1.0668) (xy 0.635 -1.0668) (xy -0.635 -1.0668) (xy -0.635 1.0668)
			)
			(stroke
				(width 0)
				(type default)
			)
			(fill no)
			(layer "F.CrtYd")
		)
		(fp_line
			(start 0.254 -0.508)
			(end 0.254 0.508)
			(stroke
				(width 0.0254)
				(type default)
			)
			(layer "F.Fab")
		)
		(fp_line
			(start -0.254 -0.508)
			(end 0.254 -0.508)
			(stroke
				(width 0.0254)
				(type default)
			)
			(layer "F.Fab")
		)
		(fp_line
			(start 0.254 0.508)
			(end -0.254 0.508)
			(stroke
				(width 0.0254)
				(type default)
			)
			(layer "F.Fab")
		)
		(fp_line
			(start -0.254 0.508)
			(end -0.254 -0.508)
			(stroke
				(width 0.0254)
				(type default)
			)
			(layer "F.Fab")
		)
		(pad "1" smd rect
			(at 0 -0.4191 90)
			(size 0.508 0.5334)
			(layers "F.Cu" "F.Mask" "F.Paste")
			(net "GND")
		)
		(pad "2" smd rect
			(at 0 0.4191 90)
			(size 0.508 0.5334)
			(layers "F.Cu" "F.Mask" "F.Paste")
			(net "VDD_5.0V_EN")
		)
		(zone
			(layer "F.Cu")
			(hatch none 0.5)
			(connect_pads
				(clearance 0)
			)
			(min_thickness 0.25)
			(keepout
				(tracks not_allowed)
				(vias allowed)
				(pads allowed)
				(copperpour not_allowed)
				(footprints allowed)
			)
			(placement
				(enabled no)
				(sheetname "")
			)
			(fill
				(thermal_gap 0.5)
				(thermal_bridge_width 0.5)
				(island_removal_mode 0)
			)
			(polygon
				(pts
					(xy 47.4726 46.5836) (xy 47.5234 46.5836) (xy 47.5234 46.6344) (xy 47.4726 46.6344)
				)
			)
		)
	)
	(footprint ""
		(layer "F.Cu")
		(at 23.241 29.337 180)
		(property "Reference" "R64"
			(at 0 0 180)
			(layer "F.SilkS")
			(hide yes)
			(effects
				(font
					(size 1.27 1.27)
				)
			)
		)
		(property "Value" "4.75K"
			(at -0.148158 1.3462 270)
			(unlocked yes)
			(layer "F.Fab")
			(hide yes)
			(effects
				(font
					(size 1.27 0.9652)
					(thickness 0.000001)
				)
				(justify left)
			)
		)
		(property "Device Type" "REST4024"
			(at -0.148158 1.3462 270)
			(unlocked yes)
			(layer "F.Fab")
			(hide yes)
			(effects
				(font
					(size 1.27 0.9652)
					(thickness 0.000001)
				)
				(justify left)
			)
		)
		(duplicate_pad_numbers_are_jumpers no)
		(fp_poly
			(pts
				(xy 0.635 1.0668) (xy 0.635 -1.0668) (xy -0.635 -1.0668) (xy -0.635 1.0668)
			)
			(stroke
				(width 0)
				(type default)
			)
			(fill no)
			(layer "F.CrtYd")
		)
		(fp_line
			(start 0.254 0.508)
			(end -0.254 0.508)
			(stroke
				(width 0.0254)
				(type default)
			)
			(layer "F.Fab")
		)
		(fp_line
			(start 0.254 -0.508)
			(end 0.254 0.508)
			(stroke
				(width 0.0254)
				(type default)
			)
			(layer "F.Fab")
		)
		(fp_line
			(start -0.254 0.508)
			(end -0.254 -0.508)
			(stroke
				(width 0.0254)
				(type default)
			)
			(layer "F.Fab")
		)
		(fp_line
			(start -0.254 -0.508)
			(end 0.254 -0.508)
			(stroke
				(width 0.0254)
				(type default)
			)
			(layer "F.Fab")
		)
		(pad "1" smd rect
			(at 0 -0.4191 180)
			(size 0.508 0.5334)
			(layers "F.Cu" "F.Mask" "F.Paste")
			(net "NFP_CPLD_PRGM_JTAG_TCK")
		)
		(pad "2" smd rect
			(at 0 0.4191 180)
			(size 0.508 0.5334)
			(layers "F.Cu" "F.Mask" "F.Paste")
			(net "GND")
		)
		(zone
			(layer "F.Cu")
			(hatch none 0.5)
			(connect_pads
				(clearance 0)
			)
			(min_thickness 0.25)
			(keepout
				(tracks not_allowed)
				(vias allowed)
				(pads allowed)
				(copperpour not_allowed)
				(footprints allowed)
			)
			(placement
				(enabled no)
				(sheetname "")
			)
			(fill
				(thermal_gap 0.5)
				(thermal_bridge_width 0.5)
				(island_removal_mode 0)
			)
			(polygon
				(pts
					(xy 23.2156 29.3624) (xy 23.2156 29.3116) (xy 23.2664 29.3116) (xy 23.2664 29.3624)
				)
			)
		)
	)
	(footprint ""
		(layer "F.Cu")
		(at 80.0862 22.987 180)
		(property "Reference" "R224"
			(at 0 0 180)
			(layer "F.SilkS")
			(hide yes)
			(effects
				(font
					(size 1.27 1.27)
				)
			)
		)
		(property "Value" "39.0"
			(at -0.148158 1.3462 270)
			(unlocked yes)
			(layer "F.Fab")
			(hide yes)
			(effects
				(font
					(size 1.27 0.9652)
					(thickness 0.000001)
				)
				(justify left)
			)
		)
		(property "Device Type" "REST0108"
			(at -0.148158 1.3462 270)
			(unlocked yes)
			(layer "F.Fab")
			(hide yes)
			(effects
				(font
					(size 1.27 0.9652)
					(thickness 0.000001)
				)
				(justify left)
			)
		)
		(duplicate_pad_numbers_are_jumpers no)
		(fp_poly
			(pts
				(xy 0.635 1.0668) (xy 0.635 -1.0668) (xy -0.635 -1.0668) (xy -0.635 1.0668)
			)
			(stroke
				(width 0)
				(type default)
			)
			(fill no)
			(layer "F.CrtYd")
		)
		(fp_line
			(start 0.254 0.508)
			(end -0.254 0.508)
			(stroke
				(width 0.0254)
				(type default)
			)
			(layer "F.Fab")
		)
		(fp_line
			(start 0.254 -0.508)
			(end 0.254 0.508)
			(stroke
				(width 0.0254)
				(type default)
			)
			(layer "F.Fab")
		)
		(fp_line
			(start -0.254 0.508)
			(end -0.254 -0.508)
			(stroke
				(width 0.0254)
				(type default)
			)
			(layer "F.Fab")
		)
		(fp_line
			(start -0.254 -0.508)
			(end 0.254 -0.508)
			(stroke
				(width 0.0254)
				(type default)
			)
			(layer "F.Fab")
		)
		(pad "1" smd rect
			(at 0 -0.4191 180)
			(size 0.508 0.5334)
			(layers "F.Cu" "F.Mask" "F.Paste")
			(net "DDR0_32A_BA0")
		)
		(pad "2" smd rect
			(at 0 0.4191 180)
			(size 0.508 0.5334)
			(layers "F.Cu" "F.Mask" "F.Paste")
			(net "DDR_VTT")
		)
		(zone
			(layer "F.Cu")
			(hatch none 0.5)
			(connect_pads
				(clearance 0)
			)
			(min_thickness 0.25)
			(keepout
				(tracks not_allowed)
				(vias allowed)
				(pads allowed)
				(copperpour not_allowed)
				(footprints allowed)
			)
			(placement
				(enabled no)
				(sheetname "")
			)
			(fill
				(thermal_gap 0.5)
				(thermal_bridge_width 0.5)
				(island_removal_mode 0)
			)
			(polygon
				(pts
					(xy 80.0608 23.0124) (xy 80.0608 22.9616) (xy 80.1116 22.9616) (xy 80.1116 23.0124)
				)
			)
		)
	)
	(footprint ""
		(layer "F.Cu")
		(at 83.693 32.576414)
		(property "Reference" "R212"
			(at 0 0 0)
			(layer "F.SilkS")
			(hide yes)
			(effects
				(font
					(size 1.27 1.27)
				)
			)
		)
		(property "Value" "39.0"
			(at -0.148158 1.3462 90)
			(unlocked yes)
			(layer "F.Fab")
			(hide yes)
			(effects
				(font
					(size 1.27 0.9652)
					(thickness 0.000001)
				)
				(justify left)
			)
		)
		(property "Device Type" "REST0108"
			(at -0.148158 1.3462 90)
			(unlocked yes)
			(layer "F.Fab")
			(hide yes)
			(effects
				(font
					(size 1.27 0.9652)
					(thickness 0.000001)
				)
				(justify left)
			)
		)
		(duplicate_pad_numbers_are_jumpers no)
		(fp_poly
			(pts
				(xy 0.635 1.0668) (xy 0.635 -1.0668) (xy -0.635 -1.0668) (xy -0.635 1.0668)
			)
			(stroke
				(width 0)
				(type default)
			)
			(fill no)
			(layer "F.CrtYd")
		)
		(fp_line
			(start -0.254 -0.508)
			(end 0.254 -0.508)
			(stroke
				(width 0.0254)
				(type default)
			)
			(layer "F.Fab")
		)
		(fp_line
			(start -0.254 0.508)
			(end -0.254 -0.508)
			(stroke
				(width 0.0254)
				(type default)
			)
			(layer "F.Fab")
		)
		(fp_line
			(start 0.254 -0.508)
			(end 0.254 0.508)
			(stroke
				(width 0.0254)
				(type default)
			)
			(layer "F.Fab")
		)
		(fp_line
			(start 0.254 0.508)
			(end -0.254 0.508)
			(stroke
				(width 0.0254)
				(type default)
			)
			(layer "F.Fab")
		)
		(pad "1" smd rect
			(at 0 -0.4191)
			(size 0.508 0.5334)
			(layers "F.Cu" "F.Mask" "F.Paste")
			(net "DDR0_32A_A6")
		)
		(pad "2" smd rect
			(at 0 0.4191)
			(size 0.508 0.5334)
			(layers "F.Cu" "F.Mask" "F.Paste")
			(net "DDR_VTT")
		)
		(zone
			(layer "F.Cu")
			(hatch none 0.5)
			(connect_pads
				(clearance 0)
			)
			(min_thickness 0.25)
			(keepout
				(tracks not_allowed)
				(vias allowed)
				(pads allowed)
				(copperpour not_allowed)
				(footprints allowed)
			)
			(placement
				(enabled no)
				(sheetname "")
			)
			(fill
				(thermal_gap 0.5)
				(thermal_bridge_width 0.5)
				(island_removal_mode 0)
			)
			(polygon
				(pts
					(xy 83.7184 32.551014) (xy 83.7184 32.601814) (xy 83.6676 32.601814) (xy 83.6676 32.551014)
				)
			)
		)
	)
	(footprint ""
		(layer "F.Cu")
		(at 21.082 35.687 180)
		(property "Reference" "R67"
			(at 0 0 180)
			(layer "F.SilkS")
			(hide yes)
			(effects
				(font
					(size 1.27 1.27)
				)
			)
		)
		(property "Value" "4.75K"
			(at -0.148158 1.3462 270)
			(unlocked yes)
			(layer "F.Fab")
			(hide yes)
			(effects
				(font
					(size 1.27 0.9652)
					(thickness 0.000001)
				)
				(justify left)
			)
		)
		(property "Device Type" "REST4024"
			(at -0.148158 1.3462 270)
			(unlocked yes)
			(layer "F.Fab")
			(hide yes)
			(effects
				(font
					(size 1.27 0.9652)
					(thickness 0.000001)
				)
				(justify left)
			)
		)
		(duplicate_pad_numbers_are_jumpers no)
		(fp_poly
			(pts
				(xy 0.635 1.0668) (xy 0.635 -1.0668) (xy -0.635 -1.0668) (xy -0.635 1.0668)
			)
			(stroke
				(width 0)
				(type default)
			)
			(fill no)
			(layer "F.CrtYd")
		)
		(fp_line
			(start 0.254 0.508)
			(end -0.254 0.508)
			(stroke
				(width 0.0254)
				(type default)
			)
			(layer "F.Fab")
		)
		(fp_line
			(start 0.254 -0.508)
			(end 0.254 0.508)
			(stroke
				(width 0.0254)
				(type default)
			)
			(layer "F.Fab")
		)
		(fp_line
			(start -0.254 0.508)
			(end -0.254 -0.508)
			(stroke
				(width 0.0254)
				(type default)
			)
			(layer "F.Fab")
		)
		(fp_line
			(start -0.254 -0.508)
			(end 0.254 -0.508)
			(stroke
				(width 0.0254)
				(type default)
			)
			(layer "F.Fab")
		)
		(pad "1" smd rect
			(at 0 -0.4191 180)
			(size 0.508 0.5334)
			(layers "F.Cu" "F.Mask" "F.Paste")
			(net "VDD_3.3V")
		)
		(pad "2" smd rect
			(at 0 0.4191 180)
			(size 0.508 0.5334)
			(layers "F.Cu" "F.Mask" "F.Paste")
			(net "NFP_CPLD_PRGM_JTAG_TDO")
		)
		(zone
			(layer "F.Cu")
			(hatch none 0.5)
			(connect_pads
				(clearance 0)
			)
			(min_thickness 0.25)
			(keepout
				(tracks not_allowed)
				(vias allowed)
				(pads allowed)
				(copperpour not_allowed)
				(footprints allowed)
			)
			(placement
				(enabled no)
				(sheetname "")
			)
			(fill
				(thermal_gap 0.5)
				(thermal_bridge_width 0.5)
				(island_removal_mode 0)
			)
			(polygon
				(pts
					(xy 21.0566 35.7124) (xy 21.0566 35.6616) (xy 21.1074 35.6616) (xy 21.1074 35.7124)
				)
			)
		)
	)
	(footprint ""
		(layer "F.Cu")
		(at 74.244962 22.041993 90)
		(property "Reference" "C2"
			(at 0.933323 -2.108962 0)
			(unlocked yes)
			(layer "F.SilkS")
			(effects
				(font
					(size 0.7874 0.5842)
					(thickness 0.127)
				)
				(justify left)
			)
		)
		(property "Value" "22UF"
			(at -0.148158 1.7526 180)
			(unlocked yes)
			(layer "F.Fab")
			(hide yes)
			(effects
				(font
					(size 1.27 0.9652)
					(thickness 0.000001)
				)
				(justify left)
			)
		)
		(property "Device Type" "CAPC0063"
			(at -0.148158 1.7526 180)
			(unlocked yes)
			(layer "F.Fab")
			(hide yes)
			(effects
				(font
					(size 1.27 0.9652)
					(thickness 0.000001)
				)
				(justify left)
			)
		)
		(duplicate_pad_numbers_are_jumpers no)
		(fp_circle
			(center 0 0)
			(end 0 0.127)
			(stroke
				(width 0.2032)
				(type default)
			)
			(fill no)
			(layer "F.SilkS")
		)
		(fp_poly
			(pts
				(xy 0.7874 -1.6637) (xy -0.7874 -1.6637) (xy -0.7874 1.6637) (xy 0.7874 1.6637)
			)
			(stroke
				(width 0)
				(type default)
			)
			(fill no)
			(layer "F.CrtYd")
		)
		(fp_line
			(start 0.4064 -0.7874)
			(end 0.4064 0.8128)
			(stroke
				(width 0.0254)
				(type default)
			)
			(layer "F.Fab")
		)
		(fp_line
			(start -0.4064 -0.7874)
			(end 0.4064 -0.7874)
			(stroke
				(width 0.0254)
				(type default)
			)
			(layer "F.Fab")
		)
		(fp_line
			(start 0.4064 0.8128)
			(end -0.4064 0.8128)
			(stroke
				(width 0.0254)
				(type default)
			)
			(layer "F.Fab")
		)
		(fp_line
			(start -0.4064 0.8128)
			(end -0.4064 -0.7874)
			(stroke
				(width 0.0254)
				(type default)
			)
			(layer "F.Fab")
		)
		(pad "1" smd rect
			(at 0 -0.8001 90)
			(size 0.8636 0.9652)
			(layers "F.Cu" "F.Mask" "F.Paste")
			(net "DDR_VDDQ")
		)
		(pad "2" smd rect
			(at 0 0.8001 90)
			(size 0.8636 0.9652)
			(layers "F.Cu" "F.Mask" "F.Paste")
			(net "GND")
		)
		(zone
			(layer "F.Cu")
			(hatch none 0.5)
			(connect_pads
				(clearance 0)
			)
			(min_thickness 0.25)
			(keepout
				(tracks not_allowed)
				(vias allowed)
				(pads allowed)
				(copperpour not_allowed)
				(footprints allowed)
			)
			(placement
				(enabled no)
				(sheetname "")
			)
			(fill
				(thermal_gap 0.5)
				(thermal_bridge_width 0.5)
				(island_removal_mode 0)
			)
			(polygon
				(pts
					(xy 73.990962 22.105493) (xy 73.990962 21.978493) (xy 74.498962 21.978493) (xy 74.498962 22.105493)
				)
			)
		)
	)
	(footprint ""
		(layer "F.Cu")
		(at 28.575 42.545)
		(property "Reference" "R326"
			(at 0 0 0)
			(layer "F.SilkS")
			(hide yes)
			(effects
				(font
					(size 1.27 1.27)
				)
			)
		)
		(property "Value" "4.99K"
			(at -0.148158 1.3462 90)
			(unlocked yes)
			(layer "F.Fab")
			(hide yes)
			(effects
				(font
					(size 1.27 0.9652)
					(thickness 0.000001)
				)
				(justify left)
			)
		)
		(property "Device Type" "REST0014"
			(at -0.148158 1.3462 90)
			(unlocked yes)
			(layer "F.Fab")
			(hide yes)
			(effects
				(font
					(size 1.27 0.9652)
					(thickness 0.000001)
				)
				(justify left)
			)
		)
		(duplicate_pad_numbers_are_jumpers no)
		(fp_poly
			(pts
				(xy 0.635 1.0668) (xy 0.635 -1.0668) (xy -0.635 -1.0668) (xy -0.635 1.0668)
			)
			(stroke
				(width 0)
				(type default)
			)
			(fill no)
			(layer "F.CrtYd")
		)
		(fp_line
			(start -0.254 -0.508)
			(end 0.254 -0.508)
			(stroke
				(width 0.0254)
				(type default)
			)
			(layer "F.Fab")
		)
		(fp_line
			(start -0.254 0.508)
			(end -0.254 -0.508)
			(stroke
				(width 0.0254)
				(type default)
			)
			(layer "F.Fab")
		)
		(fp_line
			(start 0.254 -0.508)
			(end 0.254 0.508)
			(stroke
				(width 0.0254)
				(type default)
			)
			(layer "F.Fab")
		)
		(fp_line
			(start 0.254 0.508)
			(end -0.254 0.508)
			(stroke
				(width 0.0254)
				(type default)
			)
			(layer "F.Fab")
		)
		(pad "1" smd rect
			(at 0 -0.4191)
			(size 0.508 0.5334)
			(layers "F.Cu" "F.Mask" "F.Paste")
			(net "10N2498")
		)
		(pad "2" smd rect
			(at 0 0.4191)
			(size 0.508 0.5334)
			(layers "F.Cu" "F.Mask" "F.Paste")
			(net "10N2383")
		)
		(zone
			(layer "F.Cu")
			(hatch none 0.5)
			(connect_pads
				(clearance 0)
			)
			(min_thickness 0.25)
			(keepout
				(tracks not_allowed)
				(vias allowed)
				(pads allowed)
				(copperpour not_allowed)
				(footprints allowed)
			)
			(placement
				(enabled no)
				(sheetname "")
			)
			(fill
				(thermal_gap 0.5)
				(thermal_bridge_width 0.5)
				(island_removal_mode 0)
			)
			(polygon
				(pts
					(xy 28.6004 42.5196) (xy 28.6004 42.5704) (xy 28.5496 42.5704) (xy 28.5496 42.5196)
				)
			)
		)
	)
	(footprint ""
		(layer "F.Cu")
		(at 19.05 29.464 90)
		(property "Reference" "R63"
			(at 0 0 90)
			(layer "F.SilkS")
			(hide yes)
			(effects
				(font
					(size 1.27 1.27)
				)
			)
		)
		(property "Value" "4.75K"
			(at -0.148158 1.3462 180)
			(unlocked yes)
			(layer "F.Fab")
			(hide yes)
			(effects
				(font
					(size 1.27 0.9652)
					(thickness 0.000001)
				)
				(justify left)
			)
		)
		(property "Device Type" "REST4024"
			(at -0.148158 1.3462 180)
			(unlocked yes)
			(layer "F.Fab")
			(hide yes)
			(effects
				(font
					(size 1.27 0.9652)
					(thickness 0.000001)
				)
				(justify left)
			)
		)
		(duplicate_pad_numbers_are_jumpers no)
		(fp_poly
			(pts
				(xy 0.635 1.0668) (xy 0.635 -1.0668) (xy -0.635 -1.0668) (xy -0.635 1.0668)
			)
			(stroke
				(width 0)
				(type default)
			)
			(fill no)
			(layer "F.CrtYd")
		)
		(fp_line
			(start 0.254 -0.508)
			(end 0.254 0.508)
			(stroke
				(width 0.0254)
				(type default)
			)
			(layer "F.Fab")
		)
		(fp_line
			(start -0.254 -0.508)
			(end 0.254 -0.508)
			(stroke
				(width 0.0254)
				(type default)
			)
			(layer "F.Fab")
		)
		(fp_line
			(start 0.254 0.508)
			(end -0.254 0.508)
			(stroke
				(width 0.0254)
				(type default)
			)
			(layer "F.Fab")
		)
		(fp_line
			(start -0.254 0.508)
			(end -0.254 -0.508)
			(stroke
				(width 0.0254)
				(type default)
			)
			(layer "F.Fab")
		)
		(pad "1" smd rect
			(at 0 -0.4191 90)
			(size 0.508 0.5334)
			(layers "F.Cu" "F.Mask" "F.Paste")
			(net "EXT_3.3V")
		)
		(pad "2" smd rect
			(at 0 0.4191 90)
			(size 0.508 0.5334)
			(layers "F.Cu" "F.Mask" "F.Paste")
			(net "CPLD_PGRM_JTAG_TDI")
		)
		(zone
			(layer "F.Cu")
			(hatch none 0.5)
			(connect_pads
				(clearance 0)
			)
			(min_thickness 0.25)
			(keepout
				(tracks not_allowed)
				(vias allowed)
				(pads allowed)
				(copperpour not_allowed)
				(footprints allowed)
			)
			(placement
				(enabled no)
				(sheetname "")
			)
			(fill
				(thermal_gap 0.5)
				(thermal_bridge_width 0.5)
				(island_removal_mode 0)
			)
			(polygon
				(pts
					(xy 19.0246 29.4386) (xy 19.0754 29.4386) (xy 19.0754 29.4894) (xy 19.0246 29.4894)
				)
			)
		)
	)
	(footprint ""
		(layer "F.Cu")
		(at 1.778 31.75)
		(property "Reference" "TP47"
			(at -2.413 -1.75133 0)
			(unlocked yes)
			(layer "F.SilkS")
			(effects
				(font
					(size 0.7874 0.5842)
					(thickness 0.127)
				)
				(justify left)
			)
		)
		(property "Value" "*"
			(at -0.4826 -0.14732 0)
			(unlocked yes)
			(layer "F.Fab")
			(hide yes)
			(effects
				(font
					(size 1.27 0.9652)
					(thickness 0.000001)
				)
				(justify left)
			)
		)
		(property "Device Type" "TP_SMALL"
			(at -0.4826 -0.14732 0)
			(unlocked yes)
			(layer "F.Fab")
			(hide yes)
			(effects
				(font
					(size 1.27 0.9652)
					(thickness 0.000001)
				)
				(justify left)
			)
		)
		(duplicate_pad_numbers_are_jumpers no)
		(fp_line
			(start -0.8636 -0.8636)
			(end -0.8636 0.8636)
			(stroke
				(width 0.1524)
				(type default)
			)
			(layer "F.SilkS")
		)
		(fp_line
			(start -0.8636 0.8636)
			(end 0.8636 0.8636)
			(stroke
				(width 0.1524)
				(type default)
			)
			(layer "F.SilkS")
		)
		(fp_line
			(start 0.8636 -0.8636)
			(end -0.8636 -0.8636)
			(stroke
				(width 0.1524)
				(type default)
			)
			(layer "F.SilkS")
		)
		(fp_line
			(start 0.8636 0.8636)
			(end 0.8636 -0.8636)
			(stroke
				(width 0.1524)
				(type default)
			)
			(layer "F.SilkS")
		)
		(fp_poly
			(pts
				(xy -0.635 -0.635) (xy -0.635 0.635) (xy 0.635 0.635) (xy 0.635 -0.635)
			)
			(stroke
				(width 0)
				(type default)
			)
			(fill no)
			(layer "F.CrtYd")
		)
		(pad "1" smd rect
			(at 0 0)
			(size 1.27 1.27)
			(layers "F.Cu" "F.Mask" "F.Paste")
			(net "GND")
		)
	)
	(footprint ""
		(layer "F.Cu")
		(at 41.91 47.625)
		(property "Reference" "R101"
			(at -2.413 -1.24333 0)
			(unlocked yes)
			(layer "F.SilkS")
			(effects
				(font
					(size 0.7874 0.5842)
					(thickness 0.127)
				)
				(justify left)
			)
		)
		(property "Value" "4.75K"
			(at -0.148158 1.3462 90)
			(unlocked yes)
			(layer "F.Fab")
			(hide yes)
			(effects
				(font
					(size 1.27 0.9652)
					(thickness 0.000001)
				)
				(justify left)
			)
		)
		(property "Device Type" "REST4024"
			(at -0.148158 1.3462 90)
			(unlocked yes)
			(layer "F.Fab")
			(hide yes)
			(effects
				(font
					(size 1.27 0.9652)
					(thickness 0.000001)
				)
				(justify left)
			)
		)
		(duplicate_pad_numbers_are_jumpers no)
		(fp_poly
			(pts
				(xy 0.635 1.0668) (xy 0.635 -1.0668) (xy -0.635 -1.0668) (xy -0.635 1.0668)
			)
			(stroke
				(width 0)
				(type default)
			)
			(fill no)
			(layer "F.CrtYd")
		)
		(fp_line
			(start -0.254 -0.508)
			(end 0.254 -0.508)
			(stroke
				(width 0.0254)
				(type default)
			)
			(layer "F.Fab")
		)
		(fp_line
			(start -0.254 0.508)
			(end -0.254 -0.508)
			(stroke
				(width 0.0254)
				(type default)
			)
			(layer "F.Fab")
		)
		(fp_line
			(start 0.254 -0.508)
			(end 0.254 0.508)
			(stroke
				(width 0.0254)
				(type default)
			)
			(layer "F.Fab")
		)
		(fp_line
			(start 0.254 0.508)
			(end -0.254 0.508)
			(stroke
				(width 0.0254)
				(type default)
			)
			(layer "F.Fab")
		)
		(pad "1" smd rect
			(at 0 -0.4191)
			(size 0.508 0.5334)
			(layers "F.Cu" "F.Mask" "F.Paste")
			(net "GND")
		)
		(pad "2" smd rect
			(at 0 0.4191)
			(size 0.508 0.5334)
			(layers "F.Cu" "F.Mask" "F.Paste")
			(net "EXT_12.0V_PGOOD")
		)
		(zone
			(layer "F.Cu")
			(hatch none 0.5)
			(connect_pads
				(clearance 0)
			)
			(min_thickness 0.25)
			(keepout
				(tracks not_allowed)
				(vias allowed)
				(pads allowed)
				(copperpour not_allowed)
				(footprints allowed)
			)
			(placement
				(enabled no)
				(sheetname "")
			)
			(fill
				(thermal_gap 0.5)
				(thermal_bridge_width 0.5)
				(island_removal_mode 0)
			)
			(polygon
				(pts
					(xy 41.9354 47.5996) (xy 41.9354 47.6504) (xy 41.8846 47.6504) (xy 41.8846 47.5996)
				)
			)
		)
	)
	(footprint ""
		(layer "F.Cu")
		(at 42.799 53.1368)
		(property "Reference" "R279"
			(at -3.937 -0.15113 0)
			(unlocked yes)
			(layer "F.SilkS")
			(effects
				(font
					(size 0.7874 0.5842)
					(thickness 0.127)
				)
				(justify left)
			)
		)
		(property "Value" ""
			(at 0 0 0)
			(layer "F.Fab")
			(effects
				(font
					(size 1.27 1.27)
				)
			)
		)
		(duplicate_pad_numbers_are_jumpers no)
		(fp_line
			(start -0.0254 -0.127)
			(end 0.0254 -0.127)
			(stroke
				(width 0.1016)
				(type default)
			)
			(layer "F.SilkS")
		)
		(fp_line
			(start -0.0254 0.127)
			(end -0.0254 -0.127)
			(stroke
				(width 0.1016)
				(type default)
			)
			(layer "F.SilkS")
		)
		(fp_line
			(start 0.0254 -0.127)
			(end 0.0254 0.127)
			(stroke
				(width 0.1016)
				(type default)
			)
			(layer "F.SilkS")
		)
		(fp_line
			(start 0.0254 0.127)
			(end -0.0254 0.127)
			(stroke
				(width 0.1016)
				(type default)
			)
			(layer "F.SilkS")
		)
		(fp_poly
			(pts
				(xy 0.889 -0.4953) (xy 0.889 0.4953) (xy -0.889 0.4953) (xy -0.889 -0.4953)
			)
			(stroke
				(width 0)
				(type default)
			)
			(fill no)
			(layer "F.CrtYd")
		)
		(fp_line
			(start -0.508 -0.254)
			(end -0.508 0.254)
			(stroke
				(width 0.0254)
				(type default)
			)
			(layer "F.Fab")
		)
		(fp_line
			(start -0.508 0.254)
			(end 0.508 0.254)
			(stroke
				(width 0.0254)
				(type default)
			)
			(layer "F.Fab")
		)
		(fp_line
			(start 0.508 -0.254)
			(end -0.508 -0.254)
			(stroke
				(width 0.0254)
				(type default)
			)
			(layer "F.Fab")
		)
		(fp_line
			(start 0.508 0.254)
			(end 0.508 -0.254)
			(stroke
				(width 0.0254)
				(type default)
			)
			(layer "F.Fab")
		)
		(pad "1" smd rect
			(at -0.4699 0)
			(size 0.5334 0.508)
			(layers "F.Cu" "F.Mask" "F.Paste")
			(net "EXT_12.0V_THRESHOLD")
		)
		(pad "2" smd rect
			(at 0.4699 0)
			(size 0.5334 0.508)
			(layers "F.Cu" "F.Mask" "F.Paste")
			(net "EXT_12.0V")
		)
	)
	(footprint ""
		(layer "F.Cu")
		(at 45.466 53.1368 -90)
		(property "Reference" "R278"
			(at 0 0 270)
			(layer "F.SilkS")
			(hide yes)
			(effects
				(font
					(size 1.27 1.27)
				)
			)
		)
		(property "Value" "240"
			(at -0.148158 1.3462 0)
			(unlocked yes)
			(layer "F.Fab")
			(hide yes)
			(effects
				(font
					(size 1.27 0.9652)
					(thickness 0.000001)
				)
				(justify left)
			)
		)
		(property "Device Type" "REST0009"
			(at -0.148158 1.3462 0)
			(unlocked yes)
			(layer "F.Fab")
			(hide yes)
			(effects
				(font
					(size 1.27 0.9652)
					(thickness 0.000001)
				)
				(justify left)
			)
		)
		(duplicate_pad_numbers_are_jumpers no)
		(fp_poly
			(pts
				(xy 0.635 1.0668) (xy 0.635 -1.0668) (xy -0.635 -1.0668) (xy -0.635 1.0668)
			)
			(stroke
				(width 0)
				(type default)
			)
			(fill no)
			(layer "F.CrtYd")
		)
		(fp_line
			(start -0.254 0.508)
			(end -0.254 -0.508)
			(stroke
				(width 0.0254)
				(type default)
			)
			(layer "F.Fab")
		)
		(fp_line
			(start 0.254 0.508)
			(end -0.254 0.508)
			(stroke
				(width 0.0254)
				(type default)
			)
			(layer "F.Fab")
		)
		(fp_line
			(start -0.254 -0.508)
			(end 0.254 -0.508)
			(stroke
				(width 0.0254)
				(type default)
			)
			(layer "F.Fab")
		)
		(fp_line
			(start 0.254 -0.508)
			(end 0.254 0.508)
			(stroke
				(width 0.0254)
				(type default)
			)
			(layer "F.Fab")
		)
		(pad "1" smd rect
			(at 0 -0.4191 270)
			(size 0.508 0.5334)
			(layers "F.Cu" "F.Mask" "F.Paste")
			(net "0.7V_REF")
		)
		(pad "2" smd rect
			(at 0 0.4191 270)
			(size 0.508 0.5334)
			(layers "F.Cu" "F.Mask" "F.Paste")
			(net "EXT_3.3V")
		)
		(zone
			(layer "F.Cu")
			(hatch none 0.5)
			(connect_pads
				(clearance 0)
			)
			(min_thickness 0.25)
			(keepout
				(tracks not_allowed)
				(vias allowed)
				(pads allowed)
				(copperpour not_allowed)
				(footprints allowed)
			)
			(placement
				(enabled no)
				(sheetname "")
			)
			(fill
				(thermal_gap 0.5)
				(thermal_bridge_width 0.5)
				(island_removal_mode 0)
			)
			(polygon
				(pts
					(xy 45.4914 53.1622) (xy 45.4406 53.1622) (xy 45.4406 53.1114) (xy 45.4914 53.1114)
				)
			)
		)
	)
	(footprint ""
		(layer "F.Cu")
		(at 28.321 32.639 180)
		(property "Reference" "R92"
			(at 0 0 180)
			(layer "F.SilkS")
			(hide yes)
			(effects
				(font
					(size 1.27 1.27)
				)
			)
		)
		(property "Value" "4.75K"
			(at -0.148158 1.3462 270)
			(unlocked yes)
			(layer "F.Fab")
			(hide yes)
			(effects
				(font
					(size 1.27 0.9652)
					(thickness 0.000001)
				)
				(justify left)
			)
		)
		(property "Device Type" "REST4024"
			(at -0.148158 1.3462 270)
			(unlocked yes)
			(layer "F.Fab")
			(hide yes)
			(effects
				(font
					(size 1.27 0.9652)
					(thickness 0.000001)
				)
				(justify left)
			)
		)
		(duplicate_pad_numbers_are_jumpers no)
		(fp_poly
			(pts
				(xy 0.635 1.0668) (xy 0.635 -1.0668) (xy -0.635 -1.0668) (xy -0.635 1.0668)
			)
			(stroke
				(width 0)
				(type default)
			)
			(fill no)
			(layer "F.CrtYd")
		)
		(fp_line
			(start 0.254 0.508)
			(end -0.254 0.508)
			(stroke
				(width 0.0254)
				(type default)
			)
			(layer "F.Fab")
		)
		(fp_line
			(start 0.254 -0.508)
			(end 0.254 0.508)
			(stroke
				(width 0.0254)
				(type default)
			)
			(layer "F.Fab")
		)
		(fp_line
			(start -0.254 0.508)
			(end -0.254 -0.508)
			(stroke
				(width 0.0254)
				(type default)
			)
			(layer "F.Fab")
		)
		(fp_line
			(start -0.254 -0.508)
			(end 0.254 -0.508)
			(stroke
				(width 0.0254)
				(type default)
			)
			(layer "F.Fab")
		)
		(pad "1" smd rect
			(at 0 -0.4191 180)
			(size 0.508 0.5334)
			(layers "F.Cu" "F.Mask" "F.Paste")
			(net "_NFP_CORE_VID1")
		)
		(pad "2" smd rect
			(at 0 0.4191 180)
			(size 0.508 0.5334)
			(layers "F.Cu" "F.Mask" "F.Paste")
			(net "VDD_1.2V")
		)
		(zone
			(layer "F.Cu")
			(hatch none 0.5)
			(connect_pads
				(clearance 0)
			)
			(min_thickness 0.25)
			(keepout
				(tracks not_allowed)
				(vias allowed)
				(pads allowed)
				(copperpour not_allowed)
				(footprints allowed)
			)
			(placement
				(enabled no)
				(sheetname "")
			)
			(fill
				(thermal_gap 0.5)
				(thermal_bridge_width 0.5)
				(island_removal_mode 0)
			)
			(polygon
				(pts
					(xy 28.2956 32.6644) (xy 28.2956 32.6136) (xy 28.3464 32.6136) (xy 28.3464 32.6644)
				)
			)
		)
	)
	(footprint ""
		(layer "F.Cu")
		(at 19.558 2.9972 180)
		(property "Reference" "C284"
			(at 0 0 180)
			(layer "F.SilkS")
			(hide yes)
			(effects
				(font
					(size 1.27 1.27)
				)
			)
		)
		(property "Value" "0.1UF"
			(at -0.091846 0.2921 270)
			(unlocked yes)
			(layer "F.Fab")
			(hide yes)
			(effects
				(font
					(size 0.7874 0.5842)
					(thickness 0.2032)
				)
				(justify left)
			)
		)
		(property "Device Type" "CAPC0073"
			(at -0.091846 0.2921 270)
			(unlocked yes)
			(layer "F.Fab")
			(hide yes)
			(effects
				(font
					(size 0.7874 0.5842)
					(thickness 0.2032)
				)
				(justify left)
			)
		)
		(duplicate_pad_numbers_are_jumpers no)
		(fp_poly
			(pts
				(xy 0.635 1.0668) (xy 0.635 -1.0668) (xy -0.635 -1.0668) (xy -0.635 1.0668)
			)
			(stroke
				(width 0)
				(type default)
			)
			(fill no)
			(layer "F.CrtYd")
		)
		(fp_line
			(start 0.254 0.508)
			(end -0.254 0.508)
			(stroke
				(width 0.0254)
				(type default)
			)
			(layer "F.Fab")
		)
		(fp_line
			(start 0.254 -0.508)
			(end 0.254 0.508)
			(stroke
				(width 0.0254)
				(type default)
			)
			(layer "F.Fab")
		)
		(fp_line
			(start -0.254 0.508)
			(end -0.254 -0.508)
			(stroke
				(width 0.0254)
				(type default)
			)
			(layer "F.Fab")
		)
		(fp_line
			(start -0.254 -0.508)
			(end 0.254 -0.508)
			(stroke
				(width 0.0254)
				(type default)
			)
			(layer "F.Fab")
		)
		(pad "1" smd rect
			(at 0 -0.4191 180)
			(size 0.508 0.5334)
			(layers "F.Cu" "F.Mask" "F.Paste")
			(net "EXT_3.3V")
		)
		(pad "2" smd rect
			(at 0 0.4191 180)
			(size 0.508 0.5334)
			(layers "F.Cu" "F.Mask" "F.Paste")
			(net "GND")
		)
		(zone
			(layer "F.Cu")
			(hatch none 0.5)
			(connect_pads
				(clearance 0)
			)
			(min_thickness 0.25)
			(keepout
				(tracks not_allowed)
				(vias allowed)
				(pads allowed)
				(copperpour not_allowed)
				(footprints allowed)
			)
			(placement
				(enabled no)
				(sheetname "")
			)
			(fill
				(thermal_gap 0.5)
				(thermal_bridge_width 0.5)
				(island_removal_mode 0)
			)
			(polygon
				(pts
					(xy 19.5326 3.0226) (xy 19.5326 2.9718) (xy 19.5834 2.9718) (xy 19.5834 3.0226)
				)
			)
		)
	)
	(footprint ""
		(layer "F.Cu")
		(at 79.450997 14.256004)
		(property "Reference" "V2_A-CAS"
			(at 0 0 0)
			(layer "F.SilkS")
			(hide yes)
			(effects
				(font
					(size 1.27 1.27)
				)
			)
		)
		(property "Value" ""
			(at 0 0 0)
			(layer "F.Fab")
			(effects
				(font
					(size 1.27 1.27)
				)
			)
		)
		(duplicate_pad_numbers_are_jumpers no)
		(pad "1" thru_hole circle
			(at 0 0)
			(size 0.762 0.762)
			(drill 0.20574)
			(layers "*.Cu" "*.Mask")
			(remove_unused_layers no)
			(net "DDR0_32A_CAS_L")
			(clearance 0.127)
			(thermal_gap 0.127)
			(padstack
				(mode front_inner_back)
				(layer "Inner"
					(shape circle)
					(size 0.4572 0.4572)
					(clearance 0.1143)
				)
				(layer "B.Cu"
					(shape circle)
					(size 0.4572 0.4572)
					(clearance 0.1143)
				)
			)
		)
	)
	(footprint ""
		(layer "F.Cu")
		(at 83.693 26.924)
		(property "Reference" "R215"
			(at 0 0 0)
			(layer "F.SilkS")
			(hide yes)
			(effects
				(font
					(size 1.27 1.27)
				)
			)
		)
		(property "Value" "39.0"
			(at -0.148158 1.3462 90)
			(unlocked yes)
			(layer "F.Fab")
			(hide yes)
			(effects
				(font
					(size 1.27 0.9652)
					(thickness 0.000001)
				)
				(justify left)
			)
		)
		(property "Device Type" "REST0108"
			(at -0.148158 1.3462 90)
			(unlocked yes)
			(layer "F.Fab")
			(hide yes)
			(effects
				(font
					(size 1.27 0.9652)
					(thickness 0.000001)
				)
				(justify left)
			)
		)
		(duplicate_pad_numbers_are_jumpers no)
		(fp_poly
			(pts
				(xy 0.635 1.0668) (xy 0.635 -1.0668) (xy -0.635 -1.0668) (xy -0.635 1.0668)
			)
			(stroke
				(width 0)
				(type default)
			)
			(fill no)
			(layer "F.CrtYd")
		)
		(fp_line
			(start -0.254 -0.508)
			(end 0.254 -0.508)
			(stroke
				(width 0.0254)
				(type default)
			)
			(layer "F.Fab")
		)
		(fp_line
			(start -0.254 0.508)
			(end -0.254 -0.508)
			(stroke
				(width 0.0254)
				(type default)
			)
			(layer "F.Fab")
		)
		(fp_line
			(start 0.254 -0.508)
			(end 0.254 0.508)
			(stroke
				(width 0.0254)
				(type default)
			)
			(layer "F.Fab")
		)
		(fp_line
			(start 0.254 0.508)
			(end -0.254 0.508)
			(stroke
				(width 0.0254)
				(type default)
			)
			(layer "F.Fab")
		)
		(pad "1" smd rect
			(at 0 -0.4191)
			(size 0.508 0.5334)
			(layers "F.Cu" "F.Mask" "F.Paste")
			(net "DDR0_32A_A9")
		)
		(pad "2" smd rect
			(at 0 0.4191)
			(size 0.508 0.5334)
			(layers "F.Cu" "F.Mask" "F.Paste")
			(net "DDR_VTT")
		)
		(zone
			(layer "F.Cu")
			(hatch none 0.5)
			(connect_pads
				(clearance 0)
			)
			(min_thickness 0.25)
			(keepout
				(tracks not_allowed)
				(vias allowed)
				(pads allowed)
				(copperpour not_allowed)
				(footprints allowed)
			)
			(placement
				(enabled no)
				(sheetname "")
			)
			(fill
				(thermal_gap 0.5)
				(thermal_bridge_width 0.5)
				(island_removal_mode 0)
			)
			(polygon
				(pts
					(xy 83.7184 26.8986) (xy 83.7184 26.9494) (xy 83.6676 26.9494) (xy 83.6676 26.8986)
				)
			)
		)
	)
	(footprint ""
		(layer "F.Cu")
		(at 34.29 2.286)
		(property "Reference" "R14"
			(at -1.24333 -0.889 90)
			(unlocked yes)
			(layer "F.SilkS")
			(effects
				(font
					(size 0.7874 0.5842)
					(thickness 0.127)
				)
				(justify left)
			)
		)
		(property "Value" "4.75K"
			(at -0.148158 1.3462 90)
			(unlocked yes)
			(layer "F.Fab")
			(hide yes)
			(effects
				(font
					(size 1.27 0.9652)
					(thickness 0.000001)
				)
				(justify left)
			)
		)
		(property "Device Type" "REST4024"
			(at -0.148158 1.3462 90)
			(unlocked yes)
			(layer "F.Fab")
			(hide yes)
			(effects
				(font
					(size 1.27 0.9652)
					(thickness 0.000001)
				)
				(justify left)
			)
		)
		(duplicate_pad_numbers_are_jumpers no)
		(fp_poly
			(pts
				(xy 0.635 1.0668) (xy 0.635 -1.0668) (xy -0.635 -1.0668) (xy -0.635 1.0668)
			)
			(stroke
				(width 0)
				(type default)
			)
			(fill no)
			(layer "F.CrtYd")
		)
		(fp_line
			(start -0.254 -0.508)
			(end 0.254 -0.508)
			(stroke
				(width 0.0254)
				(type default)
			)
			(layer "F.Fab")
		)
		(fp_line
			(start -0.254 0.508)
			(end -0.254 -0.508)
			(stroke
				(width 0.0254)
				(type default)
			)
			(layer "F.Fab")
		)
		(fp_line
			(start 0.254 -0.508)
			(end 0.254 0.508)
			(stroke
				(width 0.0254)
				(type default)
			)
			(layer "F.Fab")
		)
		(fp_line
			(start 0.254 0.508)
			(end -0.254 0.508)
			(stroke
				(width 0.0254)
				(type default)
			)
			(layer "F.Fab")
		)
		(pad "1" smd rect
			(at 0 -0.4191)
			(size 0.508 0.5334)
			(layers "F.Cu" "F.Mask" "F.Paste")
			(net "EXT_3.3V")
		)
		(pad "2" smd rect
			(at 0 0.4191)
			(size 0.508 0.5334)
			(layers "F.Cu" "F.Mask" "F.Paste")
			(net "3N2287")
		)
		(zone
			(layer "F.Cu")
			(hatch none 0.5)
			(connect_pads
				(clearance 0)
			)
			(min_thickness 0.25)
			(keepout
				(tracks not_allowed)
				(vias allowed)
				(pads allowed)
				(copperpour not_allowed)
				(footprints allowed)
			)
			(placement
				(enabled no)
				(sheetname "")
			)
			(fill
				(thermal_gap 0.5)
				(thermal_bridge_width 0.5)
				(island_removal_mode 0)
			)
			(polygon
				(pts
					(xy 34.3154 2.2606) (xy 34.3154 2.3114) (xy 34.2646 2.3114) (xy 34.2646 2.2606)
				)
			)
		)
	)
	(footprint ""
		(layer "F.Cu")
		(at 81.4578 32.258 -90)
		(property "Reference" "C218"
			(at -0.86233 1.8288 0)
			(unlocked yes)
			(layer "F.SilkS")
			(effects
				(font
					(size 0.7874 0.5842)
					(thickness 0.127)
				)
				(justify left)
			)
		)
		(property "Value" "1UF"
			(at -0.091846 0.2921 0)
			(unlocked yes)
			(layer "F.Fab")
			(hide yes)
			(effects
				(font
					(size 0.7874 0.5842)
					(thickness 0.2032)
				)
				(justify left)
			)
		)
		(property "Device Type" "CAPC0028"
			(at -0.091846 0.2921 0)
			(unlocked yes)
			(layer "F.Fab")
			(hide yes)
			(effects
				(font
					(size 0.7874 0.5842)
					(thickness 0.2032)
				)
				(justify left)
			)
		)
		(duplicate_pad_numbers_are_jumpers no)
		(fp_poly
			(pts
				(xy 0.635 1.0668) (xy 0.635 -1.0668) (xy -0.635 -1.0668) (xy -0.635 1.0668)
			)
			(stroke
				(width 0)
				(type default)
			)
			(fill no)
			(layer "F.CrtYd")
		)
		(fp_line
			(start -0.254 0.508)
			(end -0.254 -0.508)
			(stroke
				(width 0.0254)
				(type default)
			)
			(layer "F.Fab")
		)
		(fp_line
			(start 0.254 0.508)
			(end -0.254 0.508)
			(stroke
				(width 0.0254)
				(type default)
			)
			(layer "F.Fab")
		)
		(fp_line
			(start -0.254 -0.508)
			(end 0.254 -0.508)
			(stroke
				(width 0.0254)
				(type default)
			)
			(layer "F.Fab")
		)
		(fp_line
			(start 0.254 -0.508)
			(end 0.254 0.508)
			(stroke
				(width 0.0254)
				(type default)
			)
			(layer "F.Fab")
		)
		(pad "1" smd rect
			(at 0 -0.4191 270)
			(size 0.508 0.5334)
			(layers "F.Cu" "F.Mask" "F.Paste")
			(net "DDR_VDDQ")
		)
		(pad "2" smd rect
			(at 0 0.4191 270)
			(size 0.508 0.5334)
			(layers "F.Cu" "F.Mask" "F.Paste")
			(net "GND")
		)
		(zone
			(layer "F.Cu")
			(hatch none 0.5)
			(connect_pads
				(clearance 0)
			)
			(min_thickness 0.25)
			(keepout
				(tracks not_allowed)
				(vias allowed)
				(pads allowed)
				(copperpour not_allowed)
				(footprints allowed)
			)
			(placement
				(enabled no)
				(sheetname "")
			)
			(fill
				(thermal_gap 0.5)
				(thermal_bridge_width 0.5)
				(island_removal_mode 0)
			)
			(polygon
				(pts
					(xy 81.4832 32.2834) (xy 81.4324 32.2834) (xy 81.4324 32.2326) (xy 81.4832 32.2326)
				)
			)
		)
	)
	(footprint ""
		(layer "F.Cu")
		(at 32.766 32.639)
		(property "Reference" "R91"
			(at 0 0 0)
			(layer "F.SilkS")
			(hide yes)
			(effects
				(font
					(size 1.27 1.27)
				)
			)
		)
		(property "Value" "4.75K"
			(at -0.148158 1.3462 90)
			(unlocked yes)
			(layer "F.Fab")
			(hide yes)
			(effects
				(font
					(size 1.27 0.9652)
					(thickness 0.000001)
				)
				(justify left)
			)
		)
		(property "Device Type" "REST4024"
			(at -0.148158 1.3462 90)
			(unlocked yes)
			(layer "F.Fab")
			(hide yes)
			(effects
				(font
					(size 1.27 0.9652)
					(thickness 0.000001)
				)
				(justify left)
			)
		)
		(duplicate_pad_numbers_are_jumpers no)
		(fp_poly
			(pts
				(xy 0.635 1.0668) (xy 0.635 -1.0668) (xy -0.635 -1.0668) (xy -0.635 1.0668)
			)
			(stroke
				(width 0)
				(type default)
			)
			(fill no)
			(layer "F.CrtYd")
		)
		(fp_line
			(start -0.254 -0.508)
			(end 0.254 -0.508)
			(stroke
				(width 0.0254)
				(type default)
			)
			(layer "F.Fab")
		)
		(fp_line
			(start -0.254 0.508)
			(end -0.254 -0.508)
			(stroke
				(width 0.0254)
				(type default)
			)
			(layer "F.Fab")
		)
		(fp_line
			(start 0.254 -0.508)
			(end 0.254 0.508)
			(stroke
				(width 0.0254)
				(type default)
			)
			(layer "F.Fab")
		)
		(fp_line
			(start 0.254 0.508)
			(end -0.254 0.508)
			(stroke
				(width 0.0254)
				(type default)
			)
			(layer "F.Fab")
		)
		(pad "1" smd rect
			(at 0 -0.4191)
			(size 0.508 0.5334)
			(layers "F.Cu" "F.Mask" "F.Paste")
			(net "GND")
		)
		(pad "2" smd rect
			(at 0 0.4191)
			(size 0.508 0.5334)
			(layers "F.Cu" "F.Mask" "F.Paste")
			(net "_NFP_CORE_VID4")
		)
		(zone
			(layer "F.Cu")
			(hatch none 0.5)
			(connect_pads
				(clearance 0)
			)
			(min_thickness 0.25)
			(keepout
				(tracks not_allowed)
				(vias allowed)
				(pads allowed)
				(copperpour not_allowed)
				(footprints allowed)
			)
			(placement
				(enabled no)
				(sheetname "")
			)
			(fill
				(thermal_gap 0.5)
				(thermal_bridge_width 0.5)
				(island_removal_mode 0)
			)
			(polygon
				(pts
					(xy 32.7914 32.6136) (xy 32.7914 32.6644) (xy 32.7406 32.6644) (xy 32.7406 32.6136)
				)
			)
		)
	)
	(footprint ""
		(layer "F.Cu")
		(at 18.415 6.604 180)
		(property "Reference" "R391"
			(at 0 0 180)
			(layer "F.SilkS")
			(hide yes)
			(effects
				(font
					(size 1.27 1.27)
				)
			)
		)
		(property "Value" "0"
			(at -0.148158 1.3462 270)
			(unlocked yes)
			(layer "F.Fab")
			(hide yes)
			(effects
				(font
					(size 1.27 0.9652)
					(thickness 0.000001)
				)
				(justify left)
			)
		)
		(property "Device Type" "REST1111"
			(at -0.148158 1.3462 270)
			(unlocked yes)
			(layer "F.Fab")
			(hide yes)
			(effects
				(font
					(size 1.27 0.9652)
					(thickness 0.000001)
				)
				(justify left)
			)
		)
		(duplicate_pad_numbers_are_jumpers no)
		(fp_poly
			(pts
				(xy 0.635 1.0668) (xy 0.635 -1.0668) (xy -0.635 -1.0668) (xy -0.635 1.0668)
			)
			(stroke
				(width 0)
				(type default)
			)
			(fill no)
			(layer "F.CrtYd")
		)
		(fp_line
			(start 0.254 0.508)
			(end -0.254 0.508)
			(stroke
				(width 0.0254)
				(type default)
			)
			(layer "F.Fab")
		)
		(fp_line
			(start 0.254 -0.508)
			(end 0.254 0.508)
			(stroke
				(width 0.0254)
				(type default)
			)
			(layer "F.Fab")
		)
		(fp_line
			(start -0.254 0.508)
			(end -0.254 -0.508)
			(stroke
				(width 0.0254)
				(type default)
			)
			(layer "F.Fab")
		)
		(fp_line
			(start -0.254 -0.508)
			(end 0.254 -0.508)
			(stroke
				(width 0.0254)
				(type default)
			)
			(layer "F.Fab")
		)
		(pad "1" smd rect
			(at 0 -0.4191 180)
			(size 0.508 0.5334)
			(layers "F.Cu" "F.Mask" "F.Paste")
			(net "NFP_SMBUS_ALERT_L")
		)
		(pad "2" smd rect
			(at 0 0.4191 180)
			(size 0.508 0.5334)
			(layers "F.Cu" "F.Mask" "F.Paste")
			(net "SMBUS_ALERT_L")
		)
		(zone
			(layer "F.Cu")
			(hatch none 0.5)
			(connect_pads
				(clearance 0)
			)
			(min_thickness 0.25)
			(keepout
				(tracks not_allowed)
				(vias allowed)
				(pads allowed)
				(copperpour not_allowed)
				(footprints allowed)
			)
			(placement
				(enabled no)
				(sheetname "")
			)
			(fill
				(thermal_gap 0.5)
				(thermal_bridge_width 0.5)
				(island_removal_mode 0)
			)
			(polygon
				(pts
					(xy 18.3896 6.6294) (xy 18.3896 6.5786) (xy 18.4404 6.5786) (xy 18.4404 6.6294)
				)
			)
		)
	)
	(footprint ""
		(layer "F.Cu")
		(at 21.971 35.687 180)
		(property "Reference" "R70"
			(at 0 0 180)
			(layer "F.SilkS")
			(hide yes)
			(effects
				(font
					(size 1.27 1.27)
				)
			)
		)
		(property "Value" "4.75K"
			(at -0.148158 1.3462 270)
			(unlocked yes)
			(layer "F.Fab")
			(hide yes)
			(effects
				(font
					(size 1.27 0.9652)
					(thickness 0.000001)
				)
				(justify left)
			)
		)
		(property "Device Type" "REST4024"
			(at -0.148158 1.3462 270)
			(unlocked yes)
			(layer "F.Fab")
			(hide yes)
			(effects
				(font
					(size 1.27 0.9652)
					(thickness 0.000001)
				)
				(justify left)
			)
		)
		(duplicate_pad_numbers_are_jumpers no)
		(fp_poly
			(pts
				(xy 0.635 1.0668) (xy 0.635 -1.0668) (xy -0.635 -1.0668) (xy -0.635 1.0668)
			)
			(stroke
				(width 0)
				(type default)
			)
			(fill no)
			(layer "F.CrtYd")
		)
		(fp_line
			(start 0.254 0.508)
			(end -0.254 0.508)
			(stroke
				(width 0.0254)
				(type default)
			)
			(layer "F.Fab")
		)
		(fp_line
			(start 0.254 -0.508)
			(end 0.254 0.508)
			(stroke
				(width 0.0254)
				(type default)
			)
			(layer "F.Fab")
		)
		(fp_line
			(start -0.254 0.508)
			(end -0.254 -0.508)
			(stroke
				(width 0.0254)
				(type default)
			)
			(layer "F.Fab")
		)
		(fp_line
			(start -0.254 -0.508)
			(end 0.254 -0.508)
			(stroke
				(width 0.0254)
				(type default)
			)
			(layer "F.Fab")
		)
		(pad "1" smd rect
			(at 0 -0.4191 180)
			(size 0.508 0.5334)
			(layers "F.Cu" "F.Mask" "F.Paste")
			(net "EXT_3.3V")
		)
		(pad "2" smd rect
			(at 0 0.4191 180)
			(size 0.508 0.5334)
			(layers "F.Cu" "F.Mask" "F.Paste")
			(net "DEBUG_CPLD_PGRM_JTAG_TDO")
		)
		(zone
			(layer "F.Cu")
			(hatch none 0.5)
			(connect_pads
				(clearance 0)
			)
			(min_thickness 0.25)
			(keepout
				(tracks not_allowed)
				(vias allowed)
				(pads allowed)
				(copperpour not_allowed)
				(footprints allowed)
			)
			(placement
				(enabled no)
				(sheetname "")
			)
			(fill
				(thermal_gap 0.5)
				(thermal_bridge_width 0.5)
				(island_removal_mode 0)
			)
			(polygon
				(pts
					(xy 21.9456 35.7124) (xy 21.9456 35.6616) (xy 21.9964 35.6616) (xy 21.9964 35.7124)
				)
			)
		)
	)
	(footprint ""
		(layer "F.Cu")
		(at 28.702 44.323)
		(property "Reference" "C48"
			(at 0 0 0)
			(layer "F.SilkS")
			(hide yes)
			(effects
				(font
					(size 1.27 1.27)
				)
			)
		)
		(property "Value" "1000PF"
			(at -0.091846 0.2921 90)
			(unlocked yes)
			(layer "F.Fab")
			(hide yes)
			(effects
				(font
					(size 0.7874 0.5842)
					(thickness 0.2032)
				)
				(justify left)
			)
		)
		(property "Device Type" "CAPC0083"
			(at -0.091846 0.2921 90)
			(unlocked yes)
			(layer "F.Fab")
			(hide yes)
			(effects
				(font
					(size 0.7874 0.5842)
					(thickness 0.2032)
				)
				(justify left)
			)
		)
		(duplicate_pad_numbers_are_jumpers no)
		(fp_poly
			(pts
				(xy 0.635 1.0668) (xy 0.635 -1.0668) (xy -0.635 -1.0668) (xy -0.635 1.0668)
			)
			(stroke
				(width 0)
				(type default)
			)
			(fill no)
			(layer "F.CrtYd")
		)
		(fp_line
			(start -0.254 -0.508)
			(end 0.254 -0.508)
			(stroke
				(width 0.0254)
				(type default)
			)
			(layer "F.Fab")
		)
		(fp_line
			(start -0.254 0.508)
			(end -0.254 -0.508)
			(stroke
				(width 0.0254)
				(type default)
			)
			(layer "F.Fab")
		)
		(fp_line
			(start 0.254 -0.508)
			(end 0.254 0.508)
			(stroke
				(width 0.0254)
				(type default)
			)
			(layer "F.Fab")
		)
		(fp_line
			(start 0.254 0.508)
			(end -0.254 0.508)
			(stroke
				(width 0.0254)
				(type default)
			)
			(layer "F.Fab")
		)
		(pad "1" smd rect
			(at 0 -0.4191)
			(size 0.508 0.5334)
			(layers "F.Cu" "F.Mask" "F.Paste")
			(net "10N2384")
		)
		(pad "2" smd rect
			(at 0 0.4191)
			(size 0.508 0.5334)
			(layers "F.Cu" "F.Mask" "F.Paste")
			(net "10N2386")
		)
		(zone
			(layer "F.Cu")
			(hatch none 0.5)
			(connect_pads
				(clearance 0)
			)
			(min_thickness 0.25)
			(keepout
				(tracks not_allowed)
				(vias allowed)
				(pads allowed)
				(copperpour not_allowed)
				(footprints allowed)
			)
			(placement
				(enabled no)
				(sheetname "")
			)
			(fill
				(thermal_gap 0.5)
				(thermal_bridge_width 0.5)
				(island_removal_mode 0)
			)
			(polygon
				(pts
					(xy 28.7274 44.2976) (xy 28.7274 44.3484) (xy 28.6766 44.3484) (xy 28.6766 44.2976)
				)
			)
		)
	)
	(footprint ""
		(layer "F.Cu")
		(at 2.159 36.83)
		(property "Reference" "TP15"
			(at -2.921 -1.49733 0)
			(unlocked yes)
			(layer "F.SilkS")
			(effects
				(font
					(size 0.7874 0.5842)
					(thickness 0.127)
				)
				(justify left)
			)
		)
		(property "Value" "*"
			(at -0.4826 -0.14732 0)
			(unlocked yes)
			(layer "F.Fab")
			(hide yes)
			(effects
				(font
					(size 1.27 0.9652)
					(thickness 0.000001)
				)
				(justify left)
			)
		)
		(property "Device Type" "TP_SMALL"
			(at -0.4826 -0.14732 0)
			(unlocked yes)
			(layer "F.Fab")
			(hide yes)
			(effects
				(font
					(size 1.27 0.9652)
					(thickness 0.000001)
				)
				(justify left)
			)
		)
		(duplicate_pad_numbers_are_jumpers no)
		(fp_line
			(start -0.8636 -0.8636)
			(end -0.8636 0.8636)
			(stroke
				(width 0.1524)
				(type default)
			)
			(layer "F.SilkS")
		)
		(fp_line
			(start -0.8636 0.8636)
			(end 0.8636 0.8636)
			(stroke
				(width 0.1524)
				(type default)
			)
			(layer "F.SilkS")
		)
		(fp_line
			(start 0.8636 -0.8636)
			(end -0.8636 -0.8636)
			(stroke
				(width 0.1524)
				(type default)
			)
			(layer "F.SilkS")
		)
		(fp_line
			(start 0.8636 0.8636)
			(end 0.8636 -0.8636)
			(stroke
				(width 0.1524)
				(type default)
			)
			(layer "F.SilkS")
		)
		(fp_poly
			(pts
				(xy -0.635 -0.635) (xy -0.635 0.635) (xy 0.635 0.635) (xy 0.635 -0.635)
			)
			(stroke
				(width 0)
				(type default)
			)
			(fill no)
			(layer "F.CrtYd")
		)
		(pad "1" smd rect
			(at 0 0)
			(size 1.27 1.27)
			(layers "F.Cu" "F.Mask" "F.Paste")
			(net "PSU_I2C_SCL")
		)
	)
	(footprint ""
		(layer "F.Cu")
		(at 29.972 42.926 90)
		(property "Reference" "C52"
			(at 0 0 90)
			(layer "F.SilkS")
			(hide yes)
			(effects
				(font
					(size 1.27 1.27)
				)
			)
		)
		(property "Value" "68PF"
			(at -0.091846 0.2921 180)
			(unlocked yes)
			(layer "F.Fab")
			(hide yes)
			(effects
				(font
					(size 0.7874 0.5842)
					(thickness 0.2032)
				)
				(justify left)
			)
		)
		(property "Device Type" "CAPC0030"
			(at -0.091846 0.2921 180)
			(unlocked yes)
			(layer "F.Fab")
			(hide yes)
			(effects
				(font
					(size 0.7874 0.5842)
					(thickness 0.2032)
				)
				(justify left)
			)
		)
		(duplicate_pad_numbers_are_jumpers no)
		(fp_poly
			(pts
				(xy 0.635 1.0668) (xy 0.635 -1.0668) (xy -0.635 -1.0668) (xy -0.635 1.0668)
			)
			(stroke
				(width 0)
				(type default)
			)
			(fill no)
			(layer "F.CrtYd")
		)
		(fp_line
			(start 0.254 -0.508)
			(end 0.254 0.508)
			(stroke
				(width 0.0254)
				(type default)
			)
			(layer "F.Fab")
		)
		(fp_line
			(start -0.254 -0.508)
			(end 0.254 -0.508)
			(stroke
				(width 0.0254)
				(type default)
			)
			(layer "F.Fab")
		)
		(fp_line
			(start 0.254 0.508)
			(end -0.254 0.508)
			(stroke
				(width 0.0254)
				(type default)
			)
			(layer "F.Fab")
		)
		(fp_line
			(start -0.254 0.508)
			(end -0.254 -0.508)
			(stroke
				(width 0.0254)
				(type default)
			)
			(layer "F.Fab")
		)
		(pad "1" smd rect
			(at 0 -0.4191 90)
			(size 0.508 0.5334)
			(layers "F.Cu" "F.Mask" "F.Paste")
			(net "10N2384")
		)
		(pad "2" smd rect
			(at 0 0.4191 90)
			(size 0.508 0.5334)
			(layers "F.Cu" "F.Mask" "F.Paste")
			(net "10N2504")
		)
		(zone
			(layer "F.Cu")
			(hatch none 0.5)
			(connect_pads
				(clearance 0)
			)
			(min_thickness 0.25)
			(keepout
				(tracks not_allowed)
				(vias allowed)
				(pads allowed)
				(copperpour not_allowed)
				(footprints allowed)
			)
			(placement
				(enabled no)
				(sheetname "")
			)
			(fill
				(thermal_gap 0.5)
				(thermal_bridge_width 0.5)
				(island_removal_mode 0)
			)
			(polygon
				(pts
					(xy 29.9466 42.9006) (xy 29.9974 42.9006) (xy 29.9974 42.9514) (xy 29.9466 42.9514)
				)
			)
		)
	)
	(footprint ""
		(layer "F.Cu")
		(at 76.251003 15.056002)
		(property "Reference" "V_A-DQS2-P"
			(at 0 0 0)
			(layer "F.SilkS")
			(hide yes)
			(effects
				(font
					(size 1.27 1.27)
				)
			)
		)
		(property "Value" ""
			(at 0 0 0)
			(layer "F.Fab")
			(effects
				(font
					(size 1.27 1.27)
				)
			)
		)
		(duplicate_pad_numbers_are_jumpers no)
		(pad "1" thru_hole circle
			(at 0 0)
			(size 0.762 0.762)
			(drill 0.20574)
			(layers "*.Cu" "*.Mask")
			(remove_unused_layers no)
			(net "DDR0_32A_DQS2_P")
			(clearance 0.127)
			(thermal_gap 0.127)
			(padstack
				(mode front_inner_back)
				(layer "Inner"
					(shape circle)
					(size 0.4572 0.4572)
					(clearance 0.1143)
				)
				(layer "B.Cu"
					(shape circle)
					(size 0.4572 0.4572)
					(clearance 0.1143)
				)
			)
		)
	)
	(footprint ""
		(layer "F.Cu")
		(at 35.941 5.207 90)
		(property "Reference" "C83"
			(at 0 0 90)
			(layer "F.SilkS")
			(hide yes)
			(effects
				(font
					(size 1.27 1.27)
				)
			)
		)
		(property "Value" "0.1UF"
			(at -0.091846 0.2921 180)
			(unlocked yes)
			(layer "F.Fab")
			(hide yes)
			(effects
				(font
					(size 0.7874 0.5842)
					(thickness 0.2032)
				)
				(justify left)
			)
		)
		(property "Device Type" "CAPC0073"
			(at -0.091846 0.2921 180)
			(unlocked yes)
			(layer "F.Fab")
			(hide yes)
			(effects
				(font
					(size 0.7874 0.5842)
					(thickness 0.2032)
				)
				(justify left)
			)
		)
		(duplicate_pad_numbers_are_jumpers no)
		(fp_poly
			(pts
				(xy 0.635 1.0668) (xy 0.635 -1.0668) (xy -0.635 -1.0668) (xy -0.635 1.0668)
			)
			(stroke
				(width 0)
				(type default)
			)
			(fill no)
			(layer "F.CrtYd")
		)
		(fp_line
			(start 0.254 -0.508)
			(end 0.254 0.508)
			(stroke
				(width 0.0254)
				(type default)
			)
			(layer "F.Fab")
		)
		(fp_line
			(start -0.254 -0.508)
			(end 0.254 -0.508)
			(stroke
				(width 0.0254)
				(type default)
			)
			(layer "F.Fab")
		)
		(fp_line
			(start 0.254 0.508)
			(end -0.254 0.508)
			(stroke
				(width 0.0254)
				(type default)
			)
			(layer "F.Fab")
		)
		(fp_line
			(start -0.254 0.508)
			(end -0.254 -0.508)
			(stroke
				(width 0.0254)
				(type default)
			)
			(layer "F.Fab")
		)
		(pad "1" smd rect
			(at 0 -0.4191 90)
			(size 0.508 0.5334)
			(layers "F.Cu" "F.Mask" "F.Paste")
			(net "EXT_3.3V")
		)
		(pad "2" smd rect
			(at 0 0.4191 90)
			(size 0.508 0.5334)
			(layers "F.Cu" "F.Mask" "F.Paste")
			(net "GND")
		)
		(zone
			(layer "F.Cu")
			(hatch none 0.5)
			(connect_pads
				(clearance 0)
			)
			(min_thickness 0.25)
			(keepout
				(tracks not_allowed)
				(vias allowed)
				(pads allowed)
				(copperpour not_allowed)
				(footprints allowed)
			)
			(placement
				(enabled no)
				(sheetname "")
			)
			(fill
				(thermal_gap 0.5)
				(thermal_bridge_width 0.5)
				(island_removal_mode 0)
			)
			(polygon
				(pts
					(xy 35.9156 5.1816) (xy 35.9664 5.1816) (xy 35.9664 5.2324) (xy 35.9156 5.2324)
				)
			)
		)
	)
	(footprint ""
		(layer "F.Cu")
		(at 35.941 4.064 90)
		(property "Reference" "C24"
			(at 0.73533 -0.254 0)
			(unlocked yes)
			(layer "F.SilkS")
			(effects
				(font
					(size 0.7874 0.5842)
					(thickness 0.127)
				)
				(justify left)
			)
		)
		(property "Value" "0.01UF"
			(at -0.091846 0.2921 180)
			(unlocked yes)
			(layer "F.Fab")
			(hide yes)
			(effects
				(font
					(size 0.7874 0.5842)
					(thickness 0.2032)
				)
				(justify left)
			)
		)
		(property "Device Type" "CAPC1553"
			(at -0.091846 0.2921 180)
			(unlocked yes)
			(layer "F.Fab")
			(hide yes)
			(effects
				(font
					(size 0.7874 0.5842)
					(thickness 0.2032)
				)
				(justify left)
			)
		)
		(duplicate_pad_numbers_are_jumpers no)
		(fp_poly
			(pts
				(xy 0.635 1.0668) (xy 0.635 -1.0668) (xy -0.635 -1.0668) (xy -0.635 1.0668)
			)
			(stroke
				(width 0)
				(type default)
			)
			(fill no)
			(layer "F.CrtYd")
		)
		(fp_line
			(start 0.254 -0.508)
			(end 0.254 0.508)
			(stroke
				(width 0.0254)
				(type default)
			)
			(layer "F.Fab")
		)
		(fp_line
			(start -0.254 -0.508)
			(end 0.254 -0.508)
			(stroke
				(width 0.0254)
				(type default)
			)
			(layer "F.Fab")
		)
		(fp_line
			(start 0.254 0.508)
			(end -0.254 0.508)
			(stroke
				(width 0.0254)
				(type default)
			)
			(layer "F.Fab")
		)
		(fp_line
			(start -0.254 0.508)
			(end -0.254 -0.508)
			(stroke
				(width 0.0254)
				(type default)
			)
			(layer "F.Fab")
		)
		(pad "1" smd rect
			(at 0 -0.4191 90)
			(size 0.508 0.5334)
			(layers "F.Cu" "F.Mask" "F.Paste")
			(net "EXT_3.3V")
		)
		(pad "2" smd rect
			(at 0 0.4191 90)
			(size 0.508 0.5334)
			(layers "F.Cu" "F.Mask" "F.Paste")
			(net "GND")
		)
		(zone
			(layer "F.Cu")
			(hatch none 0.5)
			(connect_pads
				(clearance 0)
			)
			(min_thickness 0.25)
			(keepout
				(tracks not_allowed)
				(vias allowed)
				(pads allowed)
				(copperpour not_allowed)
				(footprints allowed)
			)
			(placement
				(enabled no)
				(sheetname "")
			)
			(fill
				(thermal_gap 0.5)
				(thermal_bridge_width 0.5)
				(island_removal_mode 0)
			)
			(polygon
				(pts
					(xy 35.9156 4.0386) (xy 35.9664 4.0386) (xy 35.9664 4.0894) (xy 35.9156 4.0894)
				)
			)
		)
	)
	(footprint ""
		(layer "F.Cu")
		(at 17.399 6.985)
		(property "Reference" "R392"
			(at 0.15367 3.81 90)
			(unlocked yes)
			(layer "F.SilkS")
			(effects
				(font
					(size 0.7874 0.5842)
					(thickness 0.127)
				)
				(justify left)
			)
		)
		(property "Value" "0"
			(at -0.148158 1.3462 90)
			(unlocked yes)
			(layer "F.Fab")
			(hide yes)
			(effects
				(font
					(size 1.27 0.9652)
					(thickness 0.000001)
				)
				(justify left)
			)
		)
		(property "Device Type" "REST1111"
			(at -0.148158 1.3462 90)
			(unlocked yes)
			(layer "F.Fab")
			(hide yes)
			(effects
				(font
					(size 1.27 0.9652)
					(thickness 0.000001)
				)
				(justify left)
			)
		)
		(duplicate_pad_numbers_are_jumpers no)
		(fp_poly
			(pts
				(xy 0.635 1.0668) (xy 0.635 -1.0668) (xy -0.635 -1.0668) (xy -0.635 1.0668)
			)
			(stroke
				(width 0)
				(type default)
			)
			(fill no)
			(layer "F.CrtYd")
		)
		(fp_line
			(start -0.254 -0.508)
			(end 0.254 -0.508)
			(stroke
				(width 0.0254)
				(type default)
			)
			(layer "F.Fab")
		)
		(fp_line
			(start -0.254 0.508)
			(end -0.254 -0.508)
			(stroke
				(width 0.0254)
				(type default)
			)
			(layer "F.Fab")
		)
		(fp_line
			(start 0.254 -0.508)
			(end 0.254 0.508)
			(stroke
				(width 0.0254)
				(type default)
			)
			(layer "F.Fab")
		)
		(fp_line
			(start 0.254 0.508)
			(end -0.254 0.508)
			(stroke
				(width 0.0254)
				(type default)
			)
			(layer "F.Fab")
		)
		(pad "1" smd rect
			(at 0 -0.4191)
			(size 0.508 0.5334)
			(layers "F.Cu" "F.Mask" "F.Paste")
			(net "CPLD_SMBUS_ALERT_L")
		)
		(pad "2" smd rect
			(at 0 0.4191)
			(size 0.508 0.5334)
			(layers "F.Cu" "F.Mask" "F.Paste")
			(net "SMBUS_ALERT_L")
		)
		(zone
			(layer "F.Cu")
			(hatch none 0.5)
			(connect_pads
				(clearance 0)
			)
			(min_thickness 0.25)
			(keepout
				(tracks not_allowed)
				(vias allowed)
				(pads allowed)
				(copperpour not_allowed)
				(footprints allowed)
			)
			(placement
				(enabled no)
				(sheetname "")
			)
			(fill
				(thermal_gap 0.5)
				(thermal_bridge_width 0.5)
				(island_removal_mode 0)
			)
			(polygon
				(pts
					(xy 17.4244 6.9596) (xy 17.4244 7.0104) (xy 17.3736 7.0104) (xy 17.3736 6.9596)
				)
			)
		)
	)
	(footprint ""
		(layer "F.Cu")
		(at 14.605 44.196 180)
		(property "Reference" "L19"
			(at -2.43967 -1.27 90)
			(unlocked yes)
			(layer "F.SilkS")
			(effects
				(font
					(size 0.7874 0.5842)
					(thickness 0.127)
				)
				(justify left)
			)
		)
		(property "Value" "1.0UH"
			(at -0.483362 -0.148082 180)
			(unlocked yes)
			(layer "F.Fab")
			(hide yes)
			(effects
				(font
					(size 1.27 0.9652)
					(thickness 0.000001)
				)
				(justify left)
			)
		)
		(property "Device Type" "INDS0061"
			(at -0.483362 -0.148082 180)
			(unlocked yes)
			(layer "F.Fab")
			(hide yes)
			(effects
				(font
					(size 1.27 0.9652)
					(thickness 0.000001)
				)
				(justify left)
			)
		)
		(duplicate_pad_numbers_are_jumpers no)
		(fp_line
			(start 1.27 1.397)
			(end -1.27 1.397)
			(stroke
				(width 0.1524)
				(type default)
			)
			(layer "F.SilkS")
		)
		(fp_line
			(start -1.27 -1.397)
			(end 1.27 -1.397)
			(stroke
				(width 0.1524)
				(type default)
			)
			(layer "F.SilkS")
		)
		(fp_poly
			(pts
				(xy 2.159 -1.651) (xy 2.159 1.651) (xy -2.159 1.651) (xy -2.159 -1.651)
			)
			(stroke
				(width 0)
				(type default)
			)
			(fill no)
			(layer "F.CrtYd")
		)
		(fp_line
			(start 1.3462 1.1049)
			(end 1.3462 -1.1049)
			(stroke
				(width 0.1524)
				(type default)
			)
			(layer "F.Fab")
		)
		(fp_line
			(start 1.3462 -1.1049)
			(end -1.3462 -1.1049)
			(stroke
				(width 0.1524)
				(type default)
			)
			(layer "F.Fab")
		)
		(fp_line
			(start -1.3462 1.1049)
			(end 1.3462 1.1049)
			(stroke
				(width 0.1524)
				(type default)
			)
			(layer "F.Fab")
		)
		(fp_line
			(start -1.3462 -1.1049)
			(end -1.3462 1.1049)
			(stroke
				(width 0.1524)
				(type default)
			)
			(layer "F.Fab")
		)
		(pad "1" smd rect
			(at -1.1303 0 180)
			(size 1.1938 2.3368)
			(layers "F.Cu" "F.Mask" "F.Paste")
			(net "VDD_1.8V")
		)
		(pad "2" smd rect
			(at 1.1303 0 180)
			(size 1.1938 2.3368)
			(layers "F.Cu" "F.Mask" "F.Paste")
			(net "11N1937")
		)
		(zone
			(layer "F.Cu")
			(hatch none 0.5)
			(connect_pads
				(clearance 0)
			)
			(min_thickness 0.25)
			(keepout
				(tracks allowed)
				(vias not_allowed)
				(pads allowed)
				(copperpour not_allowed)
				(footprints allowed)
			)
			(placement
				(enabled no)
				(sheetname "")
			)
			(fill
				(thermal_gap 0.5)
				(thermal_bridge_width 0.5)
				(island_removal_mode 0)
			)
			(polygon
				(pts
					(xy 15.9512 43.0911) (xy 13.2588 43.0911) (xy 13.2588 45.3009) (xy 15.9512 45.3009)
				)
			)
		)
	)
	(footprint ""
		(layer "F.Cu")
		(at 83.312 37.973)
		(property "Reference" "R107"
			(at 0 0 0)
			(layer "F.SilkS")
			(hide yes)
			(effects
				(font
					(size 1.27 1.27)
				)
			)
		)
		(property "Value" "40.2K"
			(at -0.148158 1.3462 90)
			(unlocked yes)
			(layer "F.Fab")
			(hide yes)
			(effects
				(font
					(size 1.27 0.9652)
					(thickness 0.000001)
				)
				(justify left)
			)
		)
		(property "Device Type" "REST0171"
			(at -0.148158 1.3462 90)
			(unlocked yes)
			(layer "F.Fab")
			(hide yes)
			(effects
				(font
					(size 1.27 0.9652)
					(thickness 0.000001)
				)
				(justify left)
			)
		)
		(duplicate_pad_numbers_are_jumpers no)
		(fp_poly
			(pts
				(xy 0.635 1.0668) (xy 0.635 -1.0668) (xy -0.635 -1.0668) (xy -0.635 1.0668)
			)
			(stroke
				(width 0)
				(type default)
			)
			(fill no)
			(layer "F.CrtYd")
		)
		(fp_line
			(start -0.254 -0.508)
			(end 0.254 -0.508)
			(stroke
				(width 0.0254)
				(type default)
			)
			(layer "F.Fab")
		)
		(fp_line
			(start -0.254 0.508)
			(end -0.254 -0.508)
			(stroke
				(width 0.0254)
				(type default)
			)
			(layer "F.Fab")
		)
		(fp_line
			(start 0.254 -0.508)
			(end 0.254 0.508)
			(stroke
				(width 0.0254)
				(type default)
			)
			(layer "F.Fab")
		)
		(fp_line
			(start 0.254 0.508)
			(end -0.254 0.508)
			(stroke
				(width 0.0254)
				(type default)
			)
			(layer "F.Fab")
		)
		(pad "1" smd rect
			(at 0 -0.4191)
			(size 0.508 0.5334)
			(layers "F.Cu" "F.Mask" "F.Paste")
			(net "GND")
		)
		(pad "2" smd rect
			(at 0 0.4191)
			(size 0.508 0.5334)
			(layers "F.Cu" "F.Mask" "F.Paste")
			(net "11N2140")
		)
		(zone
			(layer "F.Cu")
			(hatch none 0.5)
			(connect_pads
				(clearance 0)
			)
			(min_thickness 0.25)
			(keepout
				(tracks not_allowed)
				(vias allowed)
				(pads allowed)
				(copperpour not_allowed)
				(footprints allowed)
			)
			(placement
				(enabled no)
				(sheetname "")
			)
			(fill
				(thermal_gap 0.5)
				(thermal_bridge_width 0.5)
				(island_removal_mode 0)
			)
			(polygon
				(pts
					(xy 83.3374 37.9476) (xy 83.3374 37.9984) (xy 83.2866 37.9984) (xy 83.2866 37.9476)
				)
			)
		)
	)
	(footprint ""
		(layer "F.Cu")
		(at 4.191 34.163 180)
		(property "Reference" "R98"
			(at 0 0 180)
			(layer "F.SilkS")
			(hide yes)
			(effects
				(font
					(size 1.27 1.27)
				)
			)
		)
		(property "Value" "4.75K"
			(at -0.148158 1.3462 270)
			(unlocked yes)
			(layer "F.Fab")
			(hide yes)
			(effects
				(font
					(size 1.27 0.9652)
					(thickness 0.000001)
				)
				(justify left)
			)
		)
		(property "Device Type" "REST4024"
			(at -0.148158 1.3462 270)
			(unlocked yes)
			(layer "F.Fab")
			(hide yes)
			(effects
				(font
					(size 1.27 0.9652)
					(thickness 0.000001)
				)
				(justify left)
			)
		)
		(duplicate_pad_numbers_are_jumpers no)
		(fp_poly
			(pts
				(xy 0.635 1.0668) (xy 0.635 -1.0668) (xy -0.635 -1.0668) (xy -0.635 1.0668)
			)
			(stroke
				(width 0)
				(type default)
			)
			(fill no)
			(layer "F.CrtYd")
		)
		(fp_line
			(start 0.254 0.508)
			(end -0.254 0.508)
			(stroke
				(width 0.0254)
				(type default)
			)
			(layer "F.Fab")
		)
		(fp_line
			(start 0.254 -0.508)
			(end 0.254 0.508)
			(stroke
				(width 0.0254)
				(type default)
			)
			(layer "F.Fab")
		)
		(fp_line
			(start -0.254 0.508)
			(end -0.254 -0.508)
			(stroke
				(width 0.0254)
				(type default)
			)
			(layer "F.Fab")
		)
		(fp_line
			(start -0.254 -0.508)
			(end 0.254 -0.508)
			(stroke
				(width 0.0254)
				(type default)
			)
			(layer "F.Fab")
		)
		(pad "1" smd rect
			(at 0 -0.4191 180)
			(size 0.508 0.5334)
			(layers "F.Cu" "F.Mask" "F.Paste")
			(net "11N1979")
		)
		(pad "2" smd rect
			(at 0 0.4191 180)
			(size 0.508 0.5334)
			(layers "F.Cu" "F.Mask" "F.Paste")
			(net "VDD_5.0V")
		)
		(zone
			(layer "F.Cu")
			(hatch none 0.5)
			(connect_pads
				(clearance 0)
			)
			(min_thickness 0.25)
			(keepout
				(tracks not_allowed)
				(vias allowed)
				(pads allowed)
				(copperpour not_allowed)
				(footprints allowed)
			)
			(placement
				(enabled no)
				(sheetname "")
			)
			(fill
				(thermal_gap 0.5)
				(thermal_bridge_width 0.5)
				(island_removal_mode 0)
			)
			(polygon
				(pts
					(xy 4.1656 34.1884) (xy 4.1656 34.1376) (xy 4.2164 34.1376) (xy 4.2164 34.1884)
				)
			)
		)
	)
	(footprint ""
		(layer "F.Cu")
		(at 75.057 20.574 90)
		(property "Reference" "C266"
			(at 0.73533 -1.778 0)
			(unlocked yes)
			(layer "F.SilkS")
			(effects
				(font
					(size 0.7874 0.5842)
					(thickness 0.127)
				)
				(justify left)
			)
		)
		(property "Value" "1UF"
			(at -0.091846 0.2921 180)
			(unlocked yes)
			(layer "F.Fab")
			(hide yes)
			(effects
				(font
					(size 0.7874 0.5842)
					(thickness 0.2032)
				)
				(justify left)
			)
		)
		(property "Device Type" "CAPC0028"
			(at -0.091846 0.2921 180)
			(unlocked yes)
			(layer "F.Fab")
			(hide yes)
			(effects
				(font
					(size 0.7874 0.5842)
					(thickness 0.2032)
				)
				(justify left)
			)
		)
		(duplicate_pad_numbers_are_jumpers no)
		(fp_poly
			(pts
				(xy 0.635 1.0668) (xy 0.635 -1.0668) (xy -0.635 -1.0668) (xy -0.635 1.0668)
			)
			(stroke
				(width 0)
				(type default)
			)
			(fill no)
			(layer "F.CrtYd")
		)
		(fp_line
			(start 0.254 -0.508)
			(end 0.254 0.508)
			(stroke
				(width 0.0254)
				(type default)
			)
			(layer "F.Fab")
		)
		(fp_line
			(start -0.254 -0.508)
			(end 0.254 -0.508)
			(stroke
				(width 0.0254)
				(type default)
			)
			(layer "F.Fab")
		)
		(fp_line
			(start 0.254 0.508)
			(end -0.254 0.508)
			(stroke
				(width 0.0254)
				(type default)
			)
			(layer "F.Fab")
		)
		(fp_line
			(start -0.254 0.508)
			(end -0.254 -0.508)
			(stroke
				(width 0.0254)
				(type default)
			)
			(layer "F.Fab")
		)
		(pad "1" smd rect
			(at 0 -0.4191 90)
			(size 0.508 0.5334)
			(layers "F.Cu" "F.Mask" "F.Paste")
			(net "DDR_VDDQ")
		)
		(pad "2" smd rect
			(at 0 0.4191 90)
			(size 0.508 0.5334)
			(layers "F.Cu" "F.Mask" "F.Paste")
			(net "GND")
		)
		(zone
			(layer "F.Cu")
			(hatch none 0.5)
			(connect_pads
				(clearance 0)
			)
			(min_thickness 0.25)
			(keepout
				(tracks not_allowed)
				(vias allowed)
				(pads allowed)
				(copperpour not_allowed)
				(footprints allowed)
			)
			(placement
				(enabled no)
				(sheetname "")
			)
			(fill
				(thermal_gap 0.5)
				(thermal_bridge_width 0.5)
				(island_removal_mode 0)
			)
			(polygon
				(pts
					(xy 75.0316 20.5486) (xy 75.0824 20.5486) (xy 75.0824 20.5994) (xy 75.0316 20.5994)
				)
			)
		)
	)
	(footprint ""
		(layer "F.Cu")
		(at 29.591 44.323 180)
		(property "Reference" "R328"
			(at 0 0 180)
			(layer "F.SilkS")
			(hide yes)
			(effects
				(font
					(size 1.27 1.27)
				)
			)
		)
		(property "Value" "19.1K"
			(at -0.148158 1.3462 270)
			(unlocked yes)
			(layer "F.Fab")
			(hide yes)
			(effects
				(font
					(size 1.27 0.9652)
					(thickness 0.000001)
				)
				(justify left)
			)
		)
		(property "Device Type" "REST0018"
			(at -0.148158 1.3462 270)
			(unlocked yes)
			(layer "F.Fab")
			(hide yes)
			(effects
				(font
					(size 1.27 0.9652)
					(thickness 0.000001)
				)
				(justify left)
			)
		)
		(duplicate_pad_numbers_are_jumpers no)
		(fp_poly
			(pts
				(xy 0.635 1.0668) (xy 0.635 -1.0668) (xy -0.635 -1.0668) (xy -0.635 1.0668)
			)
			(stroke
				(width 0)
				(type default)
			)
			(fill no)
			(layer "F.CrtYd")
		)
		(fp_line
			(start 0.254 0.508)
			(end -0.254 0.508)
			(stroke
				(width 0.0254)
				(type default)
			)
			(layer "F.Fab")
		)
		(fp_line
			(start 0.254 -0.508)
			(end 0.254 0.508)
			(stroke
				(width 0.0254)
				(type default)
			)
			(layer "F.Fab")
		)
		(fp_line
			(start -0.254 0.508)
			(end -0.254 -0.508)
			(stroke
				(width 0.0254)
				(type default)
			)
			(layer "F.Fab")
		)
		(fp_line
			(start -0.254 -0.508)
			(end 0.254 -0.508)
			(stroke
				(width 0.0254)
				(type default)
			)
			(layer "F.Fab")
		)
		(pad "1" smd rect
			(at 0 -0.4191 180)
			(size 0.508 0.5334)
			(layers "F.Cu" "F.Mask" "F.Paste")
			(net "10N2386")
		)
		(pad "2" smd rect
			(at 0 0.4191 180)
			(size 0.508 0.5334)
			(layers "F.Cu" "F.Mask" "F.Paste")
			(net "10N2504")
		)
		(zone
			(layer "F.Cu")
			(hatch none 0.5)
			(connect_pads
				(clearance 0)
			)
			(min_thickness 0.25)
			(keepout
				(tracks not_allowed)
				(vias allowed)
				(pads allowed)
				(copperpour not_allowed)
				(footprints allowed)
			)
			(placement
				(enabled no)
				(sheetname "")
			)
			(fill
				(thermal_gap 0.5)
				(thermal_bridge_width 0.5)
				(island_removal_mode 0)
			)
			(polygon
				(pts
					(xy 29.5656 44.3484) (xy 29.5656 44.2976) (xy 29.6164 44.2976) (xy 29.6164 44.3484)
				)
			)
		)
	)
	(footprint ""
		(layer "F.Cu")
		(at 22.098 29.337 180)
		(property "Reference" "R72"
			(at 0 0 180)
			(layer "F.SilkS")
			(hide yes)
			(effects
				(font
					(size 1.27 1.27)
				)
			)
		)
		(property "Value" "4.75K"
			(at -0.148158 1.3462 270)
			(unlocked yes)
			(layer "F.Fab")
			(hide yes)
			(effects
				(font
					(size 1.27 0.9652)
					(thickness 0.000001)
				)
				(justify left)
			)
		)
		(property "Device Type" "REST4024"
			(at -0.148158 1.3462 270)
			(unlocked yes)
			(layer "F.Fab")
			(hide yes)
			(effects
				(font
					(size 1.27 0.9652)
					(thickness 0.000001)
				)
				(justify left)
			)
		)
		(duplicate_pad_numbers_are_jumpers no)
		(fp_poly
			(pts
				(xy 0.635 1.0668) (xy 0.635 -1.0668) (xy -0.635 -1.0668) (xy -0.635 1.0668)
			)
			(stroke
				(width 0)
				(type default)
			)
			(fill no)
			(layer "F.CrtYd")
		)
		(fp_line
			(start 0.254 0.508)
			(end -0.254 0.508)
			(stroke
				(width 0.0254)
				(type default)
			)
			(layer "F.Fab")
		)
		(fp_line
			(start 0.254 -0.508)
			(end 0.254 0.508)
			(stroke
				(width 0.0254)
				(type default)
			)
			(layer "F.Fab")
		)
		(fp_line
			(start -0.254 0.508)
			(end -0.254 -0.508)
			(stroke
				(width 0.0254)
				(type default)
			)
			(layer "F.Fab")
		)
		(fp_line
			(start -0.254 -0.508)
			(end 0.254 -0.508)
			(stroke
				(width 0.0254)
				(type default)
			)
			(layer "F.Fab")
		)
		(pad "1" smd rect
			(at 0 -0.4191 180)
			(size 0.508 0.5334)
			(layers "F.Cu" "F.Mask" "F.Paste")
			(net "CPLD_PGRM_JTAG_TCK")
		)
		(pad "2" smd rect
			(at 0 0.4191 180)
			(size 0.508 0.5334)
			(layers "F.Cu" "F.Mask" "F.Paste")
			(net "GND")
		)
		(zone
			(layer "F.Cu")
			(hatch none 0.5)
			(connect_pads
				(clearance 0)
			)
			(min_thickness 0.25)
			(keepout
				(tracks not_allowed)
				(vias allowed)
				(pads allowed)
				(copperpour not_allowed)
				(footprints allowed)
			)
			(placement
				(enabled no)
				(sheetname "")
			)
			(fill
				(thermal_gap 0.5)
				(thermal_bridge_width 0.5)
				(island_removal_mode 0)
			)
			(polygon
				(pts
					(xy 22.0726 29.3624) (xy 22.0726 29.3116) (xy 22.1234 29.3116) (xy 22.1234 29.3624)
				)
			)
		)
	)
	(footprint ""
		(layer "F.Cu")
		(at 52.07 41.5417 90)
		(property "Reference" "L18"
			(at 4.81203 -6.731 0)
			(unlocked yes)
			(layer "F.SilkS")
			(effects
				(font
					(size 0.7874 0.5842)
					(thickness 0.127)
				)
				(justify left)
			)
		)
		(property "Value" "300NH"
			(at -0.4826 1.121918 90)
			(unlocked yes)
			(layer "F.Fab")
			(hide yes)
			(effects
				(font
					(size 1.27 0.9652)
					(thickness 0.000001)
				)
				(justify left)
			)
		)
		(property "Device Type" "INDS0042"
			(at -0.4826 1.121918 90)
			(unlocked yes)
			(layer "F.Fab")
			(hide yes)
			(effects
				(font
					(size 1.27 0.9652)
					(thickness 0.000001)
				)
				(justify left)
			)
		)
		(duplicate_pad_numbers_are_jumpers no)
		(fp_line
			(start 4.191 -5.842)
			(end 4.191 -1.2954)
			(stroke
				(width 0.2032)
				(type default)
			)
			(layer "F.SilkS")
		)
		(fp_line
			(start 4.191 -5.842)
			(end 4.191 5.842)
			(stroke
				(width 0.2032)
				(type default)
			)
			(layer "F.SilkS")
		)
		(fp_line
			(start 1.5367 -5.842)
			(end 4.191 -5.842)
			(stroke
				(width 0.2032)
				(type default)
			)
			(layer "F.SilkS")
		)
		(fp_line
			(start 1.524 -5.842)
			(end 4.191 -5.842)
			(stroke
				(width 0.2032)
				(type default)
			)
			(layer "F.SilkS")
		)
		(fp_line
			(start -1.524 -5.842)
			(end -4.191 -5.842)
			(stroke
				(width 0.2032)
				(type default)
			)
			(layer "F.SilkS")
		)
		(fp_line
			(start -1.5367 -5.842)
			(end -4.191 -5.842)
			(stroke
				(width 0.2032)
				(type default)
			)
			(layer "F.SilkS")
		)
		(fp_line
			(start -4.191 -5.842)
			(end -4.191 -3.6576)
			(stroke
				(width 0.2032)
				(type default)
			)
			(layer "F.SilkS")
		)
		(fp_line
			(start -4.191 -5.842)
			(end -4.191 5.842)
			(stroke
				(width 0.2032)
				(type default)
			)
			(layer "F.SilkS")
		)
		(fp_line
			(start -4.191 -1.6764)
			(end -4.191 5.842)
			(stroke
				(width 0.2032)
				(type default)
			)
			(layer "F.SilkS")
		)
		(fp_line
			(start 4.191 3.114675)
			(end 4.191 5.842)
			(stroke
				(width 0.2032)
				(type default)
			)
			(layer "F.SilkS")
		)
		(fp_line
			(start 4.191 5.842)
			(end 2.8956 5.842)
			(stroke
				(width 0.2032)
				(type default)
			)
			(layer "F.SilkS")
		)
		(fp_line
			(start 4.191 5.842)
			(end 1.524 5.842)
			(stroke
				(width 0.2032)
				(type default)
			)
			(layer "F.SilkS")
		)
		(fp_line
			(start -4.191 5.842)
			(end -1.524 5.842)
			(stroke
				(width 0.2032)
				(type default)
			)
			(layer "F.SilkS")
		)
		(fp_line
			(start -4.191 5.842)
			(end -2.8702 5.842)
			(stroke
				(width 0.2032)
				(type default)
			)
			(layer "F.SilkS")
		)
		(fp_poly
			(pts
				(xy -4.445 -6.096) (xy -1.778 -6.096) (xy -1.778 -6.35) (xy 1.778 -6.35) (xy 1.778 -6.096) (xy 4.445 -6.096)
				(xy 4.445 6.096) (xy 1.778 6.096) (xy 1.778 6.35) (xy -1.778 6.35) (xy -1.778 6.096) (xy -4.445 6.096)
			)
			(stroke
				(width 0)
				(type default)
			)
			(fill no)
			(layer "F.CrtYd")
		)
		(fp_line
			(start 3.8227 -5.4991)
			(end -3.8227 -5.4991)
			(stroke
				(width 0.2032)
				(type default)
			)
			(layer "F.Fab")
		)
		(fp_line
			(start -3.8227 -5.4991)
			(end -3.8227 5.4991)
			(stroke
				(width 0.2032)
				(type default)
			)
			(layer "F.Fab")
		)
		(fp_line
			(start 3.8227 5.4991)
			(end 3.8227 -5.4991)
			(stroke
				(width 0.2032)
				(type default)
			)
			(layer "F.Fab")
		)
		(fp_line
			(start -3.8227 5.4991)
			(end 3.8227 5.4991)
			(stroke
				(width 0.2032)
				(type default)
			)
			(layer "F.Fab")
		)
		(pad "1" smd rect
			(at 0 -4.1783 90)
			(size 2.3622 3.4036)
			(layers "F.Cu" "F.Mask" "F.Paste")
			(net "L_2_CORE_PHASE")
		)
		(pad "2" smd rect
			(at 0 4.1783 90)
			(size 2.3622 3.4036)
			(layers "F.Cu" "F.Mask" "F.Paste")
			(net "VDD_CORE")
		)
	)
	(footprint ""
		(layer "F.Cu")
		(at 81.915 28.702 180)
		(property "Reference" "R218"
			(at 0 0 180)
			(layer "F.SilkS")
			(hide yes)
			(effects
				(font
					(size 1.27 1.27)
				)
			)
		)
		(property "Value" "39.0"
			(at -0.148158 1.3462 270)
			(unlocked yes)
			(layer "F.Fab")
			(hide yes)
			(effects
				(font
					(size 1.27 0.9652)
					(thickness 0.000001)
				)
				(justify left)
			)
		)
		(property "Device Type" "REST0108"
			(at -0.148158 1.3462 270)
			(unlocked yes)
			(layer "F.Fab")
			(hide yes)
			(effects
				(font
					(size 1.27 0.9652)
					(thickness 0.000001)
				)
				(justify left)
			)
		)
		(duplicate_pad_numbers_are_jumpers no)
		(fp_poly
			(pts
				(xy 0.635 1.0668) (xy 0.635 -1.0668) (xy -0.635 -1.0668) (xy -0.635 1.0668)
			)
			(stroke
				(width 0)
				(type default)
			)
			(fill no)
			(layer "F.CrtYd")
		)
		(fp_line
			(start 0.254 0.508)
			(end -0.254 0.508)
			(stroke
				(width 0.0254)
				(type default)
			)
			(layer "F.Fab")
		)
		(fp_line
			(start 0.254 -0.508)
			(end 0.254 0.508)
			(stroke
				(width 0.0254)
				(type default)
			)
			(layer "F.Fab")
		)
		(fp_line
			(start -0.254 0.508)
			(end -0.254 -0.508)
			(stroke
				(width 0.0254)
				(type default)
			)
			(layer "F.Fab")
		)
		(fp_line
			(start -0.254 -0.508)
			(end 0.254 -0.508)
			(stroke
				(width 0.0254)
				(type default)
			)
			(layer "F.Fab")
		)
		(pad "1" smd rect
			(at 0 -0.4191 180)
			(size 0.508 0.5334)
			(layers "F.Cu" "F.Mask" "F.Paste")
			(net "DDR0_32A_A12")
		)
		(pad "2" smd rect
			(at 0 0.4191 180)
			(size 0.508 0.5334)
			(layers "F.Cu" "F.Mask" "F.Paste")
			(net "DDR_VTT")
		)
		(zone
			(layer "F.Cu")
			(hatch none 0.5)
			(connect_pads
				(clearance 0)
			)
			(min_thickness 0.25)
			(keepout
				(tracks not_allowed)
				(vias allowed)
				(pads allowed)
				(copperpour not_allowed)
				(footprints allowed)
			)
			(placement
				(enabled no)
				(sheetname "")
			)
			(fill
				(thermal_gap 0.5)
				(thermal_bridge_width 0.5)
				(island_removal_mode 0)
			)
			(polygon
				(pts
					(xy 81.8896 28.7274) (xy 81.8896 28.6766) (xy 81.9404 28.6766) (xy 81.9404 28.7274)
				)
			)
		)
	)
	(footprint ""
		(layer "F.Cu")
		(at -1.016 31.369)
		(property "Reference" "TP66"
			(at -0.48133 -1.016 90)
			(unlocked yes)
			(layer "F.SilkS")
			(effects
				(font
					(size 0.7874 0.5842)
					(thickness 0.127)
				)
				(justify left)
			)
		)
		(property "Value" "*"
			(at -0.4826 -0.14732 0)
			(unlocked yes)
			(layer "F.Fab")
			(hide yes)
			(effects
				(font
					(size 1.27 0.9652)
					(thickness 0.000001)
				)
				(justify left)
			)
		)
		(property "Device Type" "TP_SMALL"
			(at -0.4826 -0.14732 0)
			(unlocked yes)
			(layer "F.Fab")
			(hide yes)
			(effects
				(font
					(size 1.27 0.9652)
					(thickness 0.000001)
				)
				(justify left)
			)
		)
		(duplicate_pad_numbers_are_jumpers no)
		(fp_line
			(start -0.8636 -0.8636)
			(end -0.8636 0.8636)
			(stroke
				(width 0.1524)
				(type default)
			)
			(layer "F.SilkS")
		)
		(fp_line
			(start -0.8636 0.8636)
			(end 0.8636 0.8636)
			(stroke
				(width 0.1524)
				(type default)
			)
			(layer "F.SilkS")
		)
		(fp_line
			(start 0.8636 -0.8636)
			(end -0.8636 -0.8636)
			(stroke
				(width 0.1524)
				(type default)
			)
			(layer "F.SilkS")
		)
		(fp_line
			(start 0.8636 0.8636)
			(end 0.8636 -0.8636)
			(stroke
				(width 0.1524)
				(type default)
			)
			(layer "F.SilkS")
		)
		(fp_poly
			(pts
				(xy -0.635 -0.635) (xy -0.635 0.635) (xy 0.635 0.635) (xy 0.635 -0.635)
			)
			(stroke
				(width 0)
				(type default)
			)
			(fill no)
			(layer "F.CrtYd")
		)
		(pad "1" smd rect
			(at 0 0)
			(size 1.27 1.27)
			(layers "F.Cu" "F.Mask" "F.Paste")
			(net "VDD_7401_EN")
		)
	)
	(footprint ""
		(layer "F.Cu")
		(at 80.137 28.702 180)
		(property "Reference" "R216"
			(at 0 0 180)
			(layer "F.SilkS")
			(hide yes)
			(effects
				(font
					(size 1.27 1.27)
				)
			)
		)
		(property "Value" "39.0"
			(at -0.148158 1.3462 270)
			(unlocked yes)
			(layer "F.Fab")
			(hide yes)
			(effects
				(font
					(size 1.27 0.9652)
					(thickness 0.000001)
				)
				(justify left)
			)
		)
		(property "Device Type" "REST0108"
			(at -0.148158 1.3462 270)
			(unlocked yes)
			(layer "F.Fab")
			(hide yes)
			(effects
				(font
					(size 1.27 0.9652)
					(thickness 0.000001)
				)
				(justify left)
			)
		)
		(duplicate_pad_numbers_are_jumpers no)
		(fp_poly
			(pts
				(xy 0.635 1.0668) (xy 0.635 -1.0668) (xy -0.635 -1.0668) (xy -0.635 1.0668)
			)
			(stroke
				(width 0)
				(type default)
			)
			(fill no)
			(layer "F.CrtYd")
		)
		(fp_line
			(start 0.254 0.508)
			(end -0.254 0.508)
			(stroke
				(width 0.0254)
				(type default)
			)
			(layer "F.Fab")
		)
		(fp_line
			(start 0.254 -0.508)
			(end 0.254 0.508)
			(stroke
				(width 0.0254)
				(type default)
			)
			(layer "F.Fab")
		)
		(fp_line
			(start -0.254 0.508)
			(end -0.254 -0.508)
			(stroke
				(width 0.0254)
				(type default)
			)
			(layer "F.Fab")
		)
		(fp_line
			(start -0.254 -0.508)
			(end 0.254 -0.508)
			(stroke
				(width 0.0254)
				(type default)
			)
			(layer "F.Fab")
		)
		(pad "1" smd rect
			(at 0 -0.4191 180)
			(size 0.508 0.5334)
			(layers "F.Cu" "F.Mask" "F.Paste")
			(net "DDR0_32A_A10")
		)
		(pad "2" smd rect
			(at 0 0.4191 180)
			(size 0.508 0.5334)
			(layers "F.Cu" "F.Mask" "F.Paste")
			(net "DDR_VTT")
		)
		(zone
			(layer "F.Cu")
			(hatch none 0.5)
			(connect_pads
				(clearance 0)
			)
			(min_thickness 0.25)
			(keepout
				(tracks not_allowed)
				(vias allowed)
				(pads allowed)
				(copperpour not_allowed)
				(footprints allowed)
			)
			(placement
				(enabled no)
				(sheetname "")
			)
			(fill
				(thermal_gap 0.5)
				(thermal_bridge_width 0.5)
				(island_removal_mode 0)
			)
			(polygon
				(pts
					(xy 80.1116 28.7274) (xy 80.1116 28.6766) (xy 80.1624 28.6766) (xy 80.1624 28.7274)
				)
			)
		)
	)
	(footprint ""
		(layer "F.Cu")
		(at 45.974 51.816)
		(property "Reference" "C249"
			(at 0 0 0)
			(layer "F.SilkS")
			(hide yes)
			(effects
				(font
					(size 1.27 1.27)
				)
			)
		)
		(property "Value" "0.1UF"
			(at -0.091846 0.2921 90)
			(unlocked yes)
			(layer "F.Fab")
			(hide yes)
			(effects
				(font
					(size 0.7874 0.5842)
					(thickness 0.2032)
				)
				(justify left)
			)
		)
		(property "Device Type" "CAPC0073"
			(at -0.091846 0.2921 90)
			(unlocked yes)
			(layer "F.Fab")
			(hide yes)
			(effects
				(font
					(size 0.7874 0.5842)
					(thickness 0.2032)
				)
				(justify left)
			)
		)
		(duplicate_pad_numbers_are_jumpers no)
		(fp_poly
			(pts
				(xy 0.635 1.0668) (xy 0.635 -1.0668) (xy -0.635 -1.0668) (xy -0.635 1.0668)
			)
			(stroke
				(width 0)
				(type default)
			)
			(fill no)
			(layer "F.CrtYd")
		)
		(fp_line
			(start -0.254 -0.508)
			(end 0.254 -0.508)
			(stroke
				(width 0.0254)
				(type default)
			)
			(layer "F.Fab")
		)
		(fp_line
			(start -0.254 0.508)
			(end -0.254 -0.508)
			(stroke
				(width 0.0254)
				(type default)
			)
			(layer "F.Fab")
		)
		(fp_line
			(start 0.254 -0.508)
			(end 0.254 0.508)
			(stroke
				(width 0.0254)
				(type default)
			)
			(layer "F.Fab")
		)
		(fp_line
			(start 0.254 0.508)
			(end -0.254 0.508)
			(stroke
				(width 0.0254)
				(type default)
			)
			(layer "F.Fab")
		)
		(pad "1" smd rect
			(at 0 -0.4191)
			(size 0.508 0.5334)
			(layers "F.Cu" "F.Mask" "F.Paste")
			(net "EXT_3.3V_THRESHOLD")
		)
		(pad "2" smd rect
			(at 0 0.4191)
			(size 0.508 0.5334)
			(layers "F.Cu" "F.Mask" "F.Paste")
			(net "GND")
		)
		(zone
			(layer "F.Cu")
			(hatch none 0.5)
			(connect_pads
				(clearance 0)
			)
			(min_thickness 0.25)
			(keepout
				(tracks not_allowed)
				(vias allowed)
				(pads allowed)
				(copperpour not_allowed)
				(footprints allowed)
			)
			(placement
				(enabled no)
				(sheetname "")
			)
			(fill
				(thermal_gap 0.5)
				(thermal_bridge_width 0.5)
				(island_removal_mode 0)
			)
			(polygon
				(pts
					(xy 45.9994 51.7906) (xy 45.9994 51.8414) (xy 45.9486 51.8414) (xy 45.9486 51.7906)
				)
			)
		)
	)
	(footprint ""
		(layer "F.Cu")
		(at 75.946 5.715 -90)
		(property "Reference" "C214"
			(at -0.48133 4.318 0)
			(unlocked yes)
			(layer "F.SilkS")
			(effects
				(font
					(size 0.7874 0.5842)
					(thickness 0.127)
				)
				(justify left)
			)
		)
		(property "Value" "1UF"
			(at -0.091846 0.2921 0)
			(unlocked yes)
			(layer "F.Fab")
			(hide yes)
			(effects
				(font
					(size 0.7874 0.5842)
					(thickness 0.2032)
				)
				(justify left)
			)
		)
		(property "Device Type" "CAPC0028"
			(at -0.091846 0.2921 0)
			(unlocked yes)
			(layer "F.Fab")
			(hide yes)
			(effects
				(font
					(size 0.7874 0.5842)
					(thickness 0.2032)
				)
				(justify left)
			)
		)
		(duplicate_pad_numbers_are_jumpers no)
		(fp_poly
			(pts
				(xy 0.635 1.0668) (xy 0.635 -1.0668) (xy -0.635 -1.0668) (xy -0.635 1.0668)
			)
			(stroke
				(width 0)
				(type default)
			)
			(fill no)
			(layer "F.CrtYd")
		)
		(fp_line
			(start -0.254 0.508)
			(end -0.254 -0.508)
			(stroke
				(width 0.0254)
				(type default)
			)
			(layer "F.Fab")
		)
		(fp_line
			(start 0.254 0.508)
			(end -0.254 0.508)
			(stroke
				(width 0.0254)
				(type default)
			)
			(layer "F.Fab")
		)
		(fp_line
			(start -0.254 -0.508)
			(end 0.254 -0.508)
			(stroke
				(width 0.0254)
				(type default)
			)
			(layer "F.Fab")
		)
		(fp_line
			(start 0.254 -0.508)
			(end 0.254 0.508)
			(stroke
				(width 0.0254)
				(type default)
			)
			(layer "F.Fab")
		)
		(pad "1" smd rect
			(at 0 -0.4191 270)
			(size 0.508 0.5334)
			(layers "F.Cu" "F.Mask" "F.Paste")
			(net "DDR_VDDQ")
		)
		(pad "2" smd rect
			(at 0 0.4191 270)
			(size 0.508 0.5334)
			(layers "F.Cu" "F.Mask" "F.Paste")
			(net "GND")
		)
		(zone
			(layer "F.Cu")
			(hatch none 0.5)
			(connect_pads
				(clearance 0)
			)
			(min_thickness 0.25)
			(keepout
				(tracks not_allowed)
				(vias allowed)
				(pads allowed)
				(copperpour not_allowed)
				(footprints allowed)
			)
			(placement
				(enabled no)
				(sheetname "")
			)
			(fill
				(thermal_gap 0.5)
				(thermal_bridge_width 0.5)
				(island_removal_mode 0)
			)
			(polygon
				(pts
					(xy 75.9714 5.7404) (xy 75.9206 5.7404) (xy 75.9206 5.6896) (xy 75.9714 5.6896)
				)
			)
		)
	)
	(footprint ""
		(layer "F.Cu")
		(at 31.877 32.639 180)
		(property "Reference" "R90"
			(at 0 0 180)
			(layer "F.SilkS")
			(hide yes)
			(effects
				(font
					(size 1.27 1.27)
				)
			)
		)
		(property "Value" "4.75K"
			(at -0.148158 1.3462 270)
			(unlocked yes)
			(layer "F.Fab")
			(hide yes)
			(effects
				(font
					(size 1.27 0.9652)
					(thickness 0.000001)
				)
				(justify left)
			)
		)
		(property "Device Type" "REST4024"
			(at -0.148158 1.3462 270)
			(unlocked yes)
			(layer "F.Fab")
			(hide yes)
			(effects
				(font
					(size 1.27 0.9652)
					(thickness 0.000001)
				)
				(justify left)
			)
		)
		(duplicate_pad_numbers_are_jumpers no)
		(fp_poly
			(pts
				(xy 0.635 1.0668) (xy 0.635 -1.0668) (xy -0.635 -1.0668) (xy -0.635 1.0668)
			)
			(stroke
				(width 0)
				(type default)
			)
			(fill no)
			(layer "F.CrtYd")
		)
		(fp_line
			(start 0.254 0.508)
			(end -0.254 0.508)
			(stroke
				(width 0.0254)
				(type default)
			)
			(layer "F.Fab")
		)
		(fp_line
			(start 0.254 -0.508)
			(end 0.254 0.508)
			(stroke
				(width 0.0254)
				(type default)
			)
			(layer "F.Fab")
		)
		(fp_line
			(start -0.254 0.508)
			(end -0.254 -0.508)
			(stroke
				(width 0.0254)
				(type default)
			)
			(layer "F.Fab")
		)
		(fp_line
			(start -0.254 -0.508)
			(end 0.254 -0.508)
			(stroke
				(width 0.0254)
				(type default)
			)
			(layer "F.Fab")
		)
		(pad "1" smd rect
			(at 0 -0.4191 180)
			(size 0.508 0.5334)
			(layers "F.Cu" "F.Mask" "F.Paste")
			(net "_NFP_CORE_VID4")
		)
		(pad "2" smd rect
			(at 0 0.4191 180)
			(size 0.508 0.5334)
			(layers "F.Cu" "F.Mask" "F.Paste")
			(net "VDD_1.2V")
		)
		(zone
			(layer "F.Cu")
			(hatch none 0.5)
			(connect_pads
				(clearance 0)
			)
			(min_thickness 0.25)
			(keepout
				(tracks not_allowed)
				(vias allowed)
				(pads allowed)
				(copperpour not_allowed)
				(footprints allowed)
			)
			(placement
				(enabled no)
				(sheetname "")
			)
			(fill
				(thermal_gap 0.5)
				(thermal_bridge_width 0.5)
				(island_removal_mode 0)
			)
			(polygon
				(pts
					(xy 31.8516 32.6644) (xy 31.8516 32.6136) (xy 31.9024 32.6136) (xy 31.9024 32.6644)
				)
			)
		)
	)
	(footprint ""
		(layer "F.Cu")
		(at 80.391 47.752 -90)
		(property "Reference" "C51"
			(at 0 0 270)
			(layer "F.SilkS")
			(hide yes)
			(effects
				(font
					(size 1.27 1.27)
				)
			)
		)
		(property "Value" "1000PF"
			(at -0.091846 0.2921 0)
			(unlocked yes)
			(layer "F.Fab")
			(hide yes)
			(effects
				(font
					(size 0.7874 0.5842)
					(thickness 0.2032)
				)
				(justify left)
			)
		)
		(property "Device Type" "CAPC0083"
			(at -0.091846 0.2921 0)
			(unlocked yes)
			(layer "F.Fab")
			(hide yes)
			(effects
				(font
					(size 0.7874 0.5842)
					(thickness 0.2032)
				)
				(justify left)
			)
		)
		(duplicate_pad_numbers_are_jumpers no)
		(fp_poly
			(pts
				(xy 0.635 1.0668) (xy 0.635 -1.0668) (xy -0.635 -1.0668) (xy -0.635 1.0668)
			)
			(stroke
				(width 0)
				(type default)
			)
			(fill no)
			(layer "F.CrtYd")
		)
		(fp_line
			(start -0.254 0.508)
			(end -0.254 -0.508)
			(stroke
				(width 0.0254)
				(type default)
			)
			(layer "F.Fab")
		)
		(fp_line
			(start 0.254 0.508)
			(end -0.254 0.508)
			(stroke
				(width 0.0254)
				(type default)
			)
			(layer "F.Fab")
		)
		(fp_line
			(start -0.254 -0.508)
			(end 0.254 -0.508)
			(stroke
				(width 0.0254)
				(type default)
			)
			(layer "F.Fab")
		)
		(fp_line
			(start 0.254 -0.508)
			(end 0.254 0.508)
			(stroke
				(width 0.0254)
				(type default)
			)
			(layer "F.Fab")
		)
		(pad "1" smd rect
			(at 0 -0.4191 270)
			(size 0.508 0.5334)
			(layers "F.Cu" "F.Mask" "F.Paste")
			(net "11N2258")
		)
		(pad "2" smd rect
			(at 0 0.4191 270)
			(size 0.508 0.5334)
			(layers "F.Cu" "F.Mask" "F.Paste")
			(net "GND")
		)
		(zone
			(layer "F.Cu")
			(hatch none 0.5)
			(connect_pads
				(clearance 0)
			)
			(min_thickness 0.25)
			(keepout
				(tracks not_allowed)
				(vias allowed)
				(pads allowed)
				(copperpour not_allowed)
				(footprints allowed)
			)
			(placement
				(enabled no)
				(sheetname "")
			)
			(fill
				(thermal_gap 0.5)
				(thermal_bridge_width 0.5)
				(island_removal_mode 0)
			)
			(polygon
				(pts
					(xy 80.4164 47.7774) (xy 80.3656 47.7774) (xy 80.3656 47.7266) (xy 80.4164 47.7266)
				)
			)
		)
	)
	(footprint ""
		(layer "F.Cu")
		(at 48.2346 53.594 90)
		(property "Reference" "C182"
			(at -1.143 1.93167 90)
			(unlocked yes)
			(layer "F.SilkS")
			(effects
				(font
					(size 0.7874 0.5842)
					(thickness 0.127)
				)
				(justify left)
			)
		)
		(property "Value" ""
			(at 0 0 90)
			(layer "F.Fab")
			(effects
				(font
					(size 1.27 1.27)
				)
			)
		)
		(duplicate_pad_numbers_are_jumpers no)
		(fp_arc
			(start 0.206578 -0.464261)
			(mid 0.300675 -0.409652)
			(end 0.381 -0.336271)
			(stroke
				(width 0.2032)
				(type default)
			)
			(layer "F.SilkS")
		)
		(fp_arc
			(start 0.381 0.336017)
			(mid 0.367833 0.350371)
			(end 0.354127 0.364211)
			(stroke
				(width 0.2032)
				(type default)
			)
			(layer "F.SilkS")
		)
		(fp_circle
			(center 0 0)
			(end 0 0.508)
			(stroke
				(width 0.2032)
				(type default)
			)
			(fill no)
			(layer "F.SilkS")
		)
		(fp_poly
			(pts
				(xy -1.905 1.778) (xy -1.905 -1.778) (xy 2.286 -1.778) (xy 2.286 1.778)
			)
			(stroke
				(width 0)
				(type default)
			)
			(fill no)
			(layer "F.CrtYd")
		)
		(fp_line
			(start 1.524 -1.27)
			(end 1.524 1.27)
			(stroke
				(width 0.0254)
				(type default)
			)
			(layer "F.Fab")
		)
		(fp_line
			(start -1.524 -1.27)
			(end 1.524 -1.27)
			(stroke
				(width 0.0254)
				(type default)
			)
			(layer "F.Fab")
		)
		(fp_line
			(start 1.524 1.27)
			(end -1.524 1.27)
			(stroke
				(width 0.0254)
				(type default)
			)
			(layer "F.Fab")
		)
		(fp_line
			(start -1.524 1.27)
			(end -1.524 -1.27)
			(stroke
				(width 0.0254)
				(type default)
			)
			(layer "F.Fab")
		)
		(pad "1" smd rect
			(at -1.4224 0 180)
			(size 2.7432 1.3716)
			(layers "F.Cu" "F.Mask" "F.Paste")
			(net "VDD_5.0V")
		)
		(pad "2" smd rect
			(at 1.4224 0 180)
			(size 2.7432 1.3716)
			(layers "F.Cu" "F.Mask" "F.Paste")
			(net "GND")
		)
	)
	(footprint ""
		(layer "F.Cu")
		(at 81.407 22.479 -90)
		(property "Reference" "C108"
			(at 0 0 270)
			(layer "F.SilkS")
			(hide yes)
			(effects
				(font
					(size 1.27 1.27)
				)
			)
		)
		(property "Value" "0.1UF"
			(at -0.091846 0.2921 0)
			(unlocked yes)
			(layer "F.Fab")
			(hide yes)
			(effects
				(font
					(size 0.7874 0.5842)
					(thickness 0.2032)
				)
				(justify left)
			)
		)
		(property "Device Type" "CAPC0073"
			(at -0.091846 0.2921 0)
			(unlocked yes)
			(layer "F.Fab")
			(hide yes)
			(effects
				(font
					(size 0.7874 0.5842)
					(thickness 0.2032)
				)
				(justify left)
			)
		)
		(duplicate_pad_numbers_are_jumpers no)
		(fp_poly
			(pts
				(xy 0.635 1.0668) (xy 0.635 -1.0668) (xy -0.635 -1.0668) (xy -0.635 1.0668)
			)
			(stroke
				(width 0)
				(type default)
			)
			(fill no)
			(layer "F.CrtYd")
		)
		(fp_line
			(start -0.254 0.508)
			(end -0.254 -0.508)
			(stroke
				(width 0.0254)
				(type default)
			)
			(layer "F.Fab")
		)
		(fp_line
			(start 0.254 0.508)
			(end -0.254 0.508)
			(stroke
				(width 0.0254)
				(type default)
			)
			(layer "F.Fab")
		)
		(fp_line
			(start -0.254 -0.508)
			(end 0.254 -0.508)
			(stroke
				(width 0.0254)
				(type default)
			)
			(layer "F.Fab")
		)
		(fp_line
			(start 0.254 -0.508)
			(end 0.254 0.508)
			(stroke
				(width 0.0254)
				(type default)
			)
			(layer "F.Fab")
		)
		(pad "1" smd rect
			(at 0 -0.4191 270)
			(size 0.508 0.5334)
			(layers "F.Cu" "F.Mask" "F.Paste")
			(net "DDR_VDDQ")
		)
		(pad "2" smd rect
			(at 0 0.4191 270)
			(size 0.508 0.5334)
			(layers "F.Cu" "F.Mask" "F.Paste")
			(net "DDR_VTT")
		)
		(zone
			(layer "F.Cu")
			(hatch none 0.5)
			(connect_pads
				(clearance 0)
			)
			(min_thickness 0.25)
			(keepout
				(tracks not_allowed)
				(vias allowed)
				(pads allowed)
				(copperpour not_allowed)
				(footprints allowed)
			)
			(placement
				(enabled no)
				(sheetname "")
			)
			(fill
				(thermal_gap 0.5)
				(thermal_bridge_width 0.5)
				(island_removal_mode 0)
			)
			(polygon
				(pts
					(xy 81.4324 22.5044) (xy 81.3816 22.5044) (xy 81.3816 22.4536) (xy 81.4324 22.4536)
				)
			)
		)
	)
	(footprint ""
		(layer "F.Cu")
		(at 34.544 32.639 180)
		(property "Reference" "R78"
			(at 0 0 180)
			(layer "F.SilkS")
			(hide yes)
			(effects
				(font
					(size 1.27 1.27)
				)
			)
		)
		(property "Value" "4.75K"
			(at -0.148158 1.3462 270)
			(unlocked yes)
			(layer "F.Fab")
			(hide yes)
			(effects
				(font
					(size 1.27 0.9652)
					(thickness 0.000001)
				)
				(justify left)
			)
		)
		(property "Device Type" "REST4024"
			(at -0.148158 1.3462 270)
			(unlocked yes)
			(layer "F.Fab")
			(hide yes)
			(effects
				(font
					(size 1.27 0.9652)
					(thickness 0.000001)
				)
				(justify left)
			)
		)
		(duplicate_pad_numbers_are_jumpers no)
		(fp_poly
			(pts
				(xy 0.635 1.0668) (xy 0.635 -1.0668) (xy -0.635 -1.0668) (xy -0.635 1.0668)
			)
			(stroke
				(width 0)
				(type default)
			)
			(fill no)
			(layer "F.CrtYd")
		)
		(fp_line
			(start 0.254 0.508)
			(end -0.254 0.508)
			(stroke
				(width 0.0254)
				(type default)
			)
			(layer "F.Fab")
		)
		(fp_line
			(start 0.254 -0.508)
			(end 0.254 0.508)
			(stroke
				(width 0.0254)
				(type default)
			)
			(layer "F.Fab")
		)
		(fp_line
			(start -0.254 0.508)
			(end -0.254 -0.508)
			(stroke
				(width 0.0254)
				(type default)
			)
			(layer "F.Fab")
		)
		(fp_line
			(start -0.254 -0.508)
			(end 0.254 -0.508)
			(stroke
				(width 0.0254)
				(type default)
			)
			(layer "F.Fab")
		)
		(pad "1" smd rect
			(at 0 -0.4191 180)
			(size 0.508 0.5334)
			(layers "F.Cu" "F.Mask" "F.Paste")
			(net "_NFP_CORE_VID6")
		)
		(pad "2" smd rect
			(at 0 0.4191 180)
			(size 0.508 0.5334)
			(layers "F.Cu" "F.Mask" "F.Paste")
			(net "VDD_1.2V")
		)
		(zone
			(layer "F.Cu")
			(hatch none 0.5)
			(connect_pads
				(clearance 0)
			)
			(min_thickness 0.25)
			(keepout
				(tracks not_allowed)
				(vias allowed)
				(pads allowed)
				(copperpour not_allowed)
				(footprints allowed)
			)
			(placement
				(enabled no)
				(sheetname "")
			)
			(fill
				(thermal_gap 0.5)
				(thermal_bridge_width 0.5)
				(island_removal_mode 0)
			)
			(polygon
				(pts
					(xy 34.5186 32.6644) (xy 34.5186 32.6136) (xy 34.5694 32.6136) (xy 34.5694 32.6644)
				)
			)
		)
	)
	(footprint ""
		(layer "F.Cu")
		(at 73.406 26.797 90)
		(property "Reference" "R338"
			(at 0 0 90)
			(layer "F.SilkS")
			(hide yes)
			(effects
				(font
					(size 1.27 1.27)
				)
			)
		)
		(property "Value" "4.75K"
			(at -0.148158 1.3462 180)
			(unlocked yes)
			(layer "F.Fab")
			(hide yes)
			(effects
				(font
					(size 1.27 0.9652)
					(thickness 0.000001)
				)
				(justify left)
			)
		)
		(property "Device Type" "REST4024"
			(at -0.148158 1.3462 180)
			(unlocked yes)
			(layer "F.Fab")
			(hide yes)
			(effects
				(font
					(size 1.27 0.9652)
					(thickness 0.000001)
				)
				(justify left)
			)
		)
		(duplicate_pad_numbers_are_jumpers no)
		(fp_poly
			(pts
				(xy 0.635 1.0668) (xy 0.635 -1.0668) (xy -0.635 -1.0668) (xy -0.635 1.0668)
			)
			(stroke
				(width 0)
				(type default)
			)
			(fill no)
			(layer "F.CrtYd")
		)
		(fp_line
			(start 0.254 -0.508)
			(end 0.254 0.508)
			(stroke
				(width 0.0254)
				(type default)
			)
			(layer "F.Fab")
		)
		(fp_line
			(start -0.254 -0.508)
			(end 0.254 -0.508)
			(stroke
				(width 0.0254)
				(type default)
			)
			(layer "F.Fab")
		)
		(fp_line
			(start 0.254 0.508)
			(end -0.254 0.508)
			(stroke
				(width 0.0254)
				(type default)
			)
			(layer "F.Fab")
		)
		(fp_line
			(start -0.254 0.508)
			(end -0.254 -0.508)
			(stroke
				(width 0.0254)
				(type default)
			)
			(layer "F.Fab")
		)
		(pad "1" smd rect
			(at 0 -0.4191 90)
			(size 0.508 0.5334)
			(layers "F.Cu" "F.Mask" "F.Paste")
			(net "12N3293")
		)
		(pad "2" smd rect
			(at 0 0.4191 90)
			(size 0.508 0.5334)
			(layers "F.Cu" "F.Mask" "F.Paste")
			(net "DDR_VDDQ")
		)
		(zone
			(layer "F.Cu")
			(hatch none 0.5)
			(connect_pads
				(clearance 0)
			)
			(min_thickness 0.25)
			(keepout
				(tracks not_allowed)
				(vias allowed)
				(pads allowed)
				(copperpour not_allowed)
				(footprints allowed)
			)
			(placement
				(enabled no)
				(sheetname "")
			)
			(fill
				(thermal_gap 0.5)
				(thermal_bridge_width 0.5)
				(island_removal_mode 0)
			)
			(polygon
				(pts
					(xy 73.3806 26.7716) (xy 73.4314 26.7716) (xy 73.4314 26.8224) (xy 73.3806 26.8224)
				)
			)
		)
	)
	(footprint ""
		(layer "F.Cu")
		(at 26.67 40.386 90)
		(property "Reference" "R1"
			(at 0 0 90)
			(layer "F.SilkS")
			(hide yes)
			(effects
				(font
					(size 1.27 1.27)
				)
			)
		)
		(property "Value" "121K"
			(at -0.148158 1.3462 180)
			(unlocked yes)
			(layer "F.Fab")
			(hide yes)
			(effects
				(font
					(size 1.27 0.9652)
					(thickness 0.000001)
				)
				(justify left)
			)
		)
		(property "Device Type" "REST0174"
			(at -0.148158 1.3462 180)
			(unlocked yes)
			(layer "F.Fab")
			(hide yes)
			(effects
				(font
					(size 1.27 0.9652)
					(thickness 0.000001)
				)
				(justify left)
			)
		)
		(duplicate_pad_numbers_are_jumpers no)
		(fp_poly
			(pts
				(xy 0.635 1.0668) (xy 0.635 -1.0668) (xy -0.635 -1.0668) (xy -0.635 1.0668)
			)
			(stroke
				(width 0)
				(type default)
			)
			(fill no)
			(layer "F.CrtYd")
		)
		(fp_line
			(start 0.254 -0.508)
			(end 0.254 0.508)
			(stroke
				(width 0.0254)
				(type default)
			)
			(layer "F.Fab")
		)
		(fp_line
			(start -0.254 -0.508)
			(end 0.254 -0.508)
			(stroke
				(width 0.0254)
				(type default)
			)
			(layer "F.Fab")
		)
		(fp_line
			(start 0.254 0.508)
			(end -0.254 0.508)
			(stroke
				(width 0.0254)
				(type default)
			)
			(layer "F.Fab")
		)
		(fp_line
			(start -0.254 0.508)
			(end -0.254 -0.508)
			(stroke
				(width 0.0254)
				(type default)
			)
			(layer "F.Fab")
		)
		(pad "1" smd rect
			(at 0 -0.4191 90)
			(size 0.508 0.5334)
			(layers "F.Cu" "F.Mask" "F.Paste")
			(net "GND")
		)
		(pad "2" smd rect
			(at 0 0.4191 90)
			(size 0.508 0.5334)
			(layers "F.Cu" "F.Mask" "F.Paste")
			(net "10N2411")
		)
		(zone
			(layer "F.Cu")
			(hatch none 0.5)
			(connect_pads
				(clearance 0)
			)
			(min_thickness 0.25)
			(keepout
				(tracks not_allowed)
				(vias allowed)
				(pads allowed)
				(copperpour not_allowed)
				(footprints allowed)
			)
			(placement
				(enabled no)
				(sheetname "")
			)
			(fill
				(thermal_gap 0.5)
				(thermal_bridge_width 0.5)
				(island_removal_mode 0)
			)
			(polygon
				(pts
					(xy 26.6446 40.3606) (xy 26.6954 40.3606) (xy 26.6954 40.4114) (xy 26.6446 40.4114)
				)
			)
		)
	)
	(footprint ""
		(layer "F.Cu")
		(at 35.814 43.942 -90)
		(property "Reference" "R329"
			(at 3.937 -0.40767 90)
			(unlocked yes)
			(layer "F.SilkS")
			(effects
				(font
					(size 0.7874 0.5842)
					(thickness 0.127)
				)
				(justify left)
			)
		)
		(property "Value" ""
			(at 0 0 270)
			(layer "F.Fab")
			(effects
				(font
					(size 1.27 1.27)
				)
			)
		)
		(duplicate_pad_numbers_are_jumpers no)
		(fp_line
			(start -0.0254 0.127)
			(end -0.0254 -0.127)
			(stroke
				(width 0.1016)
				(type default)
			)
			(layer "F.SilkS")
		)
		(fp_line
			(start 0.0254 0.127)
			(end -0.0254 0.127)
			(stroke
				(width 0.1016)
				(type default)
			)
			(layer "F.SilkS")
		)
		(fp_line
			(start -0.0254 -0.127)
			(end 0.0254 -0.127)
			(stroke
				(width 0.1016)
				(type default)
			)
			(layer "F.SilkS")
		)
		(fp_line
			(start 0.0254 -0.127)
			(end 0.0254 0.127)
			(stroke
				(width 0.1016)
				(type default)
			)
			(layer "F.SilkS")
		)
		(fp_poly
			(pts
				(xy 0.889 -0.4953) (xy 0.889 0.4953) (xy -0.889 0.4953) (xy -0.889 -0.4953)
			)
			(stroke
				(width 0)
				(type default)
			)
			(fill no)
			(layer "F.CrtYd")
		)
		(fp_line
			(start -0.508 0.254)
			(end 0.508 0.254)
			(stroke
				(width 0.0254)
				(type default)
			)
			(layer "F.Fab")
		)
		(fp_line
			(start 0.508 0.254)
			(end 0.508 -0.254)
			(stroke
				(width 0.0254)
				(type default)
			)
			(layer "F.Fab")
		)
		(fp_line
			(start -0.508 -0.254)
			(end -0.508 0.254)
			(stroke
				(width 0.0254)
				(type default)
			)
			(layer "F.Fab")
		)
		(fp_line
			(start 0.508 -0.254)
			(end -0.508 -0.254)
			(stroke
				(width 0.0254)
				(type default)
			)
			(layer "F.Fab")
		)
		(pad "1" smd rect
			(at -0.4699 0 270)
			(size 0.5334 0.508)
			(layers "F.Cu" "F.Mask" "F.Paste")
			(net "NFP_VDD_CORE_TCOMPA")
		)
		(pad "2" smd rect
			(at 0.4699 0 270)
			(size 0.5334 0.508)
			(layers "F.Cu" "F.Mask" "F.Paste")
			(net "NFP_VDD_CORE_TCOMPB")
		)
	)
	(footprint ""
		(layer "F.Cu")
		(at 27.178 42.164 90)
		(property "Reference" "R3"
			(at 0 0 90)
			(layer "F.SilkS")
			(hide yes)
			(effects
				(font
					(size 1.27 1.27)
				)
			)
		)
		(property "Value" "332K"
			(at -0.148158 1.3462 180)
			(unlocked yes)
			(layer "F.Fab")
			(hide yes)
			(effects
				(font
					(size 1.27 0.9652)
					(thickness 0.000001)
				)
				(justify left)
			)
		)
		(property "Device Type" "REST0121"
			(at -0.148158 1.3462 180)
			(unlocked yes)
			(layer "F.Fab")
			(hide yes)
			(effects
				(font
					(size 1.27 0.9652)
					(thickness 0.000001)
				)
				(justify left)
			)
		)
		(duplicate_pad_numbers_are_jumpers no)
		(fp_poly
			(pts
				(xy 0.635 1.0668) (xy 0.635 -1.0668) (xy -0.635 -1.0668) (xy -0.635 1.0668)
			)
			(stroke
				(width 0)
				(type default)
			)
			(fill no)
			(layer "F.CrtYd")
		)
		(fp_line
			(start 0.254 -0.508)
			(end 0.254 0.508)
			(stroke
				(width 0.0254)
				(type default)
			)
			(layer "F.Fab")
		)
		(fp_line
			(start -0.254 -0.508)
			(end 0.254 -0.508)
			(stroke
				(width 0.0254)
				(type default)
			)
			(layer "F.Fab")
		)
		(fp_line
			(start 0.254 0.508)
			(end -0.254 0.508)
			(stroke
				(width 0.0254)
				(type default)
			)
			(layer "F.Fab")
		)
		(fp_line
			(start -0.254 0.508)
			(end -0.254 -0.508)
			(stroke
				(width 0.0254)
				(type default)
			)
			(layer "F.Fab")
		)
		(pad "1" smd rect
			(at 0 -0.4191 90)
			(size 0.508 0.5334)
			(layers "F.Cu" "F.Mask" "F.Paste")
			(net "10N2407")
		)
		(pad "2" smd rect
			(at 0 0.4191 90)
			(size 0.508 0.5334)
			(layers "F.Cu" "F.Mask" "F.Paste")
			(net "10N2397")
		)
		(zone
			(layer "F.Cu")
			(hatch none 0.5)
			(connect_pads
				(clearance 0)
			)
			(min_thickness 0.25)
			(keepout
				(tracks not_allowed)
				(vias allowed)
				(pads allowed)
				(copperpour not_allowed)
				(footprints allowed)
			)
			(placement
				(enabled no)
				(sheetname "")
			)
			(fill
				(thermal_gap 0.5)
				(thermal_bridge_width 0.5)
				(island_removal_mode 0)
			)
			(polygon
				(pts
					(xy 27.1526 42.1386) (xy 27.2034 42.1386) (xy 27.2034 42.1894) (xy 27.1526 42.1894)
				)
			)
		)
	)
	(footprint ""
		(layer "F.Cu")
		(at 75.057 9.017 90)
		(property "Reference" "C212"
			(at -0.78867 -1.778 0)
			(unlocked yes)
			(layer "F.SilkS")
			(effects
				(font
					(size 0.7874 0.5842)
					(thickness 0.127)
				)
				(justify left)
			)
		)
		(property "Value" "1UF"
			(at -0.091846 0.2921 180)
			(unlocked yes)
			(layer "F.Fab")
			(hide yes)
			(effects
				(font
					(size 0.7874 0.5842)
					(thickness 0.2032)
				)
				(justify left)
			)
		)
		(property "Device Type" "CAPC0028"
			(at -0.091846 0.2921 180)
			(unlocked yes)
			(layer "F.Fab")
			(hide yes)
			(effects
				(font
					(size 0.7874 0.5842)
					(thickness 0.2032)
				)
				(justify left)
			)
		)
		(duplicate_pad_numbers_are_jumpers no)
		(fp_poly
			(pts
				(xy 0.635 1.0668) (xy 0.635 -1.0668) (xy -0.635 -1.0668) (xy -0.635 1.0668)
			)
			(stroke
				(width 0)
				(type default)
			)
			(fill no)
			(layer "F.CrtYd")
		)
		(fp_line
			(start 0.254 -0.508)
			(end 0.254 0.508)
			(stroke
				(width 0.0254)
				(type default)
			)
			(layer "F.Fab")
		)
		(fp_line
			(start -0.254 -0.508)
			(end 0.254 -0.508)
			(stroke
				(width 0.0254)
				(type default)
			)
			(layer "F.Fab")
		)
		(fp_line
			(start 0.254 0.508)
			(end -0.254 0.508)
			(stroke
				(width 0.0254)
				(type default)
			)
			(layer "F.Fab")
		)
		(fp_line
			(start -0.254 0.508)
			(end -0.254 -0.508)
			(stroke
				(width 0.0254)
				(type default)
			)
			(layer "F.Fab")
		)
		(pad "1" smd rect
			(at 0 -0.4191 90)
			(size 0.508 0.5334)
			(layers "F.Cu" "F.Mask" "F.Paste")
			(net "DDR_VDDQ")
		)
		(pad "2" smd rect
			(at 0 0.4191 90)
			(size 0.508 0.5334)
			(layers "F.Cu" "F.Mask" "F.Paste")
			(net "GND")
		)
		(zone
			(layer "F.Cu")
			(hatch none 0.5)
			(connect_pads
				(clearance 0)
			)
			(min_thickness 0.25)
			(keepout
				(tracks not_allowed)
				(vias allowed)
				(pads allowed)
				(copperpour not_allowed)
				(footprints allowed)
			)
			(placement
				(enabled no)
				(sheetname "")
			)
			(fill
				(thermal_gap 0.5)
				(thermal_bridge_width 0.5)
				(island_removal_mode 0)
			)
			(polygon
				(pts
					(xy 75.0316 8.9916) (xy 75.0824 8.9916) (xy 75.0824 9.0424) (xy 75.0316 9.0424)
				)
			)
		)
	)
	(footprint ""
		(layer "F.Cu")
		(at 73.05101 5.898998)
		(property "Reference" "V_A-DQS1-N"
			(at 0 0 0)
			(layer "F.SilkS")
			(hide yes)
			(effects
				(font
					(size 1.27 1.27)
				)
			)
		)
		(property "Value" ""
			(at 0 0 0)
			(layer "F.Fab")
			(effects
				(font
					(size 1.27 1.27)
				)
			)
		)
		(duplicate_pad_numbers_are_jumpers no)
		(pad "1" thru_hole circle
			(at 0 0)
			(size 0.762 0.762)
			(drill 0.20574)
			(layers "*.Cu" "*.Mask")
			(remove_unused_layers no)
			(net "DDR0_32A_DQS1_N")
			(clearance 0.127)
			(thermal_gap 0.127)
			(padstack
				(mode front_inner_back)
				(layer "Inner"
					(shape circle)
					(size 0.4572 0.4572)
					(clearance 0.1143)
				)
				(layer "B.Cu"
					(shape circle)
					(size 0.4572 0.4572)
					(clearance 0.1143)
				)
			)
		)
	)
	(footprint ""
		(layer "F.Cu")
		(at 25.908 36.83 -90)
		(property "Reference" "R85"
			(at 0 0 270)
			(layer "F.SilkS")
			(hide yes)
			(effects
				(font
					(size 1.27 1.27)
				)
			)
		)
		(property "Value" "4.75K"
			(at -0.148158 1.3462 0)
			(unlocked yes)
			(layer "F.Fab")
			(hide yes)
			(effects
				(font
					(size 1.27 0.9652)
					(thickness 0.000001)
				)
				(justify left)
			)
		)
		(property "Device Type" "REST4024"
			(at -0.148158 1.3462 0)
			(unlocked yes)
			(layer "F.Fab")
			(hide yes)
			(effects
				(font
					(size 1.27 0.9652)
					(thickness 0.000001)
				)
				(justify left)
			)
		)
		(duplicate_pad_numbers_are_jumpers no)
		(fp_poly
			(pts
				(xy 0.635 1.0668) (xy 0.635 -1.0668) (xy -0.635 -1.0668) (xy -0.635 1.0668)
			)
			(stroke
				(width 0)
				(type default)
			)
			(fill no)
			(layer "F.CrtYd")
		)
		(fp_line
			(start -0.254 0.508)
			(end -0.254 -0.508)
			(stroke
				(width 0.0254)
				(type default)
			)
			(layer "F.Fab")
		)
		(fp_line
			(start 0.254 0.508)
			(end -0.254 0.508)
			(stroke
				(width 0.0254)
				(type default)
			)
			(layer "F.Fab")
		)
		(fp_line
			(start -0.254 -0.508)
			(end 0.254 -0.508)
			(stroke
				(width 0.0254)
				(type default)
			)
			(layer "F.Fab")
		)
		(fp_line
			(start 0.254 -0.508)
			(end 0.254 0.508)
			(stroke
				(width 0.0254)
				(type default)
			)
			(layer "F.Fab")
		)
		(pad "1" smd rect
			(at 0 -0.4191 270)
			(size 0.508 0.5334)
			(layers "F.Cu" "F.Mask" "F.Paste")
			(net "CORE_FB_FAULT_L")
		)
		(pad "2" smd rect
			(at 0 0.4191 270)
			(size 0.508 0.5334)
			(layers "F.Cu" "F.Mask" "F.Paste")
			(net "EXT_3.3V")
		)
		(zone
			(layer "F.Cu")
			(hatch none 0.5)
			(connect_pads
				(clearance 0)
			)
			(min_thickness 0.25)
			(keepout
				(tracks not_allowed)
				(vias allowed)
				(pads allowed)
				(copperpour not_allowed)
				(footprints allowed)
			)
			(placement
				(enabled no)
				(sheetname "")
			)
			(fill
				(thermal_gap 0.5)
				(thermal_bridge_width 0.5)
				(island_removal_mode 0)
			)
			(polygon
				(pts
					(xy 25.9334 36.8554) (xy 25.8826 36.8554) (xy 25.8826 36.8046) (xy 25.9334 36.8046)
				)
			)
		)
	)
	(footprint ""
		(layer "F.Cu")
		(at 17.018 31.3055)
		(property "Reference" "L20"
			(at -2.25933 1.016 90)
			(unlocked yes)
			(layer "F.SilkS")
			(effects
				(font
					(size 0.7874 0.5842)
					(thickness 0.127)
				)
				(justify left)
			)
		)
		(property "Value" "1.0UH"
			(at -0.483362 -0.148082 0)
			(unlocked yes)
			(layer "F.Fab")
			(hide yes)
			(effects
				(font
					(size 1.27 0.9652)
					(thickness 0.000001)
				)
				(justify left)
			)
		)
		(property "Device Type" "INDS0061"
			(at -0.483362 -0.148082 0)
			(unlocked yes)
			(layer "F.Fab")
			(hide yes)
			(effects
				(font
					(size 1.27 0.9652)
					(thickness 0.000001)
				)
				(justify left)
			)
		)
		(duplicate_pad_numbers_are_jumpers no)
		(fp_line
			(start -1.27 -1.397)
			(end 1.27 -1.397)
			(stroke
				(width 0.1524)
				(type default)
			)
			(layer "F.SilkS")
		)
		(fp_line
			(start 1.27 1.397)
			(end -1.27 1.397)
			(stroke
				(width 0.1524)
				(type default)
			)
			(layer "F.SilkS")
		)
		(fp_poly
			(pts
				(xy 2.159 -1.651) (xy 2.159 1.651) (xy -2.159 1.651) (xy -2.159 -1.651)
			)
			(stroke
				(width 0)
				(type default)
			)
			(fill no)
			(layer "F.CrtYd")
		)
		(fp_line
			(start -1.3462 -1.1049)
			(end -1.3462 1.1049)
			(stroke
				(width 0.1524)
				(type default)
			)
			(layer "F.Fab")
		)
		(fp_line
			(start -1.3462 1.1049)
			(end 1.3462 1.1049)
			(stroke
				(width 0.1524)
				(type default)
			)
			(layer "F.Fab")
		)
		(fp_line
			(start 1.3462 -1.1049)
			(end -1.3462 -1.1049)
			(stroke
				(width 0.1524)
				(type default)
			)
			(layer "F.Fab")
		)
		(fp_line
			(start 1.3462 1.1049)
			(end 1.3462 -1.1049)
			(stroke
				(width 0.1524)
				(type default)
			)
			(layer "F.Fab")
		)
		(pad "1" smd rect
			(at -1.1303 0)
			(size 1.1938 2.3368)
			(layers "F.Cu" "F.Mask" "F.Paste")
			(net "11N2296")
		)
		(pad "2" smd rect
			(at 1.1303 0)
			(size 1.1938 2.3368)
			(layers "F.Cu" "F.Mask" "F.Paste")
			(net "VDD_3.3V")
		)
		(zone
			(layer "F.Cu")
			(hatch none 0.5)
			(connect_pads
				(clearance 0)
			)
			(min_thickness 0.25)
			(keepout
				(tracks allowed)
				(vias not_allowed)
				(pads allowed)
				(copperpour not_allowed)
				(footprints allowed)
			)
			(placement
				(enabled no)
				(sheetname "")
			)
			(fill
				(thermal_gap 0.5)
				(thermal_bridge_width 0.5)
				(island_removal_mode 0)
			)
			(polygon
				(pts
					(xy 15.6718 32.4104) (xy 18.3642 32.4104) (xy 18.3642 30.2006) (xy 15.6718 30.2006)
				)
			)
		)
	)
	(footprint ""
		(layer "B.Cu")
		(at 44.73702 14.042009 -90)
		(property "Reference" "C272"
			(at 0 0 90)
			(layer "B.SilkS")
			(hide yes)
			(effects
				(font
					(size 1.27 1.27)
				)
				(justify mirror)
			)
		)
		(property "Value" ""
			(at 0 0 90)
			(layer "B.Fab")
			(effects
				(font
					(size 1.27 1.27)
				)
				(justify mirror)
			)
		)
		(duplicate_pad_numbers_are_jumpers no)
		(fp_circle
			(center 0 0)
			(end 0 -0.104648)
			(stroke
				(width 0.1016)
				(type default)
			)
			(fill no)
			(layer "B.SilkS")
		)
		(fp_poly
			(pts
				(xy 0.381 -0.889) (xy 0.381 0.889) (xy -0.381 0.889) (xy -0.381 -0.889)
			)
			(stroke
				(width 0)
				(type default)
			)
			(fill no)
			(layer "B.CrtYd")
		)
		(fp_line
			(start -0.508 1.016)
			(end 0.508 1.016)
			(stroke
				(width 0.0254)
				(type default)
			)
			(layer "B.Fab")
		)
		(fp_line
			(start 0.508 1.016)
			(end 0.508 -1.016)
			(stroke
				(width 0.0254)
				(type default)
			)
			(layer "B.Fab")
		)
		(fp_line
			(start -0.508 -1.016)
			(end -0.508 1.016)
			(stroke
				(width 0.0254)
				(type default)
			)
			(layer "B.Fab")
		)
		(fp_line
			(start 0.254 -1.016)
			(end -0.508 -1.016)
			(stroke
				(width 0.0254)
				(type default)
			)
			(layer "B.Fab")
		)
		(fp_line
			(start 0.508 -1.016)
			(end 0.254 -1.016)
			(stroke
				(width 0.0254)
				(type default)
			)
			(layer "B.Fab")
		)
		(pad "1" smd custom
			(at 0 -0.500126 90)
			(size 0.127 0.127)
			(layers "B.Cu" "B.Mask" "B.Paste")
			(net "VDD_3.3V")
			(options
				(clearance outline)
				(anchor circle)
			)
			(primitives
				(gr_poly
					(pts
						(xy -0.1778 0.254) (xy 0.1778 0.254) (xy 0.254 0.1778) (xy 0.254 -0.1778) (xy 0.1778 -0.254) (xy -0.1778 -0.254)
						(xy -0.254 -0.1778) (xy -0.254 0.1778)
					)
					(width 0)
					(fill yes)
				)
			)
		)
		(pad "2" smd custom
			(at 0 0.500126 90)
			(size 0.127 0.127)
			(layers "B.Cu" "B.Mask" "B.Paste")
			(net "GND")
			(options
				(clearance outline)
				(anchor circle)
			)
			(primitives
				(gr_poly
					(pts
						(xy -0.1778 0.254) (xy 0.1778 0.254) (xy 0.254 0.1778) (xy 0.254 -0.1778) (xy 0.1778 -0.254) (xy -0.1778 -0.254)
						(xy -0.254 -0.1778) (xy -0.254 0.1778)
					)
					(width 0)
					(fill yes)
				)
			)
		)
	)
	(footprint ""
		(layer "B.Cu")
		(at 45.237019 29.541978)
		(property "Reference" "C167"
			(at -1.575689 -0.077978 270)
			(unlocked yes)
			(layer "B.SilkS")
			(effects
				(font
					(size 0.7874 0.5842)
					(thickness 0.127)
				)
				(justify mirror)
			)
		)
		(property "Value" ""
			(at 0 0 0)
			(layer "B.Fab")
			(effects
				(font
					(size 1.27 1.27)
				)
				(justify mirror)
			)
		)
		(duplicate_pad_numbers_are_jumpers no)
		(fp_circle
			(center 0 0)
			(end 0.104648 0)
			(stroke
				(width 0.1016)
				(type default)
			)
			(fill no)
			(layer "B.SilkS")
		)
		(fp_poly
			(pts
				(xy 0.381 -0.889) (xy 0.381 0.889) (xy -0.381 0.889) (xy -0.381 -0.889)
			)
			(stroke
				(width 0)
				(type default)
			)
			(fill no)
			(layer "B.CrtYd")
		)
		(fp_line
			(start -0.508 -1.016)
			(end -0.508 1.016)
			(stroke
				(width 0.0254)
				(type default)
			)
			(layer "B.Fab")
		)
		(fp_line
			(start -0.508 1.016)
			(end 0.508 1.016)
			(stroke
				(width 0.0254)
				(type default)
			)
			(layer "B.Fab")
		)
		(fp_line
			(start 0.254 -1.016)
			(end -0.508 -1.016)
			(stroke
				(width 0.0254)
				(type default)
			)
			(layer "B.Fab")
		)
		(fp_line
			(start 0.508 -1.016)
			(end 0.254 -1.016)
			(stroke
				(width 0.0254)
				(type default)
			)
			(layer "B.Fab")
		)
		(fp_line
			(start 0.508 1.016)
			(end 0.508 -1.016)
			(stroke
				(width 0.0254)
				(type default)
			)
			(layer "B.Fab")
		)
		(pad "1" smd custom
			(at 0 -0.500126 180)
			(size 0.127 0.127)
			(layers "B.Cu" "B.Mask" "B.Paste")
			(net "VDD_CORE")
			(options
				(clearance outline)
				(anchor circle)
			)
			(primitives
				(gr_poly
					(pts
						(xy -0.1778 0.254) (xy 0.1778 0.254) (xy 0.254 0.1778) (xy 0.254 -0.1778) (xy 0.1778 -0.254) (xy -0.1778 -0.254)
						(xy -0.254 -0.1778) (xy -0.254 0.1778)
					)
					(width 0)
					(fill yes)
				)
			)
		)
		(pad "2" smd custom
			(at 0 0.500126 180)
			(size 0.127 0.127)
			(layers "B.Cu" "B.Mask" "B.Paste")
			(net "GND")
			(options
				(clearance outline)
				(anchor circle)
			)
			(primitives
				(gr_poly
					(pts
						(xy -0.1778 0.254) (xy 0.1778 0.254) (xy 0.254 0.1778) (xy 0.254 -0.1778) (xy 0.1778 -0.254) (xy -0.1778 -0.254)
						(xy -0.254 -0.1778) (xy -0.254 0.1778)
					)
					(width 0)
					(fill yes)
				)
			)
		)
	)
	(footprint ""
		(layer "B.Cu")
		(at 26.924 20.5232 180)
		(property "Reference" "R56"
			(at 0 0 0)
			(layer "B.SilkS")
			(hide yes)
			(effects
				(font
					(size 1.27 1.27)
				)
				(justify mirror)
			)
		)
		(property "Value" "4.75K"
			(at 0.148158 1.3462 90)
			(unlocked yes)
			(layer "B.Fab")
			(hide yes)
			(effects
				(font
					(size 1.27 0.9652)
					(thickness 0.000001)
				)
				(justify left mirror)
			)
		)
		(property "Device Type" "REST4024"
			(at 0.148158 1.3462 90)
			(unlocked yes)
			(layer "B.Fab")
			(hide yes)
			(effects
				(font
					(size 1.27 0.9652)
					(thickness 0.000001)
				)
				(justify left mirror)
			)
		)
		(duplicate_pad_numbers_are_jumpers no)
		(fp_poly
			(pts
				(xy -0.635 1.0668) (xy -0.635 -1.0668) (xy 0.635 -1.0668) (xy 0.635 1.0668)
			)
			(stroke
				(width 0)
				(type default)
			)
			(fill no)
			(layer "B.CrtYd")
		)
		(fp_line
			(start 0.254 0.508)
			(end 0.254 -0.508)
			(stroke
				(width 0.0254)
				(type default)
			)
			(layer "B.Fab")
		)
		(fp_line
			(start 0.254 -0.508)
			(end -0.254 -0.508)
			(stroke
				(width 0.0254)
				(type default)
			)
			(layer "B.Fab")
		)
		(fp_line
			(start -0.254 0.508)
			(end 0.254 0.508)
			(stroke
				(width 0.0254)
				(type default)
			)
			(layer "B.Fab")
		)
		(fp_line
			(start -0.254 -0.508)
			(end -0.254 0.508)
			(stroke
				(width 0.0254)
				(type default)
			)
			(layer "B.Fab")
		)
		(pad "1" smd rect
			(at 0 -0.4191)
			(size 0.508 0.5334)
			(layers "B.Cu" "B.Mask" "B.Paste")
			(net "NFP_PGOOD4")
		)
		(pad "2" smd rect
			(at 0 0.4191)
			(size 0.508 0.5334)
			(layers "B.Cu" "B.Mask" "B.Paste")
			(net "GND")
		)
		(zone
			(layer "B.Cu")
			(hatch none 0.5)
			(connect_pads
				(clearance 0)
			)
			(min_thickness 0.25)
			(keepout
				(tracks not_allowed)
				(vias allowed)
				(pads allowed)
				(copperpour not_allowed)
				(footprints allowed)
			)
			(placement
				(enabled no)
				(sheetname "")
			)
			(fill
				(thermal_gap 0.5)
				(thermal_bridge_width 0.5)
				(island_removal_mode 0)
			)
			(polygon
				(pts
					(xy 26.9494 20.5486) (xy 26.9494 20.4978) (xy 26.8986 20.4978) (xy 26.8986 20.5486)
				)
			)
		)
	)
	(footprint ""
		(layer "B.Cu")
		(at 47.1551 18.542 90)
		(property "Reference" "C4"
			(at 1.37033 1.397 0)
			(unlocked yes)
			(layer "B.SilkS")
			(effects
				(font
					(size 0.7874 0.5842)
					(thickness 0.127)
				)
				(justify left mirror)
			)
		)
		(property "Value" "22UF"
			(at 0.148158 1.7526 0)
			(unlocked yes)
			(layer "B.Fab")
			(hide yes)
			(effects
				(font
					(size 1.27 0.9652)
					(thickness 0.000001)
				)
				(justify left mirror)
			)
		)
		(property "Device Type" "CAPC0063"
			(at 0.148158 1.7526 0)
			(unlocked yes)
			(layer "B.Fab")
			(hide yes)
			(effects
				(font
					(size 1.27 0.9652)
					(thickness 0.000001)
				)
				(justify left mirror)
			)
		)
		(duplicate_pad_numbers_are_jumpers no)
		(fp_circle
			(center 0 0)
			(end 0 0.127)
			(stroke
				(width 0.2032)
				(type default)
			)
			(fill no)
			(layer "B.SilkS")
		)
		(fp_poly
			(pts
				(xy -0.7874 -1.6637) (xy 0.7874 -1.6637) (xy 0.7874 1.6637) (xy -0.7874 1.6637)
			)
			(stroke
				(width 0)
				(type default)
			)
			(fill no)
			(layer "B.CrtYd")
		)
		(fp_line
			(start 0.4064 -0.7874)
			(end -0.4064 -0.7874)
			(stroke
				(width 0.0254)
				(type default)
			)
			(layer "B.Fab")
		)
		(fp_line
			(start -0.4064 -0.7874)
			(end -0.4064 0.8128)
			(stroke
				(width 0.0254)
				(type default)
			)
			(layer "B.Fab")
		)
		(fp_line
			(start 0.4064 0.8128)
			(end 0.4064 -0.7874)
			(stroke
				(width 0.0254)
				(type default)
			)
			(layer "B.Fab")
		)
		(fp_line
			(start -0.4064 0.8128)
			(end 0.4064 0.8128)
			(stroke
				(width 0.0254)
				(type default)
			)
			(layer "B.Fab")
		)
		(pad "1" smd rect
			(at 0 -0.8001 270)
			(size 0.8636 0.9652)
			(layers "B.Cu" "B.Mask" "B.Paste")
			(net "VDD_CORE")
		)
		(pad "2" smd rect
			(at 0 0.8001 270)
			(size 0.8636 0.9652)
			(layers "B.Cu" "B.Mask" "B.Paste")
			(net "GND")
		)
		(zone
			(layer "B.Cu")
			(hatch none 0.5)
			(connect_pads
				(clearance 0)
			)
			(min_thickness 0.25)
			(keepout
				(tracks not_allowed)
				(vias allowed)
				(pads allowed)
				(copperpour not_allowed)
				(footprints allowed)
			)
			(placement
				(enabled no)
				(sheetname "")
			)
			(fill
				(thermal_gap 0.5)
				(thermal_bridge_width 0.5)
				(island_removal_mode 0)
			)
			(polygon
				(pts
					(xy 46.9011 18.4785) (xy 46.9011 18.6055) (xy 47.4091 18.6055) (xy 47.4091 18.4785)
				)
			)
		)
	)
	(footprint ""
		(layer "B.Cu")
		(at 45.085 46.101)
		(property "Reference" "TP25"
			(at 4.191 0.28067 0)
			(unlocked yes)
			(layer "B.SilkS")
			(effects
				(font
					(size 0.7874 0.5842)
					(thickness 0.127)
				)
				(justify left mirror)
			)
		)
		(property "Value" "*"
			(at 0.4826 -0.14732 0)
			(unlocked yes)
			(layer "B.Fab")
			(hide yes)
			(effects
				(font
					(size 1.27 0.9652)
					(thickness 0.000001)
				)
				(justify left mirror)
			)
		)
		(property "Device Type" "TP_SMALL"
			(at 0.4826 -0.14732 0)
			(unlocked yes)
			(layer "B.Fab")
			(hide yes)
			(effects
				(font
					(size 1.27 0.9652)
					(thickness 0.000001)
				)
				(justify left mirror)
			)
		)
		(duplicate_pad_numbers_are_jumpers no)
		(fp_line
			(start -0.8636 -0.8636)
			(end 0.8636 -0.8636)
			(stroke
				(width 0.1524)
				(type default)
			)
			(layer "B.SilkS")
		)
		(fp_line
			(start -0.8636 0.8636)
			(end -0.8636 -0.8636)
			(stroke
				(width 0.1524)
				(type default)
			)
			(layer "B.SilkS")
		)
		(fp_line
			(start 0.8636 -0.8636)
			(end 0.8636 0.8636)
			(stroke
				(width 0.1524)
				(type default)
			)
			(layer "B.SilkS")
		)
		(fp_line
			(start 0.8636 0.8636)
			(end -0.8636 0.8636)
			(stroke
				(width 0.1524)
				(type default)
			)
			(layer "B.SilkS")
		)
		(fp_poly
			(pts
				(xy 0.635 -0.635) (xy 0.635 0.635) (xy -0.635 0.635) (xy -0.635 -0.635)
			)
			(stroke
				(width 0)
				(type default)
			)
			(fill no)
			(layer "B.CrtYd")
		)
		(pad "1" smd rect
			(at 0 0 180)
			(size 1.27 1.27)
			(layers "B.Cu" "B.Mask" "B.Paste")
			(net "NFP_UART_SR_RX")
		)
	)
	(footprint ""
		(layer "B.Cu")
		(at 32.512 28.321 180)
		(property "Reference" "R264"
			(at 0.381 -0.66167 0)
			(unlocked yes)
			(layer "B.SilkS")
			(effects
				(font
					(size 0.7874 0.5842)
					(thickness 0.127)
				)
				(justify left mirror)
			)
		)
		(property "Value" "39.0"
			(at 0.148158 1.3462 90)
			(unlocked yes)
			(layer "B.Fab")
			(hide yes)
			(effects
				(font
					(size 1.27 0.9652)
					(thickness 0.000001)
				)
				(justify left mirror)
			)
		)
		(property "Device Type" "REST0108"
			(at 0.148158 1.3462 90)
			(unlocked yes)
			(layer "B.Fab")
			(hide yes)
			(effects
				(font
					(size 1.27 0.9652)
					(thickness 0.000001)
				)
				(justify left mirror)
			)
		)
		(duplicate_pad_numbers_are_jumpers no)
		(fp_poly
			(pts
				(xy -0.635 1.0668) (xy -0.635 -1.0668) (xy 0.635 -1.0668) (xy 0.635 1.0668)
			)
			(stroke
				(width 0)
				(type default)
			)
			(fill no)
			(layer "B.CrtYd")
		)
		(fp_line
			(start 0.254 0.508)
			(end 0.254 -0.508)
			(stroke
				(width 0.0254)
				(type default)
			)
			(layer "B.Fab")
		)
		(fp_line
			(start 0.254 -0.508)
			(end -0.254 -0.508)
			(stroke
				(width 0.0254)
				(type default)
			)
			(layer "B.Fab")
		)
		(fp_line
			(start -0.254 0.508)
			(end 0.254 0.508)
			(stroke
				(width 0.0254)
				(type default)
			)
			(layer "B.Fab")
		)
		(fp_line
			(start -0.254 -0.508)
			(end -0.254 0.508)
			(stroke
				(width 0.0254)
				(type default)
			)
			(layer "B.Fab")
		)
		(pad "1" smd rect
			(at 0 -0.4191)
			(size 0.508 0.5334)
			(layers "B.Cu" "B.Mask" "B.Paste")
			(net "9N1879")
		)
		(pad "2" smd rect
			(at 0 0.4191)
			(size 0.508 0.5334)
			(layers "B.Cu" "B.Mask" "B.Paste")
			(net "CPLD_PGRM_JTAG_TDO")
		)
		(zone
			(layer "B.Cu")
			(hatch none 0.5)
			(connect_pads
				(clearance 0)
			)
			(min_thickness 0.25)
			(keepout
				(tracks not_allowed)
				(vias allowed)
				(pads allowed)
				(copperpour not_allowed)
				(footprints allowed)
			)
			(placement
				(enabled no)
				(sheetname "")
			)
			(fill
				(thermal_gap 0.5)
				(thermal_bridge_width 0.5)
				(island_removal_mode 0)
			)
			(polygon
				(pts
					(xy 32.5374 28.3464) (xy 32.5374 28.2956) (xy 32.4866 28.2956) (xy 32.4866 28.3464)
				)
			)
		)
	)
	(footprint ""
		(layer "B.Cu")
		(at 49.73701 11.042015 90)
		(property "Reference" "C94"
			(at 0 0 90)
			(layer "B.SilkS")
			(hide yes)
			(effects
				(font
					(size 1.27 1.27)
				)
				(justify mirror)
			)
		)
		(property "Value" ""
			(at 0 0 90)
			(layer "B.Fab")
			(effects
				(font
					(size 1.27 1.27)
				)
				(justify mirror)
			)
		)
		(duplicate_pad_numbers_are_jumpers no)
		(fp_circle
			(center 0 0)
			(end 0 0.104648)
			(stroke
				(width 0.1016)
				(type default)
			)
			(fill no)
			(layer "B.SilkS")
		)
		(fp_poly
			(pts
				(xy 0.381 -0.889) (xy 0.381 0.889) (xy -0.381 0.889) (xy -0.381 -0.889)
			)
			(stroke
				(width 0)
				(type default)
			)
			(fill no)
			(layer "B.CrtYd")
		)
		(fp_line
			(start 0.508 -1.016)
			(end 0.254 -1.016)
			(stroke
				(width 0.0254)
				(type default)
			)
			(layer "B.Fab")
		)
		(fp_line
			(start 0.254 -1.016)
			(end -0.508 -1.016)
			(stroke
				(width 0.0254)
				(type default)
			)
			(layer "B.Fab")
		)
		(fp_line
			(start -0.508 -1.016)
			(end -0.508 1.016)
			(stroke
				(width 0.0254)
				(type default)
			)
			(layer "B.Fab")
		)
		(fp_line
			(start 0.508 1.016)
			(end 0.508 -1.016)
			(stroke
				(width 0.0254)
				(type default)
			)
			(layer "B.Fab")
		)
		(fp_line
			(start -0.508 1.016)
			(end 0.508 1.016)
			(stroke
				(width 0.0254)
				(type default)
			)
			(layer "B.Fab")
		)
		(pad "1" smd custom
			(at 0 -0.500126 270)
			(size 0.127 0.127)
			(layers "B.Cu" "B.Mask" "B.Paste")
			(net "VDDA_SERDES")
			(options
				(clearance outline)
				(anchor circle)
			)
			(primitives
				(gr_poly
					(pts
						(xy -0.1778 0.254) (xy 0.1778 0.254) (xy 0.254 0.1778) (xy 0.254 -0.1778) (xy 0.1778 -0.254) (xy -0.1778 -0.254)
						(xy -0.254 -0.1778) (xy -0.254 0.1778)
					)
					(width 0)
					(fill yes)
				)
			)
		)
		(pad "2" smd custom
			(at 0 0.500126 270)
			(size 0.127 0.127)
			(layers "B.Cu" "B.Mask" "B.Paste")
			(net "GND")
			(options
				(clearance outline)
				(anchor circle)
			)
			(primitives
				(gr_poly
					(pts
						(xy -0.1778 0.254) (xy 0.1778 0.254) (xy 0.254 0.1778) (xy 0.254 -0.1778) (xy 0.1778 -0.254) (xy -0.1778 -0.254)
						(xy -0.254 -0.1778) (xy -0.254 0.1778)
					)
					(width 0)
					(fill yes)
				)
			)
		)
	)
	(footprint ""
		(layer "B.Cu")
		(at 37.6428 20.193 -90)
		(property "Reference" "R281"
			(at 0 0 90)
			(layer "B.SilkS")
			(hide yes)
			(effects
				(font
					(size 1.27 1.27)
				)
				(justify mirror)
			)
		)
		(property "Value" "100"
			(at 0.148158 1.3462 180)
			(unlocked yes)
			(layer "B.Fab")
			(hide yes)
			(effects
				(font
					(size 1.27 0.9652)
					(thickness 0.000001)
				)
				(justify left mirror)
			)
		)
		(property "Device Type" "REST4030"
			(at 0.148158 1.3462 180)
			(unlocked yes)
			(layer "B.Fab")
			(hide yes)
			(effects
				(font
					(size 1.27 0.9652)
					(thickness 0.000001)
				)
				(justify left mirror)
			)
		)
		(duplicate_pad_numbers_are_jumpers no)
		(fp_poly
			(pts
				(xy -0.635 1.0668) (xy -0.635 -1.0668) (xy 0.635 -1.0668) (xy 0.635 1.0668)
			)
			(stroke
				(width 0)
				(type default)
			)
			(fill no)
			(layer "B.CrtYd")
		)
		(fp_line
			(start -0.254 0.508)
			(end 0.254 0.508)
			(stroke
				(width 0.0254)
				(type default)
			)
			(layer "B.Fab")
		)
		(fp_line
			(start 0.254 0.508)
			(end 0.254 -0.508)
			(stroke
				(width 0.0254)
				(type default)
			)
			(layer "B.Fab")
		)
		(fp_line
			(start -0.254 -0.508)
			(end -0.254 0.508)
			(stroke
				(width 0.0254)
				(type default)
			)
			(layer "B.Fab")
		)
		(fp_line
			(start 0.254 -0.508)
			(end -0.254 -0.508)
			(stroke
				(width 0.0254)
				(type default)
			)
			(layer "B.Fab")
		)
		(pad "1" smd rect
			(at 0 -0.4191 90)
			(size 0.508 0.5334)
			(layers "B.Cu" "B.Mask" "B.Paste")
			(net "_NFP_CFG_SPI_FLASH_SEL")
		)
		(pad "2" smd rect
			(at 0 0.4191 90)
			(size 0.508 0.5334)
			(layers "B.Cu" "B.Mask" "B.Paste")
			(net "NFP_CFG_SPI_FLASH_SEL")
		)
		(zone
			(layer "B.Cu")
			(hatch none 0.5)
			(connect_pads
				(clearance 0)
			)
			(min_thickness 0.25)
			(keepout
				(tracks not_allowed)
				(vias allowed)
				(pads allowed)
				(copperpour not_allowed)
				(footprints allowed)
			)
			(placement
				(enabled no)
				(sheetname "")
			)
			(fill
				(thermal_gap 0.5)
				(thermal_bridge_width 0.5)
				(island_removal_mode 0)
			)
			(polygon
				(pts
					(xy 37.6682 20.1676) (xy 37.6174 20.1676) (xy 37.6174 20.2184) (xy 37.6682 20.2184)
				)
			)
		)
	)
	(footprint ""
		(layer "B.Cu")
		(at 27.686 16.764 180)
		(property "Reference" "R149"
			(at 0.91567 -0.508 270)
			(unlocked yes)
			(layer "B.SilkS")
			(effects
				(font
					(size 0.7874 0.5842)
					(thickness 0.127)
				)
				(justify left mirror)
			)
		)
		(property "Value" "0"
			(at 0.148158 1.3462 90)
			(unlocked yes)
			(layer "B.Fab")
			(hide yes)
			(effects
				(font
					(size 1.27 0.9652)
					(thickness 0.000001)
				)
				(justify left mirror)
			)
		)
		(property "Device Type" "REST1111"
			(at 0.148158 1.3462 90)
			(unlocked yes)
			(layer "B.Fab")
			(hide yes)
			(effects
				(font
					(size 1.27 0.9652)
					(thickness 0.000001)
				)
				(justify left mirror)
			)
		)
		(duplicate_pad_numbers_are_jumpers no)
		(fp_poly
			(pts
				(xy -0.635 1.0668) (xy -0.635 -1.0668) (xy 0.635 -1.0668) (xy 0.635 1.0668)
			)
			(stroke
				(width 0)
				(type default)
			)
			(fill no)
			(layer "B.CrtYd")
		)
		(fp_line
			(start 0.254 0.508)
			(end 0.254 -0.508)
			(stroke
				(width 0.0254)
				(type default)
			)
			(layer "B.Fab")
		)
		(fp_line
			(start 0.254 -0.508)
			(end -0.254 -0.508)
			(stroke
				(width 0.0254)
				(type default)
			)
			(layer "B.Fab")
		)
		(fp_line
			(start -0.254 0.508)
			(end 0.254 0.508)
			(stroke
				(width 0.0254)
				(type default)
			)
			(layer "B.Fab")
		)
		(fp_line
			(start -0.254 -0.508)
			(end -0.254 0.508)
			(stroke
				(width 0.0254)
				(type default)
			)
			(layer "B.Fab")
		)
		(pad "1" smd rect
			(at 0 -0.4191)
			(size 0.508 0.5334)
			(layers "B.Cu" "B.Mask" "B.Paste")
			(net "GND")
		)
		(pad "2" smd rect
			(at 0 0.4191)
			(size 0.508 0.5334)
			(layers "B.Cu" "B.Mask" "B.Paste")
			(net "MH_2")
		)
		(zone
			(layer "B.Cu")
			(hatch none 0.5)
			(connect_pads
				(clearance 0)
			)
			(min_thickness 0.25)
			(keepout
				(tracks not_allowed)
				(vias allowed)
				(pads allowed)
				(copperpour not_allowed)
				(footprints allowed)
			)
			(placement
				(enabled no)
				(sheetname "")
			)
			(fill
				(thermal_gap 0.5)
				(thermal_bridge_width 0.5)
				(island_removal_mode 0)
			)
			(polygon
				(pts
					(xy 27.7114 16.7894) (xy 27.7114 16.7386) (xy 27.6606 16.7386) (xy 27.6606 16.7894)
				)
			)
		)
	)
	(footprint ""
		(layer "B.Cu")
		(at 62.737238 34.042096 90)
		(property "Reference" "R170"
			(at 0 0 90)
			(layer "B.SilkS")
			(hide yes)
			(effects
				(font
					(size 1.27 1.27)
				)
				(justify mirror)
			)
		)
		(property "Value" ""
			(at 0 0 90)
			(layer "B.Fab")
			(effects
				(font
					(size 1.27 1.27)
				)
				(justify mirror)
			)
		)
		(duplicate_pad_numbers_are_jumpers no)
		(fp_circle
			(center 0 0)
			(end 0 0.104648)
			(stroke
				(width 0.1016)
				(type default)
			)
			(fill no)
			(layer "B.SilkS")
		)
		(fp_poly
			(pts
				(xy 0.381 -0.889) (xy 0.381 0.889) (xy -0.381 0.889) (xy -0.381 -0.889)
			)
			(stroke
				(width 0)
				(type default)
			)
			(fill no)
			(layer "B.CrtYd")
		)
		(fp_line
			(start 0.508 -1.016)
			(end 0.254 -1.016)
			(stroke
				(width 0.0254)
				(type default)
			)
			(layer "B.Fab")
		)
		(fp_line
			(start 0.254 -1.016)
			(end -0.508 -1.016)
			(stroke
				(width 0.0254)
				(type default)
			)
			(layer "B.Fab")
		)
		(fp_line
			(start -0.508 -1.016)
			(end -0.508 1.016)
			(stroke
				(width 0.0254)
				(type default)
			)
			(layer "B.Fab")
		)
		(fp_line
			(start 0.508 1.016)
			(end 0.508 -1.016)
			(stroke
				(width 0.0254)
				(type default)
			)
			(layer "B.Fab")
		)
		(fp_line
			(start -0.508 1.016)
			(end 0.508 1.016)
			(stroke
				(width 0.0254)
				(type default)
			)
			(layer "B.Fab")
		)
		(pad "1" smd custom
			(at 0 -0.500126 270)
			(size 0.127 0.127)
			(layers "B.Cu" "B.Mask" "B.Paste")
			(net "VR_OD1_L")
			(options
				(clearance outline)
				(anchor circle)
			)
			(primitives
				(gr_poly
					(pts
						(xy -0.1778 0.254) (xy 0.1778 0.254) (xy 0.254 0.1778) (xy 0.254 -0.1778) (xy 0.1778 -0.254) (xy -0.1778 -0.254)
						(xy -0.254 -0.1778) (xy -0.254 0.1778)
					)
					(width 0)
					(fill yes)
				)
			)
		)
		(pad "2" smd custom
			(at 0 0.500126 270)
			(size 0.127 0.127)
			(layers "B.Cu" "B.Mask" "B.Paste")
			(net "10N2230")
			(options
				(clearance outline)
				(anchor circle)
			)
			(primitives
				(gr_poly
					(pts
						(xy -0.1778 0.254) (xy 0.1778 0.254) (xy 0.254 0.1778) (xy 0.254 -0.1778) (xy 0.1778 -0.254) (xy -0.1778 -0.254)
						(xy -0.254 -0.1778) (xy -0.254 0.1778)
					)
					(width 0)
					(fill yes)
				)
			)
		)
	)
	(footprint ""
		(layer "B.Cu")
		(at 79.450997 2.699004)
		(property "Reference" "V1_A-CAS"
			(at 0 0 0)
			(layer "B.SilkS")
			(hide yes)
			(effects
				(font
					(size 1.27 1.27)
				)
				(justify mirror)
			)
		)
		(property "Value" ""
			(at 0 0 0)
			(layer "B.Fab")
			(effects
				(font
					(size 1.27 1.27)
				)
				(justify mirror)
			)
		)
		(duplicate_pad_numbers_are_jumpers no)
		(pad "1" thru_hole circle
			(at 0 0 180)
			(size 0.4572 0.4572)
			(drill 0.20574)
			(layers "*.Cu" "*.Mask")
			(remove_unused_layers no)
			(net "DDR0_32A_CAS_L")
			(clearance 0.1143)
			(thermal_gap 0.1143)
		)
	)
	(footprint ""
		(layer "B.Cu")
		(at 54.737 8.291297 -90)
		(property "Reference" "L2"
			(at -1.433297 0.02667 270)
			(unlocked yes)
			(layer "B.SilkS")
			(effects
				(font
					(size 0.7874 0.5842)
					(thickness 0.127)
				)
				(justify left mirror)
			)
		)
		(property "Value" ""
			(at 0 0 90)
			(layer "B.Fab")
			(effects
				(font
					(size 1.27 1.27)
				)
				(justify mirror)
			)
		)
		(duplicate_pad_numbers_are_jumpers no)
		(fp_rect
			(start -1.7907 0.889)
			(end 1.7907 -0.889)
			(stroke
				(width 0)
				(type default)
			)
			(fill no)
			(layer "B.CrtYd")
		)
		(fp_line
			(start -1.778 0.762)
			(end 1.778 0.762)
			(stroke
				(width 0.0254)
				(type default)
			)
			(layer "B.Fab")
		)
		(fp_line
			(start 1.778 0.762)
			(end 1.778 -0.762)
			(stroke
				(width 0.0254)
				(type default)
			)
			(layer "B.Fab")
		)
		(fp_line
			(start -1.778 -0.762)
			(end -1.778 0.762)
			(stroke
				(width 0.0254)
				(type default)
			)
			(layer "B.Fab")
		)
		(fp_line
			(start 1.778 -0.762)
			(end -1.778 -0.762)
			(stroke
				(width 0.0254)
				(type default)
			)
			(layer "B.Fab")
		)
		(pad "1" smd rect
			(at 0.7493 0)
			(size 0.7874 0.8128)
			(layers "B.Cu" "B.Mask" "B.Paste")
			(net "VDD_CORE")
		)
		(pad "2" smd rect
			(at -0.7493 0)
			(size 0.7874 0.8128)
			(layers "B.Cu" "B.Mask" "B.Paste")
			(net "VDDA_PCIE0")
		)
		(zone
			(layer "B.Cu")
			(hatch none 0.5)
			(connect_pads
				(clearance 0)
			)
			(min_thickness 0.25)
			(keepout
				(tracks not_allowed)
				(vias allowed)
				(pads allowed)
				(copperpour not_allowed)
				(footprints allowed)
			)
			(placement
				(enabled no)
				(sheetname "")
			)
			(fill
				(thermal_gap 0.5)
				(thermal_bridge_width 0.5)
				(island_removal_mode 0)
			)
			(polygon
				(pts
					(xy 55.1434 8.570697) (xy 54.3306 8.570697) (xy 54.3306 8.011897) (xy 55.1434 8.011897)
				)
			)
		)
	)
	(footprint ""
		(layer "B.Cu")
		(at 82.8548 42.9006 90)
		(property "Reference" "C31"
			(at -0.68707 3.2512 0)
			(unlocked yes)
			(layer "B.SilkS")
			(effects
				(font
					(size 0.7874 0.5842)
					(thickness 0.127)
				)
				(justify left mirror)
			)
		)
		(property "Value" "0.01UF"
			(at 0.091846 0.2921 0)
			(unlocked yes)
			(layer "B.Fab")
			(hide yes)
			(effects
				(font
					(size 0.7874 0.5842)
					(thickness 0.2032)
				)
				(justify left mirror)
			)
		)
		(property "Device Type" "CAPC1553"
			(at 0.091846 0.2921 0)
			(unlocked yes)
			(layer "B.Fab")
			(hide yes)
			(effects
				(font
					(size 0.7874 0.5842)
					(thickness 0.2032)
				)
				(justify left mirror)
			)
		)
		(duplicate_pad_numbers_are_jumpers no)
		(fp_poly
			(pts
				(xy -0.635 1.0668) (xy -0.635 -1.0668) (xy 0.635 -1.0668) (xy 0.635 1.0668)
			)
			(stroke
				(width 0)
				(type default)
			)
			(fill no)
			(layer "B.CrtYd")
		)
		(fp_line
			(start 0.254 -0.508)
			(end -0.254 -0.508)
			(stroke
				(width 0.0254)
				(type default)
			)
			(layer "B.Fab")
		)
		(fp_line
			(start -0.254 -0.508)
			(end -0.254 0.508)
			(stroke
				(width 0.0254)
				(type default)
			)
			(layer "B.Fab")
		)
		(fp_line
			(start 0.254 0.508)
			(end 0.254 -0.508)
			(stroke
				(width 0.0254)
				(type default)
			)
			(layer "B.Fab")
		)
		(fp_line
			(start -0.254 0.508)
			(end 0.254 0.508)
			(stroke
				(width 0.0254)
				(type default)
			)
			(layer "B.Fab")
		)
		(pad "1" smd rect
			(at 0 -0.4191 270)
			(size 0.508 0.5334)
			(layers "B.Cu" "B.Mask" "B.Paste")
			(net "11N2146")
		)
		(pad "2" smd rect
			(at 0 0.4191 270)
			(size 0.508 0.5334)
			(layers "B.Cu" "B.Mask" "B.Paste")
			(net "GND")
		)
		(zone
			(layer "B.Cu")
			(hatch none 0.5)
			(connect_pads
				(clearance 0)
			)
			(min_thickness 0.25)
			(keepout
				(tracks not_allowed)
				(vias allowed)
				(pads allowed)
				(copperpour not_allowed)
				(footprints allowed)
			)
			(placement
				(enabled no)
				(sheetname "")
			)
			(fill
				(thermal_gap 0.5)
				(thermal_bridge_width 0.5)
				(island_removal_mode 0)
			)
			(polygon
				(pts
					(xy 82.8294 42.926) (xy 82.8802 42.926) (xy 82.8802 42.8752) (xy 82.8294 42.8752)
				)
			)
		)
	)
	(footprint ""
		(layer "B.Cu")
		(at 59.236991 31.541974)
		(property "Reference" "C168"
			(at 1.061339 -0.299974 270)
			(unlocked yes)
			(layer "B.SilkS")
			(effects
				(font
					(size 0.7874 0.5842)
					(thickness 0.127)
				)
				(justify mirror)
			)
		)
		(property "Value" ""
			(at 0 0 0)
			(layer "B.Fab")
			(effects
				(font
					(size 1.27 1.27)
				)
				(justify mirror)
			)
		)
		(duplicate_pad_numbers_are_jumpers no)
		(fp_circle
			(center 0 0)
			(end 0.104648 0)
			(stroke
				(width 0.1016)
				(type default)
			)
			(fill no)
			(layer "B.SilkS")
		)
		(fp_poly
			(pts
				(xy 0.381 -0.889) (xy 0.381 0.889) (xy -0.381 0.889) (xy -0.381 -0.889)
			)
			(stroke
				(width 0)
				(type default)
			)
			(fill no)
			(layer "B.CrtYd")
		)
		(fp_line
			(start -0.508 -1.016)
			(end -0.508 1.016)
			(stroke
				(width 0.0254)
				(type default)
			)
			(layer "B.Fab")
		)
		(fp_line
			(start -0.508 1.016)
			(end 0.508 1.016)
			(stroke
				(width 0.0254)
				(type default)
			)
			(layer "B.Fab")
		)
		(fp_line
			(start 0.254 -1.016)
			(end -0.508 -1.016)
			(stroke
				(width 0.0254)
				(type default)
			)
			(layer "B.Fab")
		)
		(fp_line
			(start 0.508 -1.016)
			(end 0.254 -1.016)
			(stroke
				(width 0.0254)
				(type default)
			)
			(layer "B.Fab")
		)
		(fp_line
			(start 0.508 1.016)
			(end 0.508 -1.016)
			(stroke
				(width 0.0254)
				(type default)
			)
			(layer "B.Fab")
		)
		(pad "1" smd custom
			(at 0 -0.500126 180)
			(size 0.127 0.127)
			(layers "B.Cu" "B.Mask" "B.Paste")
			(net "VDD_CORE")
			(options
				(clearance outline)
				(anchor circle)
			)
			(primitives
				(gr_poly
					(pts
						(xy -0.1778 0.254) (xy 0.1778 0.254) (xy 0.254 0.1778) (xy 0.254 -0.1778) (xy 0.1778 -0.254) (xy -0.1778 -0.254)
						(xy -0.254 -0.1778) (xy -0.254 0.1778)
					)
					(width 0)
					(fill yes)
				)
			)
		)
		(pad "2" smd custom
			(at 0 0.500126 180)
			(size 0.127 0.127)
			(layers "B.Cu" "B.Mask" "B.Paste")
			(net "GND")
			(options
				(clearance outline)
				(anchor circle)
			)
			(primitives
				(gr_poly
					(pts
						(xy -0.1778 0.254) (xy 0.1778 0.254) (xy 0.254 0.1778) (xy 0.254 -0.1778) (xy 0.1778 -0.254) (xy -0.1778 -0.254)
						(xy -0.254 -0.1778) (xy -0.254 0.1778)
					)
					(width 0)
					(fill yes)
				)
			)
		)
	)
	(footprint ""
		(layer "B.Cu")
		(at 76.251003 2.699004)
		(property "Reference" "V_A-DQS0-N"
			(at 0 0 0)
			(layer "B.SilkS")
			(hide yes)
			(effects
				(font
					(size 1.27 1.27)
				)
				(justify mirror)
			)
		)
		(property "Value" ""
			(at 0 0 0)
			(layer "B.Fab")
			(effects
				(font
					(size 1.27 1.27)
				)
				(justify mirror)
			)
		)
		(duplicate_pad_numbers_are_jumpers no)
		(pad "1" thru_hole circle
			(at 0 0 180)
			(size 0.4572 0.4572)
			(drill 0.20574)
			(layers "*.Cu" "*.Mask")
			(remove_unused_layers no)
			(net "DDR0_32A_DQS0_N")
			(clearance 0.1143)
			(thermal_gap 0.1143)
		)
	)
	(footprint ""
		(layer "B.Cu")
		(at 49.237011 25.541986 180)
		(property "Reference" "C175"
			(at 0.495681 2.935986 270)
			(unlocked yes)
			(layer "B.SilkS")
			(effects
				(font
					(size 0.7874 0.5842)
					(thickness 0.127)
				)
				(justify mirror)
			)
		)
		(property "Value" ""
			(at 0 0 0)
			(layer "B.Fab")
			(effects
				(font
					(size 1.27 1.27)
				)
				(justify mirror)
			)
		)
		(duplicate_pad_numbers_are_jumpers no)
		(fp_circle
			(center 0 0)
			(end -0.104648 0)
			(stroke
				(width 0.1016)
				(type default)
			)
			(fill no)
			(layer "B.SilkS")
		)
		(fp_poly
			(pts
				(xy 0.381 -0.889) (xy 0.381 0.889) (xy -0.381 0.889) (xy -0.381 -0.889)
			)
			(stroke
				(width 0)
				(type default)
			)
			(fill no)
			(layer "B.CrtYd")
		)
		(fp_line
			(start 0.508 1.016)
			(end 0.508 -1.016)
			(stroke
				(width 0.0254)
				(type default)
			)
			(layer "B.Fab")
		)
		(fp_line
			(start 0.508 -1.016)
			(end 0.254 -1.016)
			(stroke
				(width 0.0254)
				(type default)
			)
			(layer "B.Fab")
		)
		(fp_line
			(start 0.254 -1.016)
			(end -0.508 -1.016)
			(stroke
				(width 0.0254)
				(type default)
			)
			(layer "B.Fab")
		)
		(fp_line
			(start -0.508 1.016)
			(end 0.508 1.016)
			(stroke
				(width 0.0254)
				(type default)
			)
			(layer "B.Fab")
		)
		(fp_line
			(start -0.508 -1.016)
			(end -0.508 1.016)
			(stroke
				(width 0.0254)
				(type default)
			)
			(layer "B.Fab")
		)
		(pad "1" smd custom
			(at 0 -0.500126)
			(size 0.127 0.127)
			(layers "B.Cu" "B.Mask" "B.Paste")
			(net "VDD_CORE")
			(options
				(clearance outline)
				(anchor circle)
			)
			(primitives
				(gr_poly
					(pts
						(xy -0.1778 0.254) (xy 0.1778 0.254) (xy 0.254 0.1778) (xy 0.254 -0.1778) (xy 0.1778 -0.254) (xy -0.1778 -0.254)
						(xy -0.254 -0.1778) (xy -0.254 0.1778)
					)
					(width 0)
					(fill yes)
				)
			)
		)
		(pad "2" smd custom
			(at 0 0.500126)
			(size 0.127 0.127)
			(layers "B.Cu" "B.Mask" "B.Paste")
			(net "GND")
			(options
				(clearance outline)
				(anchor circle)
			)
			(primitives
				(gr_poly
					(pts
						(xy -0.1778 0.254) (xy 0.1778 0.254) (xy 0.254 0.1778) (xy 0.254 -0.1778) (xy 0.1778 -0.254) (xy -0.1778 -0.254)
						(xy -0.254 -0.1778) (xy -0.254 0.1778)
					)
					(width 0)
					(fill yes)
				)
			)
		)
	)
	(footprint ""
		(layer "B.Cu")
		(at 80.250995 14.256004)
		(property "Reference" "V2_A-WE"
			(at 0 0 0)
			(layer "B.SilkS")
			(hide yes)
			(effects
				(font
					(size 1.27 1.27)
				)
				(justify mirror)
			)
		)
		(property "Value" ""
			(at 0 0 0)
			(layer "B.Fab")
			(effects
				(font
					(size 1.27 1.27)
				)
				(justify mirror)
			)
		)
		(duplicate_pad_numbers_are_jumpers no)
		(pad "1" thru_hole circle
			(at 0 0 180)
			(size 0.4572 0.4572)
			(drill 0.20574)
			(layers "*.Cu" "*.Mask")
			(remove_unused_layers no)
			(net "DDR0_32A_WE_L")
			(clearance 0.1143)
			(thermal_gap 0.1143)
		)
	)
	(footprint ""
		(layer "B.Cu")
		(at 30.988 7.493)
		(property "Reference" "C84"
			(at -1.42367 1.143 270)
			(unlocked yes)
			(layer "B.SilkS")
			(effects
				(font
					(size 0.7874 0.5842)
					(thickness 0.127)
				)
				(justify left mirror)
			)
		)
		(property "Value" "0.1UF"
			(at 0.091846 0.2921 270)
			(unlocked yes)
			(layer "B.Fab")
			(hide yes)
			(effects
				(font
					(size 0.7874 0.5842)
					(thickness 0.2032)
				)
				(justify left mirror)
			)
		)
		(property "Device Type" "CAPC0073"
			(at 0.091846 0.2921 270)
			(unlocked yes)
			(layer "B.Fab")
			(hide yes)
			(effects
				(font
					(size 0.7874 0.5842)
					(thickness 0.2032)
				)
				(justify left mirror)
			)
		)
		(duplicate_pad_numbers_are_jumpers no)
		(fp_poly
			(pts
				(xy -0.635 1.0668) (xy -0.635 -1.0668) (xy 0.635 -1.0668) (xy 0.635 1.0668)
			)
			(stroke
				(width 0)
				(type default)
			)
			(fill no)
			(layer "B.CrtYd")
		)
		(fp_line
			(start -0.254 -0.508)
			(end -0.254 0.508)
			(stroke
				(width 0.0254)
				(type default)
			)
			(layer "B.Fab")
		)
		(fp_line
			(start -0.254 0.508)
			(end 0.254 0.508)
			(stroke
				(width 0.0254)
				(type default)
			)
			(layer "B.Fab")
		)
		(fp_line
			(start 0.254 -0.508)
			(end -0.254 -0.508)
			(stroke
				(width 0.0254)
				(type default)
			)
			(layer "B.Fab")
		)
		(fp_line
			(start 0.254 0.508)
			(end 0.254 -0.508)
			(stroke
				(width 0.0254)
				(type default)
			)
			(layer "B.Fab")
		)
		(pad "1" smd rect
			(at 0 -0.4191 180)
			(size 0.508 0.5334)
			(layers "B.Cu" "B.Mask" "B.Paste")
			(net "EXT_3.3V")
		)
		(pad "2" smd rect
			(at 0 0.4191 180)
			(size 0.508 0.5334)
			(layers "B.Cu" "B.Mask" "B.Paste")
			(net "GND")
		)
		(zone
			(layer "B.Cu")
			(hatch none 0.5)
			(connect_pads
				(clearance 0)
			)
			(min_thickness 0.25)
			(keepout
				(tracks not_allowed)
				(vias allowed)
				(pads allowed)
				(copperpour not_allowed)
				(footprints allowed)
			)
			(placement
				(enabled no)
				(sheetname "")
			)
			(fill
				(thermal_gap 0.5)
				(thermal_bridge_width 0.5)
				(island_removal_mode 0)
			)
			(polygon
				(pts
					(xy 30.9626 7.4676) (xy 30.9626 7.5184) (xy 31.0134 7.5184) (xy 31.0134 7.4676)
				)
			)
		)
	)
	(footprint ""
		(layer "B.Cu")
		(at 75.451005 29.812996)
		(property "Reference" "V_A-CB5"
			(at 0 0 0)
			(layer "B.SilkS")
			(hide yes)
			(effects
				(font
					(size 1.27 1.27)
				)
				(justify mirror)
			)
		)
		(property "Value" ""
			(at 0 0 0)
			(layer "B.Fab")
			(effects
				(font
					(size 1.27 1.27)
				)
				(justify mirror)
			)
		)
		(duplicate_pad_numbers_are_jumpers no)
		(pad "1" thru_hole circle
			(at 0 0 180)
			(size 0.4572 0.4572)
			(drill 0.20574)
			(layers "*.Cu" "*.Mask")
			(remove_unused_layers no)
			(net "DDR0_32A_CB5")
			(clearance 0.1143)
			(thermal_gap 0.1143)
		)
	)
	(footprint ""
		(layer "B.Cu")
		(at 62.236985 10.542016 180)
		(property "Reference" "C116"
			(at 0 0 0)
			(layer "B.SilkS")
			(hide yes)
			(effects
				(font
					(size 1.27 1.27)
				)
				(justify mirror)
			)
		)
		(property "Value" ""
			(at 0 0 0)
			(layer "B.Fab")
			(effects
				(font
					(size 1.27 1.27)
				)
				(justify mirror)
			)
		)
		(duplicate_pad_numbers_are_jumpers no)
		(fp_circle
			(center 0 0)
			(end -0.104648 0)
			(stroke
				(width 0.1016)
				(type default)
			)
			(fill no)
			(layer "B.SilkS")
		)
		(fp_poly
			(pts
				(xy 0.381 -0.889) (xy 0.381 0.889) (xy -0.381 0.889) (xy -0.381 -0.889)
			)
			(stroke
				(width 0)
				(type default)
			)
			(fill no)
			(layer "B.CrtYd")
		)
		(fp_line
			(start 0.508 1.016)
			(end 0.508 -1.016)
			(stroke
				(width 0.0254)
				(type default)
			)
			(layer "B.Fab")
		)
		(fp_line
			(start 0.508 -1.016)
			(end 0.254 -1.016)
			(stroke
				(width 0.0254)
				(type default)
			)
			(layer "B.Fab")
		)
		(fp_line
			(start 0.254 -1.016)
			(end -0.508 -1.016)
			(stroke
				(width 0.0254)
				(type default)
			)
			(layer "B.Fab")
		)
		(fp_line
			(start -0.508 1.016)
			(end 0.508 1.016)
			(stroke
				(width 0.0254)
				(type default)
			)
			(layer "B.Fab")
		)
		(fp_line
			(start -0.508 -1.016)
			(end -0.508 1.016)
			(stroke
				(width 0.0254)
				(type default)
			)
			(layer "B.Fab")
		)
		(pad "1" smd custom
			(at 0 -0.500126)
			(size 0.127 0.127)
			(layers "B.Cu" "B.Mask" "B.Paste")
			(net "VDDA_DDR0_32A")
			(options
				(clearance outline)
				(anchor circle)
			)
			(primitives
				(gr_poly
					(pts
						(xy -0.1778 0.254) (xy 0.1778 0.254) (xy 0.254 0.1778) (xy 0.254 -0.1778) (xy 0.1778 -0.254) (xy -0.1778 -0.254)
						(xy -0.254 -0.1778) (xy -0.254 0.1778)
					)
					(width 0)
					(fill yes)
				)
			)
		)
		(pad "2" smd custom
			(at 0 0.500126)
			(size 0.127 0.127)
			(layers "B.Cu" "B.Mask" "B.Paste")
			(net "GND")
			(options
				(clearance outline)
				(anchor circle)
			)
			(primitives
				(gr_poly
					(pts
						(xy -0.1778 0.254) (xy 0.1778 0.254) (xy 0.254 0.1778) (xy 0.254 -0.1778) (xy 0.1778 -0.254) (xy -0.1778 -0.254)
						(xy -0.254 -0.1778) (xy -0.254 0.1778)
					)
					(width 0)
					(fill yes)
				)
			)
		)
	)
	(footprint ""
		(layer "B.Cu")
		(at 66.675 35.6362 180)
		(property "Reference" "C202"
			(at 0 0 0)
			(layer "B.SilkS")
			(hide yes)
			(effects
				(font
					(size 1.27 1.27)
				)
				(justify mirror)
			)
		)
		(property "Value" "1UF"
			(at 0.091846 0.2921 90)
			(unlocked yes)
			(layer "B.Fab")
			(hide yes)
			(effects
				(font
					(size 0.7874 0.5842)
					(thickness 0.2032)
				)
				(justify left mirror)
			)
		)
		(property "Device Type" "CAPC0028"
			(at 0.091846 0.2921 90)
			(unlocked yes)
			(layer "B.Fab")
			(hide yes)
			(effects
				(font
					(size 0.7874 0.5842)
					(thickness 0.2032)
				)
				(justify left mirror)
			)
		)
		(duplicate_pad_numbers_are_jumpers no)
		(fp_poly
			(pts
				(xy -0.635 1.0668) (xy -0.635 -1.0668) (xy 0.635 -1.0668) (xy 0.635 1.0668)
			)
			(stroke
				(width 0)
				(type default)
			)
			(fill no)
			(layer "B.CrtYd")
		)
		(fp_line
			(start 0.254 0.508)
			(end 0.254 -0.508)
			(stroke
				(width 0.0254)
				(type default)
			)
			(layer "B.Fab")
		)
		(fp_line
			(start 0.254 -0.508)
			(end -0.254 -0.508)
			(stroke
				(width 0.0254)
				(type default)
			)
			(layer "B.Fab")
		)
		(fp_line
			(start -0.254 0.508)
			(end 0.254 0.508)
			(stroke
				(width 0.0254)
				(type default)
			)
			(layer "B.Fab")
		)
		(fp_line
			(start -0.254 -0.508)
			(end -0.254 0.508)
			(stroke
				(width 0.0254)
				(type default)
			)
			(layer "B.Fab")
		)
		(pad "1" smd rect
			(at 0 -0.4191)
			(size 0.508 0.5334)
			(layers "B.Cu" "B.Mask" "B.Paste")
			(net "VDD_5.0V")
		)
		(pad "2" smd rect
			(at 0 0.4191)
			(size 0.508 0.5334)
			(layers "B.Cu" "B.Mask" "B.Paste")
			(net "GND")
		)
		(zone
			(layer "B.Cu")
			(hatch none 0.5)
			(connect_pads
				(clearance 0)
			)
			(min_thickness 0.25)
			(keepout
				(tracks not_allowed)
				(vias allowed)
				(pads allowed)
				(copperpour not_allowed)
				(footprints allowed)
			)
			(placement
				(enabled no)
				(sheetname "")
			)
			(fill
				(thermal_gap 0.5)
				(thermal_bridge_width 0.5)
				(island_removal_mode 0)
			)
			(polygon
				(pts
					(xy 66.7004 35.6616) (xy 66.7004 35.6108) (xy 66.6496 35.6108) (xy 66.6496 35.6616)
				)
			)
		)
	)
	(footprint ""
		(layer "B.Cu")
		(at 34.544 32.639)
		(property "Reference" "R173"
			(at 0 0 0)
			(layer "B.SilkS")
			(hide yes)
			(effects
				(font
					(size 1.27 1.27)
				)
				(justify mirror)
			)
		)
		(property "Value" "0"
			(at 0.148158 1.3462 270)
			(unlocked yes)
			(layer "B.Fab")
			(hide yes)
			(effects
				(font
					(size 1.27 0.9652)
					(thickness 0.000001)
				)
				(justify left mirror)
			)
		)
		(property "Device Type" "REST1111"
			(at 0.148158 1.3462 270)
			(unlocked yes)
			(layer "B.Fab")
			(hide yes)
			(effects
				(font
					(size 1.27 0.9652)
					(thickness 0.000001)
				)
				(justify left mirror)
			)
		)
		(duplicate_pad_numbers_are_jumpers no)
		(fp_poly
			(pts
				(xy -0.635 1.0668) (xy -0.635 -1.0668) (xy 0.635 -1.0668) (xy 0.635 1.0668)
			)
			(stroke
				(width 0)
				(type default)
			)
			(fill no)
			(layer "B.CrtYd")
		)
		(fp_line
			(start -0.254 -0.508)
			(end -0.254 0.508)
			(stroke
				(width 0.0254)
				(type default)
			)
			(layer "B.Fab")
		)
		(fp_line
			(start -0.254 0.508)
			(end 0.254 0.508)
			(stroke
				(width 0.0254)
				(type default)
			)
			(layer "B.Fab")
		)
		(fp_line
			(start 0.254 -0.508)
			(end -0.254 -0.508)
			(stroke
				(width 0.0254)
				(type default)
			)
			(layer "B.Fab")
		)
		(fp_line
			(start 0.254 0.508)
			(end 0.254 -0.508)
			(stroke
				(width 0.0254)
				(type default)
			)
			(layer "B.Fab")
		)
		(pad "1" smd rect
			(at 0 -0.4191 180)
			(size 0.508 0.5334)
			(layers "B.Cu" "B.Mask" "B.Paste")
			(net "NFP_CORE_VID6")
		)
		(pad "2" smd rect
			(at 0 0.4191 180)
			(size 0.508 0.5334)
			(layers "B.Cu" "B.Mask" "B.Paste")
			(net "_NFP_CORE_VID6")
		)
		(zone
			(layer "B.Cu")
			(hatch none 0.5)
			(connect_pads
				(clearance 0)
			)
			(min_thickness 0.25)
			(keepout
				(tracks not_allowed)
				(vias allowed)
				(pads allowed)
				(copperpour not_allowed)
				(footprints allowed)
			)
			(placement
				(enabled no)
				(sheetname "")
			)
			(fill
				(thermal_gap 0.5)
				(thermal_bridge_width 0.5)
				(island_removal_mode 0)
			)
			(polygon
				(pts
					(xy 34.5186 32.6136) (xy 34.5186 32.6644) (xy 34.5694 32.6644) (xy 34.5694 32.6136)
				)
			)
		)
	)
	(footprint ""
		(layer "B.Cu")
		(at 59.373008 0.762 180)
		(property "Reference" "C157"
			(at 0.145212 0.8763 270)
			(unlocked yes)
			(layer "B.SilkS")
			(effects
				(font
					(size 0.7874 0.5842)
					(thickness 0.127)
				)
				(justify left mirror)
			)
		)
		(property "Value" "0.22UF"
			(at 0.091846 0.2921 90)
			(unlocked yes)
			(layer "B.Fab")
			(hide yes)
			(effects
				(font
					(size 0.7874 0.5842)
					(thickness 0.2032)
				)
				(justify left mirror)
			)
		)
		(property "Device Type" "CAPC0062"
			(at 0.091846 0.2921 90)
			(unlocked yes)
			(layer "B.Fab")
			(hide yes)
			(effects
				(font
					(size 0.7874 0.5842)
					(thickness 0.2032)
				)
				(justify left mirror)
			)
		)
		(duplicate_pad_numbers_are_jumpers no)
		(fp_poly
			(pts
				(xy -0.635 1.0668) (xy -0.635 -1.0668) (xy 0.635 -1.0668) (xy 0.635 1.0668)
			)
			(stroke
				(width 0)
				(type default)
			)
			(fill no)
			(layer "B.CrtYd")
		)
		(fp_line
			(start 0.254 0.508)
			(end 0.254 -0.508)
			(stroke
				(width 0.0254)
				(type default)
			)
			(layer "B.Fab")
		)
		(fp_line
			(start 0.254 -0.508)
			(end -0.254 -0.508)
			(stroke
				(width 0.0254)
				(type default)
			)
			(layer "B.Fab")
		)
		(fp_line
			(start -0.254 0.508)
			(end 0.254 0.508)
			(stroke
				(width 0.0254)
				(type default)
			)
			(layer "B.Fab")
		)
		(fp_line
			(start -0.254 -0.508)
			(end -0.254 0.508)
			(stroke
				(width 0.0254)
				(type default)
			)
			(layer "B.Fab")
		)
		(pad "1" smd rect
			(at 0 -0.4191)
			(size 0.508 0.5334)
			(layers "B.Cu" "B.Mask" "B.Paste")
			(net "_NFP_PCIE0_PER2_P")
		)
		(pad "2" smd rect
			(at 0 0.4191)
			(size 0.508 0.5334)
			(layers "B.Cu" "B.Mask" "B.Paste")
			(net "NFP_PCIE0_PER2_P")
		)
		(zone
			(layer "B.Cu")
			(hatch none 0.5)
			(connect_pads
				(clearance 0)
			)
			(min_thickness 0.25)
			(keepout
				(tracks not_allowed)
				(vias allowed)
				(pads allowed)
				(copperpour not_allowed)
				(footprints allowed)
			)
			(placement
				(enabled no)
				(sheetname "")
			)
			(fill
				(thermal_gap 0.5)
				(thermal_bridge_width 0.5)
				(island_removal_mode 0)
			)
			(polygon
				(pts
					(xy 59.398408 0.7874) (xy 59.398408 0.7366) (xy 59.347608 0.7366) (xy 59.347608 0.7874)
				)
			)
		)
	)
	(footprint ""
		(layer "B.Cu")
		(at 83.450989 2.699004)
		(property "Reference" "V1_A-A09"
			(at 0 0 0)
			(layer "B.SilkS")
			(hide yes)
			(effects
				(font
					(size 1.27 1.27)
				)
				(justify mirror)
			)
		)
		(property "Value" ""
			(at 0 0 0)
			(layer "B.Fab")
			(effects
				(font
					(size 1.27 1.27)
				)
				(justify mirror)
			)
		)
		(duplicate_pad_numbers_are_jumpers no)
		(pad "1" thru_hole circle
			(at 0 0 180)
			(size 0.4572 0.4572)
			(drill 0.20574)
			(layers "*.Cu" "*.Mask")
			(remove_unused_layers no)
			(net "DDR0_32A_A9")
			(clearance 0.1143)
			(thermal_gap 0.1143)
		)
	)
	(footprint ""
		(layer "B.Cu")
		(at 48.2219 40.64 90)
		(property "Reference" "U5"
			(at -4.1275 2.5781 0)
			(unlocked yes)
			(layer "B.SilkS")
			(effects
				(font
					(size 1.27 0.9652)
					(thickness 0.1524)
				)
				(justify left mirror)
			)
		)
		(property "Value" "*"
			(at 0.2921 1.813154 90)
			(unlocked yes)
			(layer "B.Fab")
			(hide yes)
			(effects
				(font
					(size 0.7874 0.5842)
					(thickness 0.2032)
				)
				(justify left mirror)
			)
		)
		(property "Device Type" "TRAN0026"
			(at 0.2921 1.813154 90)
			(unlocked yes)
			(layer "B.Fab")
			(hide yes)
			(effects
				(font
					(size 0.7874 0.5842)
					(thickness 0.2032)
				)
				(justify left mirror)
			)
		)
		(duplicate_pad_numbers_are_jumpers no)
		(fp_line
			(start 3.302 -3.302)
			(end 3.302 -2.667)
			(stroke
				(width 0.1524)
				(type default)
			)
			(layer "B.SilkS")
		)
		(fp_line
			(start 2.667 -3.302)
			(end 3.302 -3.302)
			(stroke
				(width 0.1524)
				(type default)
			)
			(layer "B.SilkS")
		)
		(fp_line
			(start -3.302 2.667)
			(end -3.302 3.302)
			(stroke
				(width 0.1524)
				(type default)
			)
			(layer "B.SilkS")
		)
		(fp_line
			(start -3.302 3.302)
			(end -2.667 3.302)
			(stroke
				(width 0.1524)
				(type default)
			)
			(layer "B.SilkS")
		)
		(fp_circle
			(center 3.81508 -2.4638)
			(end 3.81508 -2.179803)
			(stroke
				(width 0.1524)
				(type default)
			)
			(fill no)
			(layer "B.SilkS")
		)
		(fp_poly
			(pts
				(xy 0 -2.032) (xy 0 -0.127) (xy -0.889 -0.127) (xy -0.889 -2.032)
			)
			(stroke
				(width 0)
				(type default)
			)
			(fill yes)
			(layer "B.Paste")
		)
		(fp_poly
			(pts
				(xy -2.032 -2.032) (xy -2.032 -0.127) (xy -1.143 -0.127) (xy -1.143 -2.032)
			)
			(stroke
				(width 0)
				(type default)
			)
			(fill yes)
			(layer "B.Paste")
		)
		(fp_poly
			(pts
				(xy 0 2.032) (xy 0 0.127) (xy -0.889 0.127) (xy -0.889 2.032)
			)
			(stroke
				(width 0)
				(type default)
			)
			(fill yes)
			(layer "B.Paste")
		)
		(fp_poly
			(pts
				(xy -2.032 2.032) (xy -2.032 0.127) (xy -1.143 0.127) (xy -1.143 2.032)
			)
			(stroke
				(width 0)
				(type default)
			)
			(fill yes)
			(layer "B.Paste")
		)
		(fp_poly
			(pts
				(xy -3.048 -3.937) (xy -3.048 3.937) (xy 3.937 3.937) (xy 3.937 2.54) (xy 3.937 -3.937)
			)
			(stroke
				(width 0)
				(type default)
			)
			(fill no)
			(layer "B.CrtYd")
		)
		(fp_line
			(start 3.048 -3.048)
			(end 3.048 3.048)
			(stroke
				(width 0.1524)
				(type default)
			)
			(layer "B.Fab")
		)
		(fp_line
			(start -3.048 -3.048)
			(end 3.048 -3.048)
			(stroke
				(width 0.1524)
				(type default)
			)
			(layer "B.Fab")
		)
		(fp_line
			(start 3.048 3.048)
			(end -3.048 3.048)
			(stroke
				(width 0.1524)
				(type default)
			)
			(layer "B.Fab")
		)
		(fp_line
			(start -3.048 3.048)
			(end -3.048 -3.048)
			(stroke
				(width 0.1524)
				(type default)
			)
			(layer "B.Fab")
		)
		(fp_circle
			(center 2.413 -2.413)
			(end 2.413 -2.129003)
			(stroke
				(width 0.1524)
				(type default)
			)
			(fill no)
			(layer "B.Fab")
		)
		(fp_text user "40"
			(at 1.905 -4.05257 270)
			(unlocked yes)
			(layer "B.SilkS")
			(effects
				(font
					(size 0.7874 0.5842)
					(thickness 0.127)
				)
				(justify left mirror)
			)
		)
		(fp_text user "20"
			(at -3.302 3.94843 270)
			(unlocked yes)
			(layer "B.SilkS")
			(effects
				(font
					(size 0.7874 0.5842)
					(thickness 0.127)
				)
				(justify left mirror)
			)
		)
		(pad "1" smd custom
			(at 2.9464 -2.250008)
			(size 0.06985 0.06985)
			(layers "B.Cu" "B.Mask" "B.Paste")
			(net "10N2256")
			(options
				(clearance outline)
				(anchor circle)
			)
			(primitives
				(gr_poly
					(pts
						(xy -0.1397 -0.4064) (xy -0.1397 0.3302) (xy -0.0635 0.4064) (xy 0.1397 0.4064) (xy 0.1397 -0.4064)
					)
					(width 0)
					(fill yes)
				)
			)
		)
		(pad "2" smd rect
			(at 2.9464 -1.750009)
			(size 0.2794 0.8128)
			(layers "B.Cu" "B.Mask" "B.Paste")
			(net "VDD_5.0V")
		)
		(pad "3" smd rect
			(at 2.9464 -1.25001)
			(size 0.2794 0.8128)
			(layers "B.Cu" "B.Mask" "B.Paste")
			(net "10N2225")
		)
		(pad "4" smd rect
			(at 2.9464 -0.750011)
			(size 0.2794 0.8128)
			(layers "B.Cu" "B.Mask" "B.Paste")
			(net "10N2232")
		)
		(pad "5" smd rect
			(at 2.9464 -0.250012)
			(size 0.2794 0.8128)
			(layers "B.Cu" "B.Mask" "B.Paste")
			(net "GND")
		)
		(pad "6" smd rect
			(at 2.9464 0.250012)
			(size 0.2794 0.8128)
			(layers "B.Cu" "B.Mask" "B.Paste")
			(net "GH_PHASE2")
		)
		(pad "7" smd rect
			(at 2.9464 0.750011)
			(size 0.2794 0.8128)
			(layers "B.Cu" "B.Mask" "B.Paste")
			(net "10N2259")
		)
		(pad "8" smd rect
			(at 2.9464 1.25001)
			(size 0.2794 0.8128)
			(layers "B.Cu" "B.Mask" "B.Paste")
			(net "EXT_12.0V")
		)
		(pad "9" smd rect
			(at 2.9464 1.750009)
			(size 0.2794 0.8128)
			(layers "B.Cu" "B.Mask" "B.Paste")
			(net "EXT_12.0V")
		)
		(pad "10" smd custom
			(at 2.9464 2.250008)
			(size 0.06985 0.06985)
			(layers "B.Cu" "B.Mask" "B.Paste")
			(net "EXT_12.0V")
			(options
				(clearance outline)
				(anchor circle)
			)
			(primitives
				(gr_poly
					(pts
						(xy 0.1397 -0.4064) (xy 0.1397 0.3302) (xy 0.0635 0.4064) (xy -0.1397 0.4064) (xy -0.1397 -0.4064)
					)
					(width 0)
					(fill yes)
				)
			)
		)
		(pad "11" smd custom
			(at 2.250008 2.9464 270)
			(size 0.06985 0.06985)
			(layers "B.Cu" "B.Mask" "B.Paste")
			(net "EXT_12.0V")
			(options
				(clearance outline)
				(anchor circle)
			)
			(primitives
				(gr_poly
					(pts
						(xy -0.1397 -0.4064) (xy -0.1397 0.3302) (xy -0.0635 0.4064) (xy 0.1397 0.4064) (xy 0.1397 -0.4064)
					)
					(width 0)
					(fill yes)
				)
			)
		)
		(pad "12" smd rect
			(at 1.750009 2.9464 270)
			(size 0.2794 0.8128)
			(layers "B.Cu" "B.Mask" "B.Paste")
			(net "EXT_12.0V")
		)
		(pad "13" smd rect
			(at 1.25001 2.9464 270)
			(size 0.2794 0.8128)
			(layers "B.Cu" "B.Mask" "B.Paste")
			(net "EXT_12.0V")
		)
		(pad "14" smd rect
			(at 0.750011 2.9464 270)
			(size 0.2794 0.8128)
			(layers "B.Cu" "B.Mask" "B.Paste")
			(net "EXT_12.0V")
		)
		(pad "15" smd rect
			(at 0.250012 2.9464 270)
			(size 0.2794 0.8128)
			(layers "B.Cu" "B.Mask" "B.Paste")
			(net "L_2_CORE_PHASE")
		)
		(pad "16" smd rect
			(at -0.250012 2.9464 270)
			(size 0.2794 0.8128)
			(layers "B.Cu" "B.Mask" "B.Paste")
			(net "GND")
		)
		(pad "17" smd rect
			(at -0.750011 2.9464 270)
			(size 0.2794 0.8128)
			(layers "B.Cu" "B.Mask" "B.Paste")
			(net "GND")
		)
		(pad "18" smd rect
			(at -1.25001 2.9464 270)
			(size 0.2794 0.8128)
			(layers "B.Cu" "B.Mask" "B.Paste")
			(net "GND")
		)
		(pad "19" smd rect
			(at -1.750009 2.9464 270)
			(size 0.2794 0.8128)
			(layers "B.Cu" "B.Mask" "B.Paste")
			(net "GND")
		)
		(pad "20" smd custom
			(at -2.250008 2.9464 270)
			(size 0.06985 0.06985)
			(layers "B.Cu" "B.Mask" "B.Paste")
			(net "GND")
			(options
				(clearance outline)
				(anchor circle)
			)
			(primitives
				(gr_poly
					(pts
						(xy 0.1397 -0.4064) (xy 0.1397 0.3302) (xy 0.0635 0.4064) (xy -0.1397 0.4064) (xy -0.1397 -0.4064)
					)
					(width 0)
					(fill yes)
				)
			)
		)
		(pad "21" smd custom
			(at -2.9464 2.250008 180)
			(size 0.06985 0.06985)
			(layers "B.Cu" "B.Mask" "B.Paste")
			(net "GND")
			(options
				(clearance outline)
				(anchor circle)
			)
			(primitives
				(gr_poly
					(pts
						(xy -0.1397 -0.4064) (xy -0.1397 0.3302) (xy -0.0635 0.4064) (xy 0.1397 0.4064) (xy 0.1397 -0.4064)
					)
					(width 0)
					(fill yes)
				)
			)
		)
		(pad "22" smd rect
			(at -2.9464 1.750009 180)
			(size 0.2794 0.8128)
			(layers "B.Cu" "B.Mask" "B.Paste")
			(net "GND")
		)
		(pad "23" smd rect
			(at -2.9464 1.25001 180)
			(size 0.2794 0.8128)
			(layers "B.Cu" "B.Mask" "B.Paste")
			(net "GND")
		)
		(pad "24" smd rect
			(at -2.9464 0.750011 180)
			(size 0.2794 0.8128)
			(layers "B.Cu" "B.Mask" "B.Paste")
			(net "GND")
		)
		(pad "25" smd rect
			(at -2.9464 0.250012 180)
			(size 0.2794 0.8128)
			(layers "B.Cu" "B.Mask" "B.Paste")
			(net "GND")
		)
		(pad "26" smd rect
			(at -2.9464 -0.250012 180)
			(size 0.2794 0.8128)
			(layers "B.Cu" "B.Mask" "B.Paste")
			(net "GND")
		)
		(pad "27" smd rect
			(at -2.9464 -0.750011 180)
			(size 0.2794 0.8128)
			(layers "B.Cu" "B.Mask" "B.Paste")
			(net "GND")
		)
		(pad "28" smd rect
			(at -2.9464 -1.25001 180)
			(size 0.2794 0.8128)
			(layers "B.Cu" "B.Mask" "B.Paste")
			(net "GND")
		)
		(pad "29" smd rect
			(at -2.9464 -1.750009 180)
			(size 0.2794 0.8128)
			(layers "B.Cu" "B.Mask" "B.Paste")
			(net "L_2_CORE_PHASE")
		)
		(pad "30" smd custom
			(at -2.9464 -2.250008 180)
			(size 0.06985 0.06985)
			(layers "B.Cu" "B.Mask" "B.Paste")
			(net "L_2_CORE_PHASE")
			(options
				(clearance outline)
				(anchor circle)
			)
			(primitives
				(gr_poly
					(pts
						(xy 0.1397 -0.4064) (xy 0.1397 0.3302) (xy 0.0635 0.4064) (xy -0.1397 0.4064) (xy -0.1397 -0.4064)
					)
					(width 0)
					(fill yes)
				)
			)
		)
		(pad "31" smd custom
			(at -2.250008 -2.9464 90)
			(size 0.06985 0.06985)
			(layers "B.Cu" "B.Mask" "B.Paste")
			(net "L_2_CORE_PHASE")
			(options
				(clearance outline)
				(anchor circle)
			)
			(primitives
				(gr_poly
					(pts
						(xy -0.1397 -0.4064) (xy -0.1397 0.3302) (xy -0.0635 0.4064) (xy 0.1397 0.4064) (xy 0.1397 -0.4064)
					)
					(width 0)
					(fill yes)
				)
			)
		)
		(pad "32" smd rect
			(at -1.750009 -2.9464 90)
			(size 0.2794 0.8128)
			(layers "B.Cu" "B.Mask" "B.Paste")
			(net "L_2_CORE_PHASE")
		)
		(pad "33" smd rect
			(at -1.25001 -2.9464 90)
			(size 0.2794 0.8128)
			(layers "B.Cu" "B.Mask" "B.Paste")
			(net "L_2_CORE_PHASE")
		)
		(pad "34" smd rect
			(at -0.750011 -2.9464 90)
			(size 0.2794 0.8128)
			(layers "B.Cu" "B.Mask" "B.Paste")
			(net "L_2_CORE_PHASE")
		)
		(pad "35" smd rect
			(at -0.250012 -2.9464 90)
			(size 0.2794 0.8128)
			(layers "B.Cu" "B.Mask" "B.Paste")
			(net "L_2_CORE_PHASE")
		)
		(pad "36" smd rect
			(at 0.250012 -2.9464 90)
			(size 0.2794 0.8128)
			(layers "B.Cu" "B.Mask" "B.Paste")
			(net "GL_PHASE2")
		)
		(pad "37" smd rect
			(at 0.750011 -2.9464 90)
			(size 0.2794 0.8128)
			(layers "B.Cu" "B.Mask" "B.Paste")
			(net "GND")
		)
		(pad "38" smd rect
			(at 1.25001 -2.9464 90)
			(size 0.2794 0.8128)
			(layers "B.Cu" "B.Mask" "B.Paste")
			(net "CORE_FB_PH2_THERM_L")
		)
		(pad "39" smd rect
			(at 1.750009 -2.9464 90)
			(size 0.2794 0.8128)
			(layers "B.Cu" "B.Mask" "B.Paste")
			(net "10N2235")
		)
		(pad "40" smd custom
			(at 2.250008 -2.9464 90)
			(size 0.06985 0.06985)
			(layers "B.Cu" "B.Mask" "B.Paste")
			(net "NFP_CORE_PWM2")
			(options
				(clearance outline)
				(anchor circle)
			)
			(primitives
				(gr_poly
					(pts
						(xy 0.1397 -0.4064) (xy 0.1397 0.3302) (xy 0.0635 0.4064) (xy -0.1397 0.4064) (xy -0.1397 -0.4064)
					)
					(width 0)
					(fill yes)
				)
			)
		)
		(pad "41" smd rect
			(at 1.4478 -1.1938 270)
			(size 1.4986 2.0066)
			(layers "B.Cu" "B.Mask" "B.Paste")
			(net "GND")
		)
		(pad "42" smd rect
			(at 1.4478 1.1938 270)
			(size 1.4986 2.0066)
			(layers "B.Cu" "B.Mask" "B.Paste")
			(net "EXT_12.0V")
		)
		(pad "43" smd rect
			(at -1.0033 0 270)
			(size 2.3876 4.3942)
			(layers "B.Cu" "B.Mask" "B.Paste")
			(net "L_2_CORE_PHASE")
		)
		(zone
			(layer "B.Cu")
			(hatch none 0.5)
			(connect_pads
				(clearance 0)
			)
			(min_thickness 0.25)
			(keepout
				(tracks allowed)
				(vias not_allowed)
				(pads allowed)
				(copperpour not_allowed)
				(footprints allowed)
			)
			(placement
				(enabled no)
				(sheetname "")
			)
			(fill
				(thermal_gap 0.5)
				(thermal_bridge_width 0.5)
				(island_removal_mode 0)
			)
			(polygon
				(pts
					(arc
						(start 46.118297 36.82492)
						(mid 45.397903 36.82492)
						(end 46.118297 36.82492)
					)
				)
			)
		)
	)
	(footprint ""
		(layer "B.Cu")
		(at 5.08 3.81 90)
		(property "Reference" "R277"
			(at 0 0 90)
			(layer "B.SilkS")
			(hide yes)
			(effects
				(font
					(size 1.27 1.27)
				)
				(justify mirror)
			)
		)
		(property "Value" "240"
			(at 0.148158 1.3462 0)
			(unlocked yes)
			(layer "B.Fab")
			(hide yes)
			(effects
				(font
					(size 1.27 0.9652)
					(thickness 0.000001)
				)
				(justify left mirror)
			)
		)
		(property "Device Type" "REST0009"
			(at 0.148158 1.3462 0)
			(unlocked yes)
			(layer "B.Fab")
			(hide yes)
			(effects
				(font
					(size 1.27 0.9652)
					(thickness 0.000001)
				)
				(justify left mirror)
			)
		)
		(duplicate_pad_numbers_are_jumpers no)
		(fp_poly
			(pts
				(xy -0.635 1.0668) (xy -0.635 -1.0668) (xy 0.635 -1.0668) (xy 0.635 1.0668)
			)
			(stroke
				(width 0)
				(type default)
			)
			(fill no)
			(layer "B.CrtYd")
		)
		(fp_line
			(start 0.254 -0.508)
			(end -0.254 -0.508)
			(stroke
				(width 0.0254)
				(type default)
			)
			(layer "B.Fab")
		)
		(fp_line
			(start -0.254 -0.508)
			(end -0.254 0.508)
			(stroke
				(width 0.0254)
				(type default)
			)
			(layer "B.Fab")
		)
		(fp_line
			(start 0.254 0.508)
			(end 0.254 -0.508)
			(stroke
				(width 0.0254)
				(type default)
			)
			(layer "B.Fab")
		)
		(fp_line
			(start -0.254 0.508)
			(end 0.254 0.508)
			(stroke
				(width 0.0254)
				(type default)
			)
			(layer "B.Fab")
		)
		(pad "1" smd rect
			(at 0 -0.4191 270)
			(size 0.508 0.5334)
			(layers "B.Cu" "B.Mask" "B.Paste")
			(net "PWR_GOOD_LED_L")
		)
		(pad "2" smd rect
			(at 0 0.4191 270)
			(size 0.508 0.5334)
			(layers "B.Cu" "B.Mask" "B.Paste")
			(net "9N2141")
		)
		(zone
			(layer "B.Cu")
			(hatch none 0.5)
			(connect_pads
				(clearance 0)
			)
			(min_thickness 0.25)
			(keepout
				(tracks not_allowed)
				(vias allowed)
				(pads allowed)
				(copperpour not_allowed)
				(footprints allowed)
			)
			(placement
				(enabled no)
				(sheetname "")
			)
			(fill
				(thermal_gap 0.5)
				(thermal_bridge_width 0.5)
				(island_removal_mode 0)
			)
			(polygon
				(pts
					(xy 5.0546 3.8354) (xy 5.1054 3.8354) (xy 5.1054 3.7846) (xy 5.0546 3.7846)
				)
			)
		)
	)
	(footprint ""
		(layer "B.Cu")
		(at 56.236997 27.541982)
		(property "Reference" "C163"
			(at 0 0 0)
			(layer "B.SilkS")
			(hide yes)
			(effects
				(font
					(size 1.27 1.27)
				)
				(justify mirror)
			)
		)
		(property "Value" ""
			(at 0 0 0)
			(layer "B.Fab")
			(effects
				(font
					(size 1.27 1.27)
				)
				(justify mirror)
			)
		)
		(duplicate_pad_numbers_are_jumpers no)
		(fp_circle
			(center 0 0)
			(end 0.104648 0)
			(stroke
				(width 0.1016)
				(type default)
			)
			(fill no)
			(layer "B.SilkS")
		)
		(fp_poly
			(pts
				(xy 0.381 -0.889) (xy 0.381 0.889) (xy -0.381 0.889) (xy -0.381 -0.889)
			)
			(stroke
				(width 0)
				(type default)
			)
			(fill no)
			(layer "B.CrtYd")
		)
		(fp_line
			(start -0.508 -1.016)
			(end -0.508 1.016)
			(stroke
				(width 0.0254)
				(type default)
			)
			(layer "B.Fab")
		)
		(fp_line
			(start -0.508 1.016)
			(end 0.508 1.016)
			(stroke
				(width 0.0254)
				(type default)
			)
			(layer "B.Fab")
		)
		(fp_line
			(start 0.254 -1.016)
			(end -0.508 -1.016)
			(stroke
				(width 0.0254)
				(type default)
			)
			(layer "B.Fab")
		)
		(fp_line
			(start 0.508 -1.016)
			(end 0.254 -1.016)
			(stroke
				(width 0.0254)
				(type default)
			)
			(layer "B.Fab")
		)
		(fp_line
			(start 0.508 1.016)
			(end 0.508 -1.016)
			(stroke
				(width 0.0254)
				(type default)
			)
			(layer "B.Fab")
		)
		(pad "1" smd custom
			(at 0 -0.500126 180)
			(size 0.127 0.127)
			(layers "B.Cu" "B.Mask" "B.Paste")
			(net "VDD_CORE")
			(options
				(clearance outline)
				(anchor circle)
			)
			(primitives
				(gr_poly
					(pts
						(xy -0.1778 0.254) (xy 0.1778 0.254) (xy 0.254 0.1778) (xy 0.254 -0.1778) (xy 0.1778 -0.254) (xy -0.1778 -0.254)
						(xy -0.254 -0.1778) (xy -0.254 0.1778)
					)
					(width 0)
					(fill yes)
				)
			)
		)
		(pad "2" smd custom
			(at 0 0.500126 180)
			(size 0.127 0.127)
			(layers "B.Cu" "B.Mask" "B.Paste")
			(net "GND")
			(options
				(clearance outline)
				(anchor circle)
			)
			(primitives
				(gr_poly
					(pts
						(xy -0.1778 0.254) (xy 0.1778 0.254) (xy 0.254 0.1778) (xy 0.254 -0.1778) (xy 0.1778 -0.254) (xy -0.1778 -0.254)
						(xy -0.254 -0.1778) (xy -0.254 0.1778)
					)
					(width 0)
					(fill yes)
				)
			)
		)
	)
	(footprint ""
		(layer "B.Cu")
		(at 84.250987 18.255996)
		(property "Reference" "V2_A-A14"
			(at 0 0 0)
			(layer "B.SilkS")
			(hide yes)
			(effects
				(font
					(size 1.27 1.27)
				)
				(justify mirror)
			)
		)
		(property "Value" ""
			(at 0 0 0)
			(layer "B.Fab")
			(effects
				(font
					(size 1.27 1.27)
				)
				(justify mirror)
			)
		)
		(duplicate_pad_numbers_are_jumpers no)
		(pad "1" thru_hole circle
			(at 0 0 180)
			(size 0.4572 0.4572)
			(drill 0.20574)
			(layers "*.Cu" "*.Mask")
			(remove_unused_layers no)
			(net "DDR0_32A_A14")
			(clearance 0.1143)
			(thermal_gap 0.1143)
		)
	)
	(footprint ""
		(layer "B.Cu")
		(at 45.237019 33.54197)
		(property "Reference" "C79"
			(at 1.472311 -0.64897 270)
			(unlocked yes)
			(layer "B.SilkS")
			(effects
				(font
					(size 0.7874 0.5842)
					(thickness 0.127)
				)
				(justify mirror)
			)
		)
		(property "Value" ""
			(at 0 0 0)
			(layer "B.Fab")
			(effects
				(font
					(size 1.27 1.27)
				)
				(justify mirror)
			)
		)
		(duplicate_pad_numbers_are_jumpers no)
		(fp_circle
			(center 0 0)
			(end 0.104648 0)
			(stroke
				(width 0.1016)
				(type default)
			)
			(fill no)
			(layer "B.SilkS")
		)
		(fp_poly
			(pts
				(xy 0.381 -0.889) (xy 0.381 0.889) (xy -0.381 0.889) (xy -0.381 -0.889)
			)
			(stroke
				(width 0)
				(type default)
			)
			(fill no)
			(layer "B.CrtYd")
		)
		(fp_line
			(start -0.508 -1.016)
			(end -0.508 1.016)
			(stroke
				(width 0.0254)
				(type default)
			)
			(layer "B.Fab")
		)
		(fp_line
			(start -0.508 1.016)
			(end 0.508 1.016)
			(stroke
				(width 0.0254)
				(type default)
			)
			(layer "B.Fab")
		)
		(fp_line
			(start 0.254 -1.016)
			(end -0.508 -1.016)
			(stroke
				(width 0.0254)
				(type default)
			)
			(layer "B.Fab")
		)
		(fp_line
			(start 0.508 -1.016)
			(end 0.254 -1.016)
			(stroke
				(width 0.0254)
				(type default)
			)
			(layer "B.Fab")
		)
		(fp_line
			(start 0.508 1.016)
			(end 0.508 -1.016)
			(stroke
				(width 0.0254)
				(type default)
			)
			(layer "B.Fab")
		)
		(pad "1" smd custom
			(at 0 -0.500126 180)
			(size 0.127 0.127)
			(layers "B.Cu" "B.Mask" "B.Paste")
			(net "VDD_CORE")
			(options
				(clearance outline)
				(anchor circle)
			)
			(primitives
				(gr_poly
					(pts
						(xy -0.1778 0.254) (xy 0.1778 0.254) (xy 0.254 0.1778) (xy 0.254 -0.1778) (xy 0.1778 -0.254) (xy -0.1778 -0.254)
						(xy -0.254 -0.1778) (xy -0.254 0.1778)
					)
					(width 0)
					(fill yes)
				)
			)
		)
		(pad "2" smd custom
			(at 0 0.500126 180)
			(size 0.127 0.127)
			(layers "B.Cu" "B.Mask" "B.Paste")
			(net "GND")
			(options
				(clearance outline)
				(anchor circle)
			)
			(primitives
				(gr_poly
					(pts
						(xy -0.1778 0.254) (xy 0.1778 0.254) (xy 0.254 0.1778) (xy 0.254 -0.1778) (xy 0.1778 -0.254) (xy -0.1778 -0.254)
						(xy -0.254 -0.1778) (xy -0.254 0.1778)
					)
					(width 0)
					(fill yes)
				)
			)
		)
	)
	(footprint ""
		(layer "B.Cu")
		(at 83.450989 18.255996)
		(property "Reference" "V2_A-A11"
			(at 0 0 0)
			(layer "B.SilkS")
			(hide yes)
			(effects
				(font
					(size 1.27 1.27)
				)
				(justify mirror)
			)
		)
		(property "Value" ""
			(at 0 0 0)
			(layer "B.Fab")
			(effects
				(font
					(size 1.27 1.27)
				)
				(justify mirror)
			)
		)
		(duplicate_pad_numbers_are_jumpers no)
		(pad "1" thru_hole circle
			(at 0 0 180)
			(size 0.4572 0.4572)
			(drill 0.20574)
			(layers "*.Cu" "*.Mask")
			(remove_unused_layers no)
			(net "DDR0_32A_A11")
			(clearance 0.1143)
			(thermal_gap 0.1143)
		)
	)
	(footprint ""
		(layer "B.Cu")
		(at 60.736988 14.042009 90)
		(property "Reference" "R145"
			(at 0 0 90)
			(layer "B.SilkS")
			(hide yes)
			(effects
				(font
					(size 1.27 1.27)
				)
				(justify mirror)
			)
		)
		(property "Value" ""
			(at 0 0 90)
			(layer "B.Fab")
			(effects
				(font
					(size 1.27 1.27)
				)
				(justify mirror)
			)
		)
		(duplicate_pad_numbers_are_jumpers no)
		(fp_circle
			(center 0 0)
			(end 0 0.104648)
			(stroke
				(width 0.1016)
				(type default)
			)
			(fill no)
			(layer "B.SilkS")
		)
		(fp_poly
			(pts
				(xy 0.381 -0.889) (xy 0.381 0.889) (xy -0.381 0.889) (xy -0.381 -0.889)
			)
			(stroke
				(width 0)
				(type default)
			)
			(fill no)
			(layer "B.CrtYd")
		)
		(fp_line
			(start 0.508 -1.016)
			(end 0.254 -1.016)
			(stroke
				(width 0.0254)
				(type default)
			)
			(layer "B.Fab")
		)
		(fp_line
			(start 0.254 -1.016)
			(end -0.508 -1.016)
			(stroke
				(width 0.0254)
				(type default)
			)
			(layer "B.Fab")
		)
		(fp_line
			(start -0.508 -1.016)
			(end -0.508 1.016)
			(stroke
				(width 0.0254)
				(type default)
			)
			(layer "B.Fab")
		)
		(fp_line
			(start 0.508 1.016)
			(end 0.508 -1.016)
			(stroke
				(width 0.0254)
				(type default)
			)
			(layer "B.Fab")
		)
		(fp_line
			(start -0.508 1.016)
			(end 0.508 1.016)
			(stroke
				(width 0.0254)
				(type default)
			)
			(layer "B.Fab")
		)
		(pad "1" smd custom
			(at 0 -0.500126 270)
			(size 0.127 0.127)
			(layers "B.Cu" "B.Mask" "B.Paste")
			(net "VDD_CORE")
			(options
				(clearance outline)
				(anchor circle)
			)
			(primitives
				(gr_poly
					(pts
						(xy -0.1778 0.254) (xy 0.1778 0.254) (xy 0.254 0.1778) (xy 0.254 -0.1778) (xy 0.1778 -0.254) (xy -0.1778 -0.254)
						(xy -0.254 -0.1778) (xy -0.254 0.1778)
					)
					(width 0)
					(fill yes)
				)
			)
		)
		(pad "2" smd custom
			(at 0 0.500126 270)
			(size 0.127 0.127)
			(layers "B.Cu" "B.Mask" "B.Paste")
			(net "VDDA_DDR0_32B")
			(options
				(clearance outline)
				(anchor circle)
			)
			(primitives
				(gr_poly
					(pts
						(xy -0.1778 0.254) (xy 0.1778 0.254) (xy 0.254 0.1778) (xy 0.254 -0.1778) (xy 0.1778 -0.254) (xy -0.1778 -0.254)
						(xy -0.254 -0.1778) (xy -0.254 0.1778)
					)
					(width 0)
					(fill yes)
				)
			)
		)
	)
	(footprint ""
		(layer "B.Cu")
		(at 52.737004 7.042023 90)
		(property "Reference" "C101"
			(at 0 0 90)
			(layer "B.SilkS")
			(hide yes)
			(effects
				(font
					(size 1.27 1.27)
				)
				(justify mirror)
			)
		)
		(property "Value" ""
			(at 0 0 90)
			(layer "B.Fab")
			(effects
				(font
					(size 1.27 1.27)
				)
				(justify mirror)
			)
		)
		(duplicate_pad_numbers_are_jumpers no)
		(fp_circle
			(center 0 0)
			(end 0 0.104648)
			(stroke
				(width 0.1016)
				(type default)
			)
			(fill no)
			(layer "B.SilkS")
		)
		(fp_poly
			(pts
				(xy 0.381 -0.889) (xy 0.381 0.889) (xy -0.381 0.889) (xy -0.381 -0.889)
			)
			(stroke
				(width 0)
				(type default)
			)
			(fill no)
			(layer "B.CrtYd")
		)
		(fp_line
			(start 0.508 -1.016)
			(end 0.254 -1.016)
			(stroke
				(width 0.0254)
				(type default)
			)
			(layer "B.Fab")
		)
		(fp_line
			(start 0.254 -1.016)
			(end -0.508 -1.016)
			(stroke
				(width 0.0254)
				(type default)
			)
			(layer "B.Fab")
		)
		(fp_line
			(start -0.508 -1.016)
			(end -0.508 1.016)
			(stroke
				(width 0.0254)
				(type default)
			)
			(layer "B.Fab")
		)
		(fp_line
			(start 0.508 1.016)
			(end 0.508 -1.016)
			(stroke
				(width 0.0254)
				(type default)
			)
			(layer "B.Fab")
		)
		(fp_line
			(start -0.508 1.016)
			(end 0.508 1.016)
			(stroke
				(width 0.0254)
				(type default)
			)
			(layer "B.Fab")
		)
		(pad "1" smd custom
			(at 0 -0.500126 270)
			(size 0.127 0.127)
			(layers "B.Cu" "B.Mask" "B.Paste")
			(net "VDDAH_SERDES")
			(options
				(clearance outline)
				(anchor circle)
			)
			(primitives
				(gr_poly
					(pts
						(xy -0.1778 0.254) (xy 0.1778 0.254) (xy 0.254 0.1778) (xy 0.254 -0.1778) (xy 0.1778 -0.254) (xy -0.1778 -0.254)
						(xy -0.254 -0.1778) (xy -0.254 0.1778)
					)
					(width 0)
					(fill yes)
				)
			)
		)
		(pad "2" smd custom
			(at 0 0.500126 270)
			(size 0.127 0.127)
			(layers "B.Cu" "B.Mask" "B.Paste")
			(net "GND")
			(options
				(clearance outline)
				(anchor circle)
			)
			(primitives
				(gr_poly
					(pts
						(xy -0.1778 0.254) (xy 0.1778 0.254) (xy 0.254 0.1778) (xy 0.254 -0.1778) (xy 0.1778 -0.254) (xy -0.1778 -0.254)
						(xy -0.254 -0.1778) (xy -0.254 0.1778)
					)
					(width 0)
					(fill yes)
				)
			)
		)
	)
	(footprint ""
		(layer "B.Cu")
		(at 3.3655 16.129 90)
		(property "Reference" "R385"
			(at 0 0 90)
			(layer "B.SilkS")
			(hide yes)
			(effects
				(font
					(size 1.27 1.27)
				)
				(justify mirror)
			)
		)
		(property "Value" "0"
			(at 0.148158 1.3462 0)
			(unlocked yes)
			(layer "B.Fab")
			(hide yes)
			(effects
				(font
					(size 1.27 0.9652)
					(thickness 0.000001)
				)
				(justify left mirror)
			)
		)
		(property "Device Type" "REST1111"
			(at 0.148158 1.3462 0)
			(unlocked yes)
			(layer "B.Fab")
			(hide yes)
			(effects
				(font
					(size 1.27 0.9652)
					(thickness 0.000001)
				)
				(justify left mirror)
			)
		)
		(duplicate_pad_numbers_are_jumpers no)
		(fp_poly
			(pts
				(xy -0.635 1.0668) (xy -0.635 -1.0668) (xy 0.635 -1.0668) (xy 0.635 1.0668)
			)
			(stroke
				(width 0)
				(type default)
			)
			(fill no)
			(layer "B.CrtYd")
		)
		(fp_line
			(start 0.254 -0.508)
			(end -0.254 -0.508)
			(stroke
				(width 0.0254)
				(type default)
			)
			(layer "B.Fab")
		)
		(fp_line
			(start -0.254 -0.508)
			(end -0.254 0.508)
			(stroke
				(width 0.0254)
				(type default)
			)
			(layer "B.Fab")
		)
		(fp_line
			(start 0.254 0.508)
			(end 0.254 -0.508)
			(stroke
				(width 0.0254)
				(type default)
			)
			(layer "B.Fab")
		)
		(fp_line
			(start -0.254 0.508)
			(end 0.254 0.508)
			(stroke
				(width 0.0254)
				(type default)
			)
			(layer "B.Fab")
		)
		(pad "1" smd rect
			(at 0 -0.4191 270)
			(size 0.508 0.5334)
			(layers "B.Cu" "B.Mask" "B.Paste")
			(net "NWK0_I2C_SCL")
		)
		(pad "2" smd rect
			(at 0 0.4191 270)
			(size 0.508 0.5334)
			(layers "B.Cu" "B.Mask" "B.Paste")
			(net "MUX_NFP_GPIO0_NWK0_I2C_SCL")
		)
		(zone
			(layer "B.Cu")
			(hatch none 0.5)
			(connect_pads
				(clearance 0)
			)
			(min_thickness 0.25)
			(keepout
				(tracks not_allowed)
				(vias allowed)
				(pads allowed)
				(copperpour not_allowed)
				(footprints allowed)
			)
			(placement
				(enabled no)
				(sheetname "")
			)
			(fill
				(thermal_gap 0.5)
				(thermal_bridge_width 0.5)
				(island_removal_mode 0)
			)
			(polygon
				(pts
					(xy 3.3401 16.1544) (xy 3.3909 16.1544) (xy 3.3909 16.1036) (xy 3.3401 16.1036)
				)
			)
		)
	)
	(footprint ""
		(layer "B.Cu")
		(at 3.683 17.4498)
		(property "Reference" "R394"
			(at 0.86233 3.8862 270)
			(unlocked yes)
			(layer "B.SilkS")
			(effects
				(font
					(size 0.7874 0.5842)
					(thickness 0.127)
				)
				(justify left mirror)
			)
		)
		(property "Value" "240"
			(at 0.148158 1.3462 270)
			(unlocked yes)
			(layer "B.Fab")
			(hide yes)
			(effects
				(font
					(size 1.27 0.9652)
					(thickness 0.000001)
				)
				(justify left mirror)
			)
		)
		(property "Device Type" "REST0009"
			(at 0.148158 1.3462 270)
			(unlocked yes)
			(layer "B.Fab")
			(hide yes)
			(effects
				(font
					(size 1.27 0.9652)
					(thickness 0.000001)
				)
				(justify left mirror)
			)
		)
		(duplicate_pad_numbers_are_jumpers no)
		(fp_poly
			(pts
				(xy -0.635 1.0668) (xy -0.635 -1.0668) (xy 0.635 -1.0668) (xy 0.635 1.0668)
			)
			(stroke
				(width 0)
				(type default)
			)
			(fill no)
			(layer "B.CrtYd")
		)
		(fp_line
			(start -0.254 -0.508)
			(end -0.254 0.508)
			(stroke
				(width 0.0254)
				(type default)
			)
			(layer "B.Fab")
		)
		(fp_line
			(start -0.254 0.508)
			(end 0.254 0.508)
			(stroke
				(width 0.0254)
				(type default)
			)
			(layer "B.Fab")
		)
		(fp_line
			(start 0.254 -0.508)
			(end -0.254 -0.508)
			(stroke
				(width 0.0254)
				(type default)
			)
			(layer "B.Fab")
		)
		(fp_line
			(start 0.254 0.508)
			(end 0.254 -0.508)
			(stroke
				(width 0.0254)
				(type default)
			)
			(layer "B.Fab")
		)
		(pad "1" smd rect
			(at 0 -0.4191 180)
			(size 0.508 0.5334)
			(layers "B.Cu" "B.Mask" "B.Paste")
			(net "13N4351")
		)
		(pad "2" smd rect
			(at 0 0.4191 180)
			(size 0.508 0.5334)
			(layers "B.Cu" "B.Mask" "B.Paste")
			(net "VDD_3.3V")
		)
		(zone
			(layer "B.Cu")
			(hatch none 0.5)
			(connect_pads
				(clearance 0)
			)
			(min_thickness 0.25)
			(keepout
				(tracks not_allowed)
				(vias allowed)
				(pads allowed)
				(copperpour not_allowed)
				(footprints allowed)
			)
			(placement
				(enabled no)
				(sheetname "")
			)
			(fill
				(thermal_gap 0.5)
				(thermal_bridge_width 0.5)
				(island_removal_mode 0)
			)
			(polygon
				(pts
					(xy 3.6576 17.4244) (xy 3.6576 17.4752) (xy 3.7084 17.4752) (xy 3.7084 17.4244)
				)
			)
		)
	)
	(footprint ""
		(layer "B.Cu")
		(at 53.467 0.762 180)
		(property "Reference" "C147"
			(at 0.145212 0.8763 270)
			(unlocked yes)
			(layer "B.SilkS")
			(effects
				(font
					(size 0.7874 0.5842)
					(thickness 0.127)
				)
				(justify left mirror)
			)
		)
		(property "Value" "0.22UF"
			(at 0.091846 0.2921 90)
			(unlocked yes)
			(layer "B.Fab")
			(hide yes)
			(effects
				(font
					(size 0.7874 0.5842)
					(thickness 0.2032)
				)
				(justify left mirror)
			)
		)
		(property "Device Type" "CAPC0062"
			(at 0.091846 0.2921 90)
			(unlocked yes)
			(layer "B.Fab")
			(hide yes)
			(effects
				(font
					(size 0.7874 0.5842)
					(thickness 0.2032)
				)
				(justify left mirror)
			)
		)
		(duplicate_pad_numbers_are_jumpers no)
		(fp_poly
			(pts
				(xy -0.635 1.0668) (xy -0.635 -1.0668) (xy 0.635 -1.0668) (xy 0.635 1.0668)
			)
			(stroke
				(width 0)
				(type default)
			)
			(fill no)
			(layer "B.CrtYd")
		)
		(fp_line
			(start 0.254 0.508)
			(end 0.254 -0.508)
			(stroke
				(width 0.0254)
				(type default)
			)
			(layer "B.Fab")
		)
		(fp_line
			(start 0.254 -0.508)
			(end -0.254 -0.508)
			(stroke
				(width 0.0254)
				(type default)
			)
			(layer "B.Fab")
		)
		(fp_line
			(start -0.254 0.508)
			(end 0.254 0.508)
			(stroke
				(width 0.0254)
				(type default)
			)
			(layer "B.Fab")
		)
		(fp_line
			(start -0.254 -0.508)
			(end -0.254 0.508)
			(stroke
				(width 0.0254)
				(type default)
			)
			(layer "B.Fab")
		)
		(pad "1" smd rect
			(at 0 -0.4191)
			(size 0.508 0.5334)
			(layers "B.Cu" "B.Mask" "B.Paste")
			(net "_NFP_PCIE0_PER5_P")
		)
		(pad "2" smd rect
			(at 0 0.4191)
			(size 0.508 0.5334)
			(layers "B.Cu" "B.Mask" "B.Paste")
			(net "NFP_PCIE0_PER5_P")
		)
		(zone
			(layer "B.Cu")
			(hatch none 0.5)
			(connect_pads
				(clearance 0)
			)
			(min_thickness 0.25)
			(keepout
				(tracks not_allowed)
				(vias allowed)
				(pads allowed)
				(copperpour not_allowed)
				(footprints allowed)
			)
			(placement
				(enabled no)
				(sheetname "")
			)
			(fill
				(thermal_gap 0.5)
				(thermal_bridge_width 0.5)
				(island_removal_mode 0)
			)
			(polygon
				(pts
					(xy 53.4924 0.7874) (xy 53.4924 0.7366) (xy 53.4416 0.7366) (xy 53.4416 0.7874)
				)
			)
		)
	)
	(footprint ""
		(layer "B.Cu")
		(at 54.229 45.593)
		(property "Reference" "TP40"
			(at -0.15367 4.064 270)
			(unlocked yes)
			(layer "B.SilkS")
			(effects
				(font
					(size 0.7874 0.5842)
					(thickness 0.127)
				)
				(justify left mirror)
			)
		)
		(property "Value" "*"
			(at 0.4826 -0.14732 0)
			(unlocked yes)
			(layer "B.Fab")
			(hide yes)
			(effects
				(font
					(size 1.27 0.9652)
					(thickness 0.000001)
				)
				(justify left mirror)
			)
		)
		(property "Device Type" "TP_SMALL"
			(at 0.4826 -0.14732 0)
			(unlocked yes)
			(layer "B.Fab")
			(hide yes)
			(effects
				(font
					(size 1.27 0.9652)
					(thickness 0.000001)
				)
				(justify left mirror)
			)
		)
		(duplicate_pad_numbers_are_jumpers no)
		(fp_line
			(start -0.8636 -0.8636)
			(end 0.8636 -0.8636)
			(stroke
				(width 0.1524)
				(type default)
			)
			(layer "B.SilkS")
		)
		(fp_line
			(start -0.8636 0.8636)
			(end -0.8636 -0.8636)
			(stroke
				(width 0.1524)
				(type default)
			)
			(layer "B.SilkS")
		)
		(fp_line
			(start 0.8636 -0.8636)
			(end 0.8636 0.8636)
			(stroke
				(width 0.1524)
				(type default)
			)
			(layer "B.SilkS")
		)
		(fp_line
			(start 0.8636 0.8636)
			(end -0.8636 0.8636)
			(stroke
				(width 0.1524)
				(type default)
			)
			(layer "B.SilkS")
		)
		(fp_poly
			(pts
				(xy 0.635 -0.635) (xy 0.635 0.635) (xy -0.635 0.635) (xy -0.635 -0.635)
			)
			(stroke
				(width 0)
				(type default)
			)
			(fill no)
			(layer "B.CrtYd")
		)
		(pad "1" smd rect
			(at 0 0 180)
			(size 1.27 1.27)
			(layers "B.Cu" "B.Mask" "B.Paste")
			(net "GND")
		)
	)
	(footprint ""
		(layer "B.Cu")
		(at 81.050994 25.813004)
		(property "Reference" "V3_A-BA2"
			(at 0 0 0)
			(layer "B.SilkS")
			(hide yes)
			(effects
				(font
					(size 1.27 1.27)
				)
				(justify mirror)
			)
		)
		(property "Value" ""
			(at 0 0 0)
			(layer "B.Fab")
			(effects
				(font
					(size 1.27 1.27)
				)
				(justify mirror)
			)
		)
		(duplicate_pad_numbers_are_jumpers no)
		(pad "1" thru_hole circle
			(at 0 0 180)
			(size 0.4572 0.4572)
			(drill 0.20574)
			(layers "*.Cu" "*.Mask")
			(remove_unused_layers no)
			(net "DDR0_32A_BA2")
			(clearance 0.1143)
			(thermal_gap 0.1143)
		)
	)
	(footprint ""
		(layer "B.Cu")
		(at 0.6604 9.8552 180)
		(property "Reference" "R374"
			(at 0.4064 0.30353 0)
			(unlocked yes)
			(layer "B.SilkS")
			(effects
				(font
					(size 0.7874 0.5842)
					(thickness 0.127)
				)
				(justify left mirror)
			)
		)
		(property "Value" "4.75K"
			(at 0.148158 1.3462 90)
			(unlocked yes)
			(layer "B.Fab")
			(hide yes)
			(effects
				(font
					(size 1.27 0.9652)
					(thickness 0.000001)
				)
				(justify left mirror)
			)
		)
		(property "Device Type" "REST4024"
			(at 0.148158 1.3462 90)
			(unlocked yes)
			(layer "B.Fab")
			(hide yes)
			(effects
				(font
					(size 1.27 0.9652)
					(thickness 0.000001)
				)
				(justify left mirror)
			)
		)
		(duplicate_pad_numbers_are_jumpers no)
		(fp_poly
			(pts
				(xy -0.635 1.0668) (xy -0.635 -1.0668) (xy 0.635 -1.0668) (xy 0.635 1.0668)
			)
			(stroke
				(width 0)
				(type default)
			)
			(fill no)
			(layer "B.CrtYd")
		)
		(fp_line
			(start 0.254 0.508)
			(end 0.254 -0.508)
			(stroke
				(width 0.0254)
				(type default)
			)
			(layer "B.Fab")
		)
		(fp_line
			(start 0.254 -0.508)
			(end -0.254 -0.508)
			(stroke
				(width 0.0254)
				(type default)
			)
			(layer "B.Fab")
		)
		(fp_line
			(start -0.254 0.508)
			(end 0.254 0.508)
			(stroke
				(width 0.0254)
				(type default)
			)
			(layer "B.Fab")
		)
		(fp_line
			(start -0.254 -0.508)
			(end -0.254 0.508)
			(stroke
				(width 0.0254)
				(type default)
			)
			(layer "B.Fab")
		)
		(pad "1" smd rect
			(at 0 -0.4191)
			(size 0.508 0.5334)
			(layers "B.Cu" "B.Mask" "B.Paste")
			(net "NWK1_I2C_SCL")
		)
		(pad "2" smd rect
			(at 0 0.4191)
			(size 0.508 0.5334)
			(layers "B.Cu" "B.Mask" "B.Paste")
			(net "EXT_3.3V")
		)
		(zone
			(layer "B.Cu")
			(hatch none 0.5)
			(connect_pads
				(clearance 0)
			)
			(min_thickness 0.25)
			(keepout
				(tracks not_allowed)
				(vias allowed)
				(pads allowed)
				(copperpour not_allowed)
				(footprints allowed)
			)
			(placement
				(enabled no)
				(sheetname "")
			)
			(fill
				(thermal_gap 0.5)
				(thermal_bridge_width 0.5)
				(island_removal_mode 0)
			)
			(polygon
				(pts
					(xy 0.6858 9.8806) (xy 0.6858 9.8298) (xy 0.635 9.8298) (xy 0.635 9.8806)
				)
			)
		)
	)
	(footprint ""
		(layer "B.Cu")
		(at 44.73702 15.042007 90)
		(property "Reference" "C271"
			(at 0 0 90)
			(layer "B.SilkS")
			(hide yes)
			(effects
				(font
					(size 1.27 1.27)
				)
				(justify mirror)
			)
		)
		(property "Value" ""
			(at 0 0 90)
			(layer "B.Fab")
			(effects
				(font
					(size 1.27 1.27)
				)
				(justify mirror)
			)
		)
		(duplicate_pad_numbers_are_jumpers no)
		(fp_circle
			(center 0 0)
			(end 0 0.104648)
			(stroke
				(width 0.1016)
				(type default)
			)
			(fill no)
			(layer "B.SilkS")
		)
		(fp_poly
			(pts
				(xy 0.381 -0.889) (xy 0.381 0.889) (xy -0.381 0.889) (xy -0.381 -0.889)
			)
			(stroke
				(width 0)
				(type default)
			)
			(fill no)
			(layer "B.CrtYd")
		)
		(fp_line
			(start 0.508 -1.016)
			(end 0.254 -1.016)
			(stroke
				(width 0.0254)
				(type default)
			)
			(layer "B.Fab")
		)
		(fp_line
			(start 0.254 -1.016)
			(end -0.508 -1.016)
			(stroke
				(width 0.0254)
				(type default)
			)
			(layer "B.Fab")
		)
		(fp_line
			(start -0.508 -1.016)
			(end -0.508 1.016)
			(stroke
				(width 0.0254)
				(type default)
			)
			(layer "B.Fab")
		)
		(fp_line
			(start 0.508 1.016)
			(end 0.508 -1.016)
			(stroke
				(width 0.0254)
				(type default)
			)
			(layer "B.Fab")
		)
		(fp_line
			(start -0.508 1.016)
			(end 0.508 1.016)
			(stroke
				(width 0.0254)
				(type default)
			)
			(layer "B.Fab")
		)
		(pad "1" smd custom
			(at 0 -0.500126 270)
			(size 0.127 0.127)
			(layers "B.Cu" "B.Mask" "B.Paste")
			(net "VDD_3.3V")
			(options
				(clearance outline)
				(anchor circle)
			)
			(primitives
				(gr_poly
					(pts
						(xy -0.1778 0.254) (xy 0.1778 0.254) (xy 0.254 0.1778) (xy 0.254 -0.1778) (xy 0.1778 -0.254) (xy -0.1778 -0.254)
						(xy -0.254 -0.1778) (xy -0.254 0.1778)
					)
					(width 0)
					(fill yes)
				)
			)
		)
		(pad "2" smd custom
			(at 0 0.500126 270)
			(size 0.127 0.127)
			(layers "B.Cu" "B.Mask" "B.Paste")
			(net "GND")
			(options
				(clearance outline)
				(anchor circle)
			)
			(primitives
				(gr_poly
					(pts
						(xy -0.1778 0.254) (xy 0.1778 0.254) (xy 0.254 0.1778) (xy 0.254 -0.1778) (xy 0.1778 -0.254) (xy -0.1778 -0.254)
						(xy -0.254 -0.1778) (xy -0.254 0.1778)
					)
					(width 0)
					(fill yes)
				)
			)
		)
	)
	(footprint ""
		(layer "B.Cu")
		(at 52.737004 5.042027 90)
		(property "Reference" "C41"
			(at 1.994027 -1.074674 270)
			(unlocked yes)
			(layer "B.SilkS")
			(effects
				(font
					(size 0.7874 0.5842)
					(thickness 0.127)
				)
				(justify mirror)
			)
		)
		(property "Value" ""
			(at 0 0 90)
			(layer "B.Fab")
			(effects
				(font
					(size 1.27 1.27)
				)
				(justify mirror)
			)
		)
		(duplicate_pad_numbers_are_jumpers no)
		(fp_circle
			(center 0 0)
			(end 0 0.104648)
			(stroke
				(width 0.1016)
				(type default)
			)
			(fill no)
			(layer "B.SilkS")
		)
		(fp_poly
			(pts
				(xy 0.381 -0.889) (xy 0.381 0.889) (xy -0.381 0.889) (xy -0.381 -0.889)
			)
			(stroke
				(width 0)
				(type default)
			)
			(fill no)
			(layer "B.CrtYd")
		)
		(fp_line
			(start 0.508 -1.016)
			(end 0.254 -1.016)
			(stroke
				(width 0.0254)
				(type default)
			)
			(layer "B.Fab")
		)
		(fp_line
			(start 0.254 -1.016)
			(end -0.508 -1.016)
			(stroke
				(width 0.0254)
				(type default)
			)
			(layer "B.Fab")
		)
		(fp_line
			(start -0.508 -1.016)
			(end -0.508 1.016)
			(stroke
				(width 0.0254)
				(type default)
			)
			(layer "B.Fab")
		)
		(fp_line
			(start 0.508 1.016)
			(end 0.508 -1.016)
			(stroke
				(width 0.0254)
				(type default)
			)
			(layer "B.Fab")
		)
		(fp_line
			(start -0.508 1.016)
			(end 0.508 1.016)
			(stroke
				(width 0.0254)
				(type default)
			)
			(layer "B.Fab")
		)
		(pad "1" smd custom
			(at 0 -0.500126 270)
			(size 0.127 0.127)
			(layers "B.Cu" "B.Mask" "B.Paste")
			(net "VDDAH_SERDES")
			(options
				(clearance outline)
				(anchor circle)
			)
			(primitives
				(gr_poly
					(pts
						(xy -0.1778 0.254) (xy 0.1778 0.254) (xy 0.254 0.1778) (xy 0.254 -0.1778) (xy 0.1778 -0.254) (xy -0.1778 -0.254)
						(xy -0.254 -0.1778) (xy -0.254 0.1778)
					)
					(width 0)
					(fill yes)
				)
			)
		)
		(pad "2" smd custom
			(at 0 0.500126 270)
			(size 0.127 0.127)
			(layers "B.Cu" "B.Mask" "B.Paste")
			(net "GND")
			(options
				(clearance outline)
				(anchor circle)
			)
			(primitives
				(gr_poly
					(pts
						(xy -0.1778 0.254) (xy 0.1778 0.254) (xy 0.254 0.1778) (xy 0.254 -0.1778) (xy 0.1778 -0.254) (xy -0.1778 -0.254)
						(xy -0.254 -0.1778) (xy -0.254 0.1778)
					)
					(width 0)
					(fill yes)
				)
			)
		)
	)
	(footprint ""
		(layer "B.Cu")
		(at 28.829 22.352 180)
		(property "Reference" "R53"
			(at 0 0 0)
			(layer "B.SilkS")
			(hide yes)
			(effects
				(font
					(size 1.27 1.27)
				)
				(justify mirror)
			)
		)
		(property "Value" "4.75K"
			(at 0.148158 1.3462 90)
			(unlocked yes)
			(layer "B.Fab")
			(hide yes)
			(effects
				(font
					(size 1.27 0.9652)
					(thickness 0.000001)
				)
				(justify left mirror)
			)
		)
		(property "Device Type" "REST4024"
			(at 0.148158 1.3462 90)
			(unlocked yes)
			(layer "B.Fab")
			(hide yes)
			(effects
				(font
					(size 1.27 0.9652)
					(thickness 0.000001)
				)
				(justify left mirror)
			)
		)
		(duplicate_pad_numbers_are_jumpers no)
		(fp_poly
			(pts
				(xy -0.635 1.0668) (xy -0.635 -1.0668) (xy 0.635 -1.0668) (xy 0.635 1.0668)
			)
			(stroke
				(width 0)
				(type default)
			)
			(fill no)
			(layer "B.CrtYd")
		)
		(fp_line
			(start 0.254 0.508)
			(end 0.254 -0.508)
			(stroke
				(width 0.0254)
				(type default)
			)
			(layer "B.Fab")
		)
		(fp_line
			(start 0.254 -0.508)
			(end -0.254 -0.508)
			(stroke
				(width 0.0254)
				(type default)
			)
			(layer "B.Fab")
		)
		(fp_line
			(start -0.254 0.508)
			(end 0.254 0.508)
			(stroke
				(width 0.0254)
				(type default)
			)
			(layer "B.Fab")
		)
		(fp_line
			(start -0.254 -0.508)
			(end -0.254 0.508)
			(stroke
				(width 0.0254)
				(type default)
			)
			(layer "B.Fab")
		)
		(pad "1" smd rect
			(at 0 -0.4191)
			(size 0.508 0.5334)
			(layers "B.Cu" "B.Mask" "B.Paste")
			(net "EXT_3.3V")
		)
		(pad "2" smd rect
			(at 0 0.4191)
			(size 0.508 0.5334)
			(layers "B.Cu" "B.Mask" "B.Paste")
			(net "CPLD_VERSION_2")
		)
		(zone
			(layer "B.Cu")
			(hatch none 0.5)
			(connect_pads
				(clearance 0)
			)
			(min_thickness 0.25)
			(keepout
				(tracks not_allowed)
				(vias allowed)
				(pads allowed)
				(copperpour not_allowed)
				(footprints allowed)
			)
			(placement
				(enabled no)
				(sheetname "")
			)
			(fill
				(thermal_gap 0.5)
				(thermal_bridge_width 0.5)
				(island_removal_mode 0)
			)
			(polygon
				(pts
					(xy 28.8544 22.3774) (xy 28.8544 22.3266) (xy 28.8036 22.3266) (xy 28.8036 22.3774)
				)
			)
		)
	)
	(footprint ""
		(layer "B.Cu")
		(at 41.275 18.558002 -90)
		(property "Reference" "R203"
			(at 0 0 90)
			(layer "B.SilkS")
			(hide yes)
			(effects
				(font
					(size 1.27 1.27)
				)
				(justify mirror)
			)
		)
		(property "Value" "39.0"
			(at 0.148158 1.3462 180)
			(unlocked yes)
			(layer "B.Fab")
			(hide yes)
			(effects
				(font
					(size 1.27 0.9652)
					(thickness 0.000001)
				)
				(justify left mirror)
			)
		)
		(property "Device Type" "REST0108"
			(at 0.148158 1.3462 180)
			(unlocked yes)
			(layer "B.Fab")
			(hide yes)
			(effects
				(font
					(size 1.27 0.9652)
					(thickness 0.000001)
				)
				(justify left mirror)
			)
		)
		(duplicate_pad_numbers_are_jumpers no)
		(fp_poly
			(pts
				(xy -0.635 1.0668) (xy -0.635 -1.0668) (xy 0.635 -1.0668) (xy 0.635 1.0668)
			)
			(stroke
				(width 0)
				(type default)
			)
			(fill no)
			(layer "B.CrtYd")
		)
		(fp_line
			(start -0.254 0.508)
			(end 0.254 0.508)
			(stroke
				(width 0.0254)
				(type default)
			)
			(layer "B.Fab")
		)
		(fp_line
			(start 0.254 0.508)
			(end 0.254 -0.508)
			(stroke
				(width 0.0254)
				(type default)
			)
			(layer "B.Fab")
		)
		(fp_line
			(start -0.254 -0.508)
			(end -0.254 0.508)
			(stroke
				(width 0.0254)
				(type default)
			)
			(layer "B.Fab")
		)
		(fp_line
			(start 0.254 -0.508)
			(end -0.254 -0.508)
			(stroke
				(width 0.0254)
				(type default)
			)
			(layer "B.Fab")
		)
		(pad "1" smd rect
			(at 0 -0.4191 90)
			(size 0.508 0.5334)
			(layers "B.Cu" "B.Mask" "B.Paste")
			(net "_NFP_SPI2_MOSI")
		)
		(pad "2" smd rect
			(at 0 0.4191 90)
			(size 0.508 0.5334)
			(layers "B.Cu" "B.Mask" "B.Paste")
			(net "NFP_SPI2_MOSI")
		)
		(zone
			(layer "B.Cu")
			(hatch none 0.5)
			(connect_pads
				(clearance 0)
			)
			(min_thickness 0.25)
			(keepout
				(tracks not_allowed)
				(vias allowed)
				(pads allowed)
				(copperpour not_allowed)
				(footprints allowed)
			)
			(placement
				(enabled no)
				(sheetname "")
			)
			(fill
				(thermal_gap 0.5)
				(thermal_bridge_width 0.5)
				(island_removal_mode 0)
			)
			(polygon
				(pts
					(xy 41.3004 18.532602) (xy 41.2496 18.532602) (xy 41.2496 18.583402) (xy 41.3004 18.583402)
				)
			)
		)
	)
	(footprint ""
		(layer "B.Cu")
		(at 73.025 40.386 90)
		(property "Reference" "C179"
			(at -1.27 1.87833 270)
			(unlocked yes)
			(layer "B.SilkS")
			(effects
				(font
					(size 0.7874 0.5842)
					(thickness 0.127)
				)
				(justify left mirror)
			)
		)
		(property "Value" ""
			(at 0 0 90)
			(layer "B.Fab")
			(effects
				(font
					(size 1.27 1.27)
				)
				(justify mirror)
			)
		)
		(duplicate_pad_numbers_are_jumpers no)
		(fp_circle
			(center 0 0)
			(end 0 0.508)
			(stroke
				(width 0.2032)
				(type default)
			)
			(fill no)
			(layer "B.SilkS")
		)
		(fp_poly
			(pts
				(xy 2.286 1.581404) (xy 2.286 -1.778) (xy -2.286 -1.778) (xy -2.286 1.778) (xy 1.474165 1.778) (xy 1.656004 1.596161)
				(xy 2.271243 1.596161)
			)
			(stroke
				(width 0)
				(type default)
			)
			(fill no)
			(layer "B.CrtYd")
		)
		(fp_line
			(start 1.524 -1.27)
			(end -1.524 -1.27)
			(stroke
				(width 0.0254)
				(type default)
			)
			(layer "B.Fab")
		)
		(fp_line
			(start -1.524 -1.27)
			(end -1.524 1.27)
			(stroke
				(width 0.0254)
				(type default)
			)
			(layer "B.Fab")
		)
		(fp_line
			(start 1.524 1.27)
			(end 1.524 -1.27)
			(stroke
				(width 0.0254)
				(type default)
			)
			(layer "B.Fab")
		)
		(fp_line
			(start -1.524 1.27)
			(end 1.524 1.27)
			(stroke
				(width 0.0254)
				(type default)
			)
			(layer "B.Fab")
		)
		(pad "1" smd rect
			(at 1.4224 0 180)
			(size 2.7432 1.3716)
			(layers "B.Cu" "B.Mask" "B.Paste")
			(net "EXT_12.0V")
		)
		(pad "2" smd rect
			(at -1.4224 0 180)
			(size 2.7432 1.3716)
			(layers "B.Cu" "B.Mask" "B.Paste")
			(net "GND")
		)
	)
	(footprint ""
		(layer "B.Cu")
		(at 82.65099 29.812996)
		(property "Reference" "V3_A-A01"
			(at 0 0 0)
			(layer "B.SilkS")
			(hide yes)
			(effects
				(font
					(size 1.27 1.27)
				)
				(justify mirror)
			)
		)
		(property "Value" ""
			(at 0 0 0)
			(layer "B.Fab")
			(effects
				(font
					(size 1.27 1.27)
				)
				(justify mirror)
			)
		)
		(duplicate_pad_numbers_are_jumpers no)
		(pad "1" thru_hole circle
			(at 0 0 180)
			(size 0.4572 0.4572)
			(drill 0.20574)
			(layers "*.Cu" "*.Mask")
			(remove_unused_layers no)
			(net "DDR0_32A_A1")
			(clearance 0.1143)
			(thermal_gap 0.1143)
		)
	)
	(footprint ""
		(layer "B.Cu")
		(at 38.711632 17.042003 180)
		(property "Reference" "R282"
			(at 0 0 0)
			(layer "B.SilkS")
			(hide yes)
			(effects
				(font
					(size 1.27 1.27)
				)
				(justify mirror)
			)
		)
		(property "Value" "100"
			(at 0.148158 1.3462 90)
			(unlocked yes)
			(layer "B.Fab")
			(hide yes)
			(effects
				(font
					(size 1.27 0.9652)
					(thickness 0.000001)
				)
				(justify left mirror)
			)
		)
		(property "Device Type" "REST4030"
			(at 0.148158 1.3462 90)
			(unlocked yes)
			(layer "B.Fab")
			(hide yes)
			(effects
				(font
					(size 1.27 0.9652)
					(thickness 0.000001)
				)
				(justify left mirror)
			)
		)
		(duplicate_pad_numbers_are_jumpers no)
		(fp_poly
			(pts
				(xy -0.635 1.0668) (xy -0.635 -1.0668) (xy 0.635 -1.0668) (xy 0.635 1.0668)
			)
			(stroke
				(width 0)
				(type default)
			)
			(fill no)
			(layer "B.CrtYd")
		)
		(fp_line
			(start 0.254 0.508)
			(end 0.254 -0.508)
			(stroke
				(width 0.0254)
				(type default)
			)
			(layer "B.Fab")
		)
		(fp_line
			(start 0.254 -0.508)
			(end -0.254 -0.508)
			(stroke
				(width 0.0254)
				(type default)
			)
			(layer "B.Fab")
		)
		(fp_line
			(start -0.254 0.508)
			(end 0.254 0.508)
			(stroke
				(width 0.0254)
				(type default)
			)
			(layer "B.Fab")
		)
		(fp_line
			(start -0.254 -0.508)
			(end -0.254 0.508)
			(stroke
				(width 0.0254)
				(type default)
			)
			(layer "B.Fab")
		)
		(pad "1" smd rect
			(at 0 -0.4191)
			(size 0.508 0.5334)
			(layers "B.Cu" "B.Mask" "B.Paste")
			(net "_NFP_ARM_SPI_FLASH_SEL")
		)
		(pad "2" smd rect
			(at 0 0.4191)
			(size 0.508 0.5334)
			(layers "B.Cu" "B.Mask" "B.Paste")
			(net "NFP_ARM_SPI_FLASH_SEL")
		)
		(zone
			(layer "B.Cu")
			(hatch none 0.5)
			(connect_pads
				(clearance 0)
			)
			(min_thickness 0.25)
			(keepout
				(tracks not_allowed)
				(vias allowed)
				(pads allowed)
				(copperpour not_allowed)
				(footprints allowed)
			)
			(placement
				(enabled no)
				(sheetname "")
			)
			(fill
				(thermal_gap 0.5)
				(thermal_bridge_width 0.5)
				(island_removal_mode 0)
			)
			(polygon
				(pts
					(xy 38.737032 17.067403) (xy 38.737032 17.016603) (xy 38.686232 17.016603) (xy 38.686232 17.067403)
				)
			)
		)
	)
	(footprint ""
		(layer "B.Cu")
		(at 49.00168 35.433 90)
		(property "Reference" "C33"
			(at -1.29667 0.6731 0)
			(unlocked yes)
			(layer "B.SilkS")
			(effects
				(font
					(size 0.7874 0.5842)
					(thickness 0.127)
				)
				(justify left mirror)
			)
		)
		(property "Value" "0.22UF"
			(at 0.148158 1.7526 0)
			(unlocked yes)
			(layer "B.Fab")
			(hide yes)
			(effects
				(font
					(size 1.27 0.9652)
					(thickness 0.000001)
				)
				(justify left mirror)
			)
		)
		(property "Device Type" "CAPC0022"
			(at 0.148158 1.7526 0)
			(unlocked yes)
			(layer "B.Fab")
			(hide yes)
			(effects
				(font
					(size 1.27 0.9652)
					(thickness 0.000001)
				)
				(justify left mirror)
			)
		)
		(duplicate_pad_numbers_are_jumpers no)
		(fp_circle
			(center 0 0)
			(end 0 0.127)
			(stroke
				(width 0.2032)
				(type default)
			)
			(fill no)
			(layer "B.SilkS")
		)
		(fp_poly
			(pts
				(xy -0.7874 -1.6637) (xy 0.7874 -1.6637) (xy 0.7874 1.6637) (xy -0.7874 1.6637)
			)
			(stroke
				(width 0)
				(type default)
			)
			(fill no)
			(layer "B.CrtYd")
		)
		(fp_line
			(start 0.4064 -0.7874)
			(end -0.4064 -0.7874)
			(stroke
				(width 0.0254)
				(type default)
			)
			(layer "B.Fab")
		)
		(fp_line
			(start -0.4064 -0.7874)
			(end -0.4064 0.8128)
			(stroke
				(width 0.0254)
				(type default)
			)
			(layer "B.Fab")
		)
		(fp_line
			(start 0.4064 0.8128)
			(end 0.4064 -0.7874)
			(stroke
				(width 0.0254)
				(type default)
			)
			(layer "B.Fab")
		)
		(fp_line
			(start -0.4064 0.8128)
			(end 0.4064 0.8128)
			(stroke
				(width 0.0254)
				(type default)
			)
			(layer "B.Fab")
		)
		(pad "1" smd rect
			(at 0 -0.8001 270)
			(size 0.8636 0.9652)
			(layers "B.Cu" "B.Mask" "B.Paste")
			(net "10N2232")
		)
		(pad "2" smd rect
			(at 0 0.8001 270)
			(size 0.8636 0.9652)
			(layers "B.Cu" "B.Mask" "B.Paste")
			(net "10N2233")
		)
		(zone
			(layer "B.Cu")
			(hatch none 0.5)
			(connect_pads
				(clearance 0)
			)
			(min_thickness 0.25)
			(keepout
				(tracks not_allowed)
				(vias allowed)
				(pads allowed)
				(copperpour not_allowed)
				(footprints allowed)
			)
			(placement
				(enabled no)
				(sheetname "")
			)
			(fill
				(thermal_gap 0.5)
				(thermal_bridge_width 0.5)
				(island_removal_mode 0)
			)
			(polygon
				(pts
					(xy 48.74768 35.3695) (xy 48.74768 35.4965) (xy 49.25568 35.4965) (xy 49.25568 35.3695)
				)
			)
		)
	)
	(footprint ""
		(layer "B.Cu")
		(at 41.737026 12.042013 90)
		(property "Reference" "R16"
			(at 0 0 90)
			(layer "B.SilkS")
			(hide yes)
			(effects
				(font
					(size 1.27 1.27)
				)
				(justify mirror)
			)
		)
		(property "Value" ""
			(at 0 0 90)
			(layer "B.Fab")
			(effects
				(font
					(size 1.27 1.27)
				)
				(justify mirror)
			)
		)
		(duplicate_pad_numbers_are_jumpers no)
		(fp_circle
			(center 0 0)
			(end 0 0.104648)
			(stroke
				(width 0.1016)
				(type default)
			)
			(fill no)
			(layer "B.SilkS")
		)
		(fp_poly
			(pts
				(xy 0.381 -0.889) (xy 0.381 0.889) (xy -0.381 0.889) (xy -0.381 -0.889)
			)
			(stroke
				(width 0)
				(type default)
			)
			(fill no)
			(layer "B.CrtYd")
		)
		(fp_line
			(start 0.508 -1.016)
			(end 0.254 -1.016)
			(stroke
				(width 0.0254)
				(type default)
			)
			(layer "B.Fab")
		)
		(fp_line
			(start 0.254 -1.016)
			(end -0.508 -1.016)
			(stroke
				(width 0.0254)
				(type default)
			)
			(layer "B.Fab")
		)
		(fp_line
			(start -0.508 -1.016)
			(end -0.508 1.016)
			(stroke
				(width 0.0254)
				(type default)
			)
			(layer "B.Fab")
		)
		(fp_line
			(start 0.508 1.016)
			(end 0.508 -1.016)
			(stroke
				(width 0.0254)
				(type default)
			)
			(layer "B.Fab")
		)
		(fp_line
			(start -0.508 1.016)
			(end 0.508 1.016)
			(stroke
				(width 0.0254)
				(type default)
			)
			(layer "B.Fab")
		)
		(pad "1" smd custom
			(at 0 -0.500126 270)
			(size 0.127 0.127)
			(layers "B.Cu" "B.Mask" "B.Paste")
			(net "NFP_FAIL_SAFE_BOOT_L")
			(options
				(clearance outline)
				(anchor circle)
			)
			(primitives
				(gr_poly
					(pts
						(xy -0.1778 0.254) (xy 0.1778 0.254) (xy 0.254 0.1778) (xy 0.254 -0.1778) (xy 0.1778 -0.254) (xy -0.1778 -0.254)
						(xy -0.254 -0.1778) (xy -0.254 0.1778)
					)
					(width 0)
					(fill yes)
				)
			)
		)
		(pad "2" smd custom
			(at 0 0.500126 270)
			(size 0.127 0.127)
			(layers "B.Cu" "B.Mask" "B.Paste")
			(net "GND")
			(options
				(clearance outline)
				(anchor circle)
			)
			(primitives
				(gr_poly
					(pts
						(xy -0.1778 0.254) (xy 0.1778 0.254) (xy 0.254 0.1778) (xy 0.254 -0.1778) (xy 0.1778 -0.254) (xy -0.1778 -0.254)
						(xy -0.254 -0.1778) (xy -0.254 0.1778)
					)
					(width 0)
					(fill yes)
				)
			)
		)
	)
	(footprint ""
		(layer "B.Cu")
		(at 40.237029 26.542238)
		(property "Reference" "R406"
			(at 0 0 0)
			(layer "B.SilkS")
			(hide yes)
			(effects
				(font
					(size 1.27 1.27)
				)
				(justify mirror)
			)
		)
		(property "Value" ""
			(at 0 0 0)
			(layer "B.Fab")
			(effects
				(font
					(size 1.27 1.27)
				)
				(justify mirror)
			)
		)
		(duplicate_pad_numbers_are_jumpers no)
		(fp_circle
			(center 0 0)
			(end 0.104648 0)
			(stroke
				(width 0.1016)
				(type default)
			)
			(fill no)
			(layer "B.SilkS")
		)
		(fp_poly
			(pts
				(xy 0.381 -0.889) (xy 0.381 0.889) (xy -0.381 0.889) (xy -0.381 -0.889)
			)
			(stroke
				(width 0)
				(type default)
			)
			(fill no)
			(layer "B.CrtYd")
		)
		(fp_line
			(start -0.508 -1.016)
			(end -0.508 1.016)
			(stroke
				(width 0.0254)
				(type default)
			)
			(layer "B.Fab")
		)
		(fp_line
			(start -0.508 1.016)
			(end 0.508 1.016)
			(stroke
				(width 0.0254)
				(type default)
			)
			(layer "B.Fab")
		)
		(fp_line
			(start 0.254 -1.016)
			(end -0.508 -1.016)
			(stroke
				(width 0.0254)
				(type default)
			)
			(layer "B.Fab")
		)
		(fp_line
			(start 0.508 -1.016)
			(end 0.254 -1.016)
			(stroke
				(width 0.0254)
				(type default)
			)
			(layer "B.Fab")
		)
		(fp_line
			(start 0.508 1.016)
			(end 0.508 -1.016)
			(stroke
				(width 0.0254)
				(type default)
			)
			(layer "B.Fab")
		)
		(pad "1" smd custom
			(at 0 -0.500126 180)
			(size 0.127 0.127)
			(layers "B.Cu" "B.Mask" "B.Paste")
			(net "VDD_3.3V")
			(options
				(clearance outline)
				(anchor circle)
			)
			(primitives
				(gr_poly
					(pts
						(xy -0.1778 0.254) (xy 0.1778 0.254) (xy 0.254 0.1778) (xy 0.254 -0.1778) (xy 0.1778 -0.254) (xy -0.1778 -0.254)
						(xy -0.254 -0.1778) (xy -0.254 0.1778)
					)
					(width 0)
					(fill yes)
				)
			)
		)
		(pad "2" smd custom
			(at 0 0.500126 180)
			(size 0.127 0.127)
			(layers "B.Cu" "B.Mask" "B.Paste")
			(net "NFP_JTAG_ARM_TRST_L")
			(options
				(clearance outline)
				(anchor circle)
			)
			(primitives
				(gr_poly
					(pts
						(xy -0.1778 0.254) (xy 0.1778 0.254) (xy 0.254 0.1778) (xy 0.254 -0.1778) (xy 0.1778 -0.254) (xy -0.1778 -0.254)
						(xy -0.254 -0.1778) (xy -0.254 0.1778)
					)
					(width 0)
					(fill yes)
				)
			)
		)
	)
	(footprint ""
		(layer "B.Cu")
		(at 81.850992 25.813004)
		(property "Reference" "V3_A-A00"
			(at 0 0 0)
			(layer "B.SilkS")
			(hide yes)
			(effects
				(font
					(size 1.27 1.27)
				)
				(justify mirror)
			)
		)
		(property "Value" ""
			(at 0 0 0)
			(layer "B.Fab")
			(effects
				(font
					(size 1.27 1.27)
				)
				(justify mirror)
			)
		)
		(duplicate_pad_numbers_are_jumpers no)
		(pad "1" thru_hole circle
			(at 0 0 180)
			(size 0.4572 0.4572)
			(drill 0.20574)
			(layers "*.Cu" "*.Mask")
			(remove_unused_layers no)
			(net "DDR0_32A_A0")
			(clearance 0.1143)
			(thermal_gap 0.1143)
		)
	)
	(footprint ""
		(layer "B.Cu")
		(at 45.237019 9.542018)
		(property "Reference" "R322"
			(at 0 0 0)
			(layer "B.SilkS")
			(hide yes)
			(effects
				(font
					(size 1.27 1.27)
				)
				(justify mirror)
			)
		)
		(property "Value" ""
			(at 0 0 0)
			(layer "B.Fab")
			(effects
				(font
					(size 1.27 1.27)
				)
				(justify mirror)
			)
		)
		(duplicate_pad_numbers_are_jumpers no)
		(fp_circle
			(center 0 0)
			(end 0.104648 0)
			(stroke
				(width 0.1016)
				(type default)
			)
			(fill no)
			(layer "B.SilkS")
		)
		(fp_poly
			(pts
				(xy 0.381 -0.889) (xy 0.381 0.889) (xy -0.381 0.889) (xy -0.381 -0.889)
			)
			(stroke
				(width 0)
				(type default)
			)
			(fill no)
			(layer "B.CrtYd")
		)
		(fp_line
			(start -0.508 -1.016)
			(end -0.508 1.016)
			(stroke
				(width 0.0254)
				(type default)
			)
			(layer "B.Fab")
		)
		(fp_line
			(start -0.508 1.016)
			(end 0.508 1.016)
			(stroke
				(width 0.0254)
				(type default)
			)
			(layer "B.Fab")
		)
		(fp_line
			(start 0.254 -1.016)
			(end -0.508 -1.016)
			(stroke
				(width 0.0254)
				(type default)
			)
			(layer "B.Fab")
		)
		(fp_line
			(start 0.508 -1.016)
			(end 0.254 -1.016)
			(stroke
				(width 0.0254)
				(type default)
			)
			(layer "B.Fab")
		)
		(fp_line
			(start 0.508 1.016)
			(end 0.508 -1.016)
			(stroke
				(width 0.0254)
				(type default)
			)
			(layer "B.Fab")
		)
		(pad "1" smd custom
			(at 0 -0.500126 180)
			(size 0.127 0.127)
			(layers "B.Cu" "B.Mask" "B.Paste")
			(net "GND")
			(options
				(clearance outline)
				(anchor circle)
			)
			(primitives
				(gr_poly
					(pts
						(xy -0.1778 0.254) (xy 0.1778 0.254) (xy 0.254 0.1778) (xy 0.254 -0.1778) (xy 0.1778 -0.254) (xy -0.1778 -0.254)
						(xy -0.254 -0.1778) (xy -0.254 0.1778)
					)
					(width 0)
					(fill yes)
				)
			)
		)
		(pad "2" smd custom
			(at 0 0.500126 180)
			(size 0.127 0.127)
			(layers "B.Cu" "B.Mask" "B.Paste")
			(net "NFP_SERDES012_SYSCLK_IN_N")
			(options
				(clearance outline)
				(anchor circle)
			)
			(primitives
				(gr_poly
					(pts
						(xy -0.1778 0.254) (xy 0.1778 0.254) (xy 0.254 0.1778) (xy 0.254 -0.1778) (xy 0.1778 -0.254) (xy -0.1778 -0.254)
						(xy -0.254 -0.1778) (xy -0.254 0.1778)
					)
					(width 0)
					(fill yes)
				)
			)
		)
	)
	(footprint ""
		(layer "B.Cu")
		(at 47.736887 13.042138 -90)
		(property "Reference" "C172"
			(at 0 0 90)
			(layer "B.SilkS")
			(hide yes)
			(effects
				(font
					(size 1.27 1.27)
				)
				(justify mirror)
			)
		)
		(property "Value" ""
			(at 0 0 90)
			(layer "B.Fab")
			(effects
				(font
					(size 1.27 1.27)
				)
				(justify mirror)
			)
		)
		(duplicate_pad_numbers_are_jumpers no)
		(fp_circle
			(center 0 0)
			(end 0 -0.104648)
			(stroke
				(width 0.1016)
				(type default)
			)
			(fill no)
			(layer "B.SilkS")
		)
		(fp_poly
			(pts
				(xy 0.381 -0.889) (xy 0.381 0.889) (xy -0.381 0.889) (xy -0.381 -0.889)
			)
			(stroke
				(width 0)
				(type default)
			)
			(fill no)
			(layer "B.CrtYd")
		)
		(fp_line
			(start -0.508 1.016)
			(end 0.508 1.016)
			(stroke
				(width 0.0254)
				(type default)
			)
			(layer "B.Fab")
		)
		(fp_line
			(start 0.508 1.016)
			(end 0.508 -1.016)
			(stroke
				(width 0.0254)
				(type default)
			)
			(layer "B.Fab")
		)
		(fp_line
			(start -0.508 -1.016)
			(end -0.508 1.016)
			(stroke
				(width 0.0254)
				(type default)
			)
			(layer "B.Fab")
		)
		(fp_line
			(start 0.254 -1.016)
			(end -0.508 -1.016)
			(stroke
				(width 0.0254)
				(type default)
			)
			(layer "B.Fab")
		)
		(fp_line
			(start 0.508 -1.016)
			(end 0.254 -1.016)
			(stroke
				(width 0.0254)
				(type default)
			)
			(layer "B.Fab")
		)
		(pad "1" smd custom
			(at 0 -0.500126 90)
			(size 0.127 0.127)
			(layers "B.Cu" "B.Mask" "B.Paste")
			(net "VDDA_SERDES")
			(options
				(clearance outline)
				(anchor circle)
			)
			(primitives
				(gr_poly
					(pts
						(xy -0.1778 0.254) (xy 0.1778 0.254) (xy 0.254 0.1778) (xy 0.254 -0.1778) (xy 0.1778 -0.254) (xy -0.1778 -0.254)
						(xy -0.254 -0.1778) (xy -0.254 0.1778)
					)
					(width 0)
					(fill yes)
				)
			)
		)
		(pad "2" smd custom
			(at 0 0.500126 90)
			(size 0.127 0.127)
			(layers "B.Cu" "B.Mask" "B.Paste")
			(net "GND")
			(options
				(clearance outline)
				(anchor circle)
			)
			(primitives
				(gr_poly
					(pts
						(xy -0.1778 0.254) (xy 0.1778 0.254) (xy 0.254 0.1778) (xy 0.254 -0.1778) (xy 0.1778 -0.254) (xy -0.1778 -0.254)
						(xy -0.254 -0.1778) (xy -0.254 0.1778)
					)
					(width 0)
					(fill yes)
				)
			)
		)
	)
	(footprint ""
		(layer "B.Cu")
		(at 54.737 15.748)
		(property "Reference" "C5"
			(at 0.635 2.05867 0)
			(unlocked yes)
			(layer "B.SilkS")
			(effects
				(font
					(size 0.7874 0.5842)
					(thickness 0.127)
				)
				(justify left mirror)
			)
		)
		(property "Value" "22UF"
			(at 0.148158 1.7526 270)
			(unlocked yes)
			(layer "B.Fab")
			(hide yes)
			(effects
				(font
					(size 1.27 0.9652)
					(thickness 0.000001)
				)
				(justify left mirror)
			)
		)
		(property "Device Type" "CAPC0063"
			(at 0.148158 1.7526 270)
			(unlocked yes)
			(layer "B.Fab")
			(hide yes)
			(effects
				(font
					(size 1.27 0.9652)
					(thickness 0.000001)
				)
				(justify left mirror)
			)
		)
		(duplicate_pad_numbers_are_jumpers no)
		(fp_circle
			(center 0 0)
			(end 0.127 0)
			(stroke
				(width 0.2032)
				(type default)
			)
			(fill no)
			(layer "B.SilkS")
		)
		(fp_poly
			(pts
				(xy -0.7874 -1.6637) (xy 0.7874 -1.6637) (xy 0.7874 1.6637) (xy -0.7874 1.6637)
			)
			(stroke
				(width 0)
				(type default)
			)
			(fill no)
			(layer "B.CrtYd")
		)
		(fp_line
			(start -0.4064 -0.7874)
			(end -0.4064 0.8128)
			(stroke
				(width 0.0254)
				(type default)
			)
			(layer "B.Fab")
		)
		(fp_line
			(start -0.4064 0.8128)
			(end 0.4064 0.8128)
			(stroke
				(width 0.0254)
				(type default)
			)
			(layer "B.Fab")
		)
		(fp_line
			(start 0.4064 -0.7874)
			(end -0.4064 -0.7874)
			(stroke
				(width 0.0254)
				(type default)
			)
			(layer "B.Fab")
		)
		(fp_line
			(start 0.4064 0.8128)
			(end 0.4064 -0.7874)
			(stroke
				(width 0.0254)
				(type default)
			)
			(layer "B.Fab")
		)
		(pad "1" smd rect
			(at 0 -0.8001 180)
			(size 0.8636 0.9652)
			(layers "B.Cu" "B.Mask" "B.Paste")
			(net "VDD_CORE")
		)
		(pad "2" smd rect
			(at 0 0.8001 180)
			(size 0.8636 0.9652)
			(layers "B.Cu" "B.Mask" "B.Paste")
			(net "GND")
		)
		(zone
			(layer "B.Cu")
			(hatch none 0.5)
			(connect_pads
				(clearance 0)
			)
			(min_thickness 0.25)
			(keepout
				(tracks not_allowed)
				(vias allowed)
				(pads allowed)
				(copperpour not_allowed)
				(footprints allowed)
			)
			(placement
				(enabled no)
				(sheetname "")
			)
			(fill
				(thermal_gap 0.5)
				(thermal_bridge_width 0.5)
				(island_removal_mode 0)
			)
			(polygon
				(pts
					(xy 54.8005 15.494) (xy 54.6735 15.494) (xy 54.6735 16.002) (xy 54.8005 16.002)
				)
			)
		)
	)
	(footprint ""
		(layer "B.Cu")
		(at 55.88 45.593 90)
		(property "Reference" "TP37"
			(at -3.937 -0.66167 270)
			(unlocked yes)
			(layer "B.SilkS")
			(effects
				(font
					(size 0.7874 0.5842)
					(thickness 0.127)
				)
				(justify left mirror)
			)
		)
		(property "Value" "*"
			(at 0.4826 -0.14732 90)
			(unlocked yes)
			(layer "B.Fab")
			(hide yes)
			(effects
				(font
					(size 1.27 0.9652)
					(thickness 0.000001)
				)
				(justify left mirror)
			)
		)
		(property "Device Type" "TP_SMALL"
			(at 0.4826 -0.14732 90)
			(unlocked yes)
			(layer "B.Fab")
			(hide yes)
			(effects
				(font
					(size 1.27 0.9652)
					(thickness 0.000001)
				)
				(justify left mirror)
			)
		)
		(duplicate_pad_numbers_are_jumpers no)
		(fp_line
			(start 0.8636 -0.8636)
			(end 0.8636 0.8636)
			(stroke
				(width 0.1524)
				(type default)
			)
			(layer "B.SilkS")
		)
		(fp_line
			(start -0.8636 -0.8636)
			(end 0.8636 -0.8636)
			(stroke
				(width 0.1524)
				(type default)
			)
			(layer "B.SilkS")
		)
		(fp_line
			(start 0.8636 0.8636)
			(end -0.8636 0.8636)
			(stroke
				(width 0.1524)
				(type default)
			)
			(layer "B.SilkS")
		)
		(fp_line
			(start -0.8636 0.8636)
			(end -0.8636 -0.8636)
			(stroke
				(width 0.1524)
				(type default)
			)
			(layer "B.SilkS")
		)
		(fp_poly
			(pts
				(xy 0.635 -0.635) (xy 0.635 0.635) (xy -0.635 0.635) (xy -0.635 -0.635)
			)
			(stroke
				(width 0)
				(type default)
			)
			(fill no)
			(layer "B.CrtYd")
		)
		(pad "1" smd rect
			(at 0 0 270)
			(size 1.27 1.27)
			(layers "B.Cu" "B.Mask" "B.Paste")
			(net "VDD_CORE")
		)
	)
	(footprint ""
		(layer "B.Cu")
		(at 76.251003 14.256004)
		(property "Reference" "V_A-DQS2-N"
			(at 0 0 0)
			(layer "B.SilkS")
			(hide yes)
			(effects
				(font
					(size 1.27 1.27)
				)
				(justify mirror)
			)
		)
		(property "Value" ""
			(at 0 0 0)
			(layer "B.Fab")
			(effects
				(font
					(size 1.27 1.27)
				)
				(justify mirror)
			)
		)
		(duplicate_pad_numbers_are_jumpers no)
		(pad "1" thru_hole circle
			(at 0 0 180)
			(size 0.4572 0.4572)
			(drill 0.20574)
			(layers "*.Cu" "*.Mask")
			(remove_unused_layers no)
			(net "DDR0_32A_DQS2_N")
			(clearance 0.1143)
			(thermal_gap 0.1143)
		)
	)
	(footprint ""
		(layer "B.Cu")
		(at 67.236975 12.542012 180)
		(property "Reference" "C193"
			(at 0 0 0)
			(layer "B.SilkS")
			(hide yes)
			(effects
				(font
					(size 1.27 1.27)
				)
				(justify mirror)
			)
		)
		(property "Value" ""
			(at 0 0 0)
			(layer "B.Fab")
			(effects
				(font
					(size 1.27 1.27)
				)
				(justify mirror)
			)
		)
		(duplicate_pad_numbers_are_jumpers no)
		(fp_circle
			(center 0 0)
			(end -0.104648 0)
			(stroke
				(width 0.1016)
				(type default)
			)
			(fill no)
			(layer "B.SilkS")
		)
		(fp_poly
			(pts
				(xy 0.381 -0.889) (xy 0.381 0.889) (xy -0.381 0.889) (xy -0.381 -0.889)
			)
			(stroke
				(width 0)
				(type default)
			)
			(fill no)
			(layer "B.CrtYd")
		)
		(fp_line
			(start 0.508 1.016)
			(end 0.508 -1.016)
			(stroke
				(width 0.0254)
				(type default)
			)
			(layer "B.Fab")
		)
		(fp_line
			(start 0.508 -1.016)
			(end 0.254 -1.016)
			(stroke
				(width 0.0254)
				(type default)
			)
			(layer "B.Fab")
		)
		(fp_line
			(start 0.254 -1.016)
			(end -0.508 -1.016)
			(stroke
				(width 0.0254)
				(type default)
			)
			(layer "B.Fab")
		)
		(fp_line
			(start -0.508 1.016)
			(end 0.508 1.016)
			(stroke
				(width 0.0254)
				(type default)
			)
			(layer "B.Fab")
		)
		(fp_line
			(start -0.508 -1.016)
			(end -0.508 1.016)
			(stroke
				(width 0.0254)
				(type default)
			)
			(layer "B.Fab")
		)
		(pad "1" smd custom
			(at 0 -0.500126)
			(size 0.127 0.127)
			(layers "B.Cu" "B.Mask" "B.Paste")
			(net "DDR_VDDQ")
			(options
				(clearance outline)
				(anchor circle)
			)
			(primitives
				(gr_poly
					(pts
						(xy -0.1778 0.254) (xy 0.1778 0.254) (xy 0.254 0.1778) (xy 0.254 -0.1778) (xy 0.1778 -0.254) (xy -0.1778 -0.254)
						(xy -0.254 -0.1778) (xy -0.254 0.1778)
					)
					(width 0)
					(fill yes)
				)
			)
		)
		(pad "2" smd custom
			(at 0 0.500126)
			(size 0.127 0.127)
			(layers "B.Cu" "B.Mask" "B.Paste")
			(net "GND")
			(options
				(clearance outline)
				(anchor circle)
			)
			(primitives
				(gr_poly
					(pts
						(xy -0.1778 0.254) (xy 0.1778 0.254) (xy 0.254 0.1778) (xy 0.254 -0.1778) (xy 0.1778 -0.254) (xy -0.1778 -0.254)
						(xy -0.254 -0.1778) (xy -0.254 0.1778)
					)
					(width 0)
					(fill yes)
				)
			)
		)
	)
	(footprint ""
		(layer "B.Cu")
		(at 24.13 2.794)
		(property "Reference" "R370"
			(at 0.98933 1.524 270)
			(unlocked yes)
			(layer "B.SilkS")
			(effects
				(font
					(size 0.7874 0.5842)
					(thickness 0.127)
				)
				(justify left mirror)
			)
		)
		(property "Value" "4.75K"
			(at 0.148158 1.3462 270)
			(unlocked yes)
			(layer "B.Fab")
			(hide yes)
			(effects
				(font
					(size 1.27 0.9652)
					(thickness 0.000001)
				)
				(justify left mirror)
			)
		)
		(property "Device Type" "REST4024"
			(at 0.148158 1.3462 270)
			(unlocked yes)
			(layer "B.Fab")
			(hide yes)
			(effects
				(font
					(size 1.27 0.9652)
					(thickness 0.000001)
				)
				(justify left mirror)
			)
		)
		(duplicate_pad_numbers_are_jumpers no)
		(fp_poly
			(pts
				(xy -0.635 1.0668) (xy -0.635 -1.0668) (xy 0.635 -1.0668) (xy 0.635 1.0668)
			)
			(stroke
				(width 0)
				(type default)
			)
			(fill no)
			(layer "B.CrtYd")
		)
		(fp_line
			(start -0.254 -0.508)
			(end -0.254 0.508)
			(stroke
				(width 0.0254)
				(type default)
			)
			(layer "B.Fab")
		)
		(fp_line
			(start -0.254 0.508)
			(end 0.254 0.508)
			(stroke
				(width 0.0254)
				(type default)
			)
			(layer "B.Fab")
		)
		(fp_line
			(start 0.254 -0.508)
			(end -0.254 -0.508)
			(stroke
				(width 0.0254)
				(type default)
			)
			(layer "B.Fab")
		)
		(fp_line
			(start 0.254 0.508)
			(end 0.254 -0.508)
			(stroke
				(width 0.0254)
				(type default)
			)
			(layer "B.Fab")
		)
		(pad "1" smd rect
			(at 0 -0.4191 180)
			(size 0.508 0.5334)
			(layers "B.Cu" "B.Mask" "B.Paste")
			(net "NFP_SMBUS_SCL")
		)
		(pad "2" smd rect
			(at 0 0.4191 180)
			(size 0.508 0.5334)
			(layers "B.Cu" "B.Mask" "B.Paste")
			(net "EXT_3.3V")
		)
		(zone
			(layer "B.Cu")
			(hatch none 0.5)
			(connect_pads
				(clearance 0)
			)
			(min_thickness 0.25)
			(keepout
				(tracks not_allowed)
				(vias allowed)
				(pads allowed)
				(copperpour not_allowed)
				(footprints allowed)
			)
			(placement
				(enabled no)
				(sheetname "")
			)
			(fill
				(thermal_gap 0.5)
				(thermal_bridge_width 0.5)
				(island_removal_mode 0)
			)
			(polygon
				(pts
					(xy 24.1046 2.7686) (xy 24.1046 2.8194) (xy 24.1554 2.8194) (xy 24.1554 2.7686)
				)
			)
		)
	)
	(footprint ""
		(layer "B.Cu")
		(at 40.64 28.829)
		(property "Reference" "R408"
			(at -0.02667 3.683 270)
			(unlocked yes)
			(layer "B.SilkS")
			(effects
				(font
					(size 0.7874 0.5842)
					(thickness 0.127)
				)
				(justify left mirror)
			)
		)
		(property "Value" "4.75K"
			(at 0.148158 1.3462 270)
			(unlocked yes)
			(layer "B.Fab")
			(hide yes)
			(effects
				(font
					(size 1.27 0.9652)
					(thickness 0.000001)
				)
				(justify left mirror)
			)
		)
		(property "Device Type" "REST4024"
			(at 0.148158 1.3462 270)
			(unlocked yes)
			(layer "B.Fab")
			(hide yes)
			(effects
				(font
					(size 1.27 0.9652)
					(thickness 0.000001)
				)
				(justify left mirror)
			)
		)
		(duplicate_pad_numbers_are_jumpers no)
		(fp_poly
			(pts
				(xy -0.635 1.0668) (xy -0.635 -1.0668) (xy 0.635 -1.0668) (xy 0.635 1.0668)
			)
			(stroke
				(width 0)
				(type default)
			)
			(fill no)
			(layer "B.CrtYd")
		)
		(fp_line
			(start -0.254 -0.508)
			(end -0.254 0.508)
			(stroke
				(width 0.0254)
				(type default)
			)
			(layer "B.Fab")
		)
		(fp_line
			(start -0.254 0.508)
			(end 0.254 0.508)
			(stroke
				(width 0.0254)
				(type default)
			)
			(layer "B.Fab")
		)
		(fp_line
			(start 0.254 -0.508)
			(end -0.254 -0.508)
			(stroke
				(width 0.0254)
				(type default)
			)
			(layer "B.Fab")
		)
		(fp_line
			(start 0.254 0.508)
			(end 0.254 -0.508)
			(stroke
				(width 0.0254)
				(type default)
			)
			(layer "B.Fab")
		)
		(pad "1" smd rect
			(at 0 -0.4191 180)
			(size 0.508 0.5334)
			(layers "B.Cu" "B.Mask" "B.Paste")
			(net "NFP_JTAG_ARM_TCK")
		)
		(pad "2" smd rect
			(at 0 0.4191 180)
			(size 0.508 0.5334)
			(layers "B.Cu" "B.Mask" "B.Paste")
			(net "GND")
		)
		(zone
			(layer "B.Cu")
			(hatch none 0.5)
			(connect_pads
				(clearance 0)
			)
			(min_thickness 0.25)
			(keepout
				(tracks not_allowed)
				(vias allowed)
				(pads allowed)
				(copperpour not_allowed)
				(footprints allowed)
			)
			(placement
				(enabled no)
				(sheetname "")
			)
			(fill
				(thermal_gap 0.5)
				(thermal_bridge_width 0.5)
				(island_removal_mode 0)
			)
			(polygon
				(pts
					(xy 40.6146 28.8036) (xy 40.6146 28.8544) (xy 40.6654 28.8544) (xy 40.6654 28.8036)
				)
			)
		)
	)
	(footprint ""
		(layer "B.Cu")
		(at 80.250995 29.812996)
		(property "Reference" "V3_A-A10"
			(at 0 0 0)
			(layer "B.SilkS")
			(hide yes)
			(effects
				(font
					(size 1.27 1.27)
				)
				(justify mirror)
			)
		)
		(property "Value" ""
			(at 0 0 0)
			(layer "B.Fab")
			(effects
				(font
					(size 1.27 1.27)
				)
				(justify mirror)
			)
		)
		(duplicate_pad_numbers_are_jumpers no)
		(pad "1" thru_hole circle
			(at 0 0 180)
			(size 0.4572 0.4572)
			(drill 0.20574)
			(layers "*.Cu" "*.Mask")
			(remove_unused_layers no)
			(net "DDR0_32A_A10")
			(clearance 0.1143)
			(thermal_gap 0.1143)
		)
	)
	(footprint ""
		(layer "B.Cu")
		(at 30.988 5.588 180)
		(property "Reference" "C36"
			(at 0.02667 0.889 270)
			(unlocked yes)
			(layer "B.SilkS")
			(effects
				(font
					(size 0.7874 0.5842)
					(thickness 0.127)
				)
				(justify left mirror)
			)
		)
		(property "Value" "10UF"
			(at 0.091846 0.2921 90)
			(unlocked yes)
			(layer "B.Fab")
			(hide yes)
			(effects
				(font
					(size 0.7874 0.5842)
					(thickness 0.2032)
				)
				(justify left mirror)
			)
		)
		(property "Device Type" "CAPC0064"
			(at 0.091846 0.2921 90)
			(unlocked yes)
			(layer "B.Fab")
			(hide yes)
			(effects
				(font
					(size 0.7874 0.5842)
					(thickness 0.2032)
				)
				(justify left mirror)
			)
		)
		(duplicate_pad_numbers_are_jumpers no)
		(fp_poly
			(pts
				(xy -0.635 1.0668) (xy -0.635 -1.0668) (xy 0.635 -1.0668) (xy 0.635 1.0668)
			)
			(stroke
				(width 0)
				(type default)
			)
			(fill no)
			(layer "B.CrtYd")
		)
		(fp_line
			(start 0.254 0.508)
			(end 0.254 -0.508)
			(stroke
				(width 0.0254)
				(type default)
			)
			(layer "B.Fab")
		)
		(fp_line
			(start 0.254 -0.508)
			(end -0.254 -0.508)
			(stroke
				(width 0.0254)
				(type default)
			)
			(layer "B.Fab")
		)
		(fp_line
			(start -0.254 0.508)
			(end 0.254 0.508)
			(stroke
				(width 0.0254)
				(type default)
			)
			(layer "B.Fab")
		)
		(fp_line
			(start -0.254 -0.508)
			(end -0.254 0.508)
			(stroke
				(width 0.0254)
				(type default)
			)
			(layer "B.Fab")
		)
		(pad "1" smd rect
			(at 0 -0.4191)
			(size 0.508 0.5334)
			(layers "B.Cu" "B.Mask" "B.Paste")
			(net "EXT_3.3V")
		)
		(pad "2" smd rect
			(at 0 0.4191)
			(size 0.508 0.5334)
			(layers "B.Cu" "B.Mask" "B.Paste")
			(net "GND")
		)
		(zone
			(layer "B.Cu")
			(hatch none 0.5)
			(connect_pads
				(clearance 0)
			)
			(min_thickness 0.25)
			(keepout
				(tracks not_allowed)
				(vias allowed)
				(pads allowed)
				(copperpour not_allowed)
				(footprints allowed)
			)
			(placement
				(enabled no)
				(sheetname "")
			)
			(fill
				(thermal_gap 0.5)
				(thermal_bridge_width 0.5)
				(island_removal_mode 0)
			)
			(polygon
				(pts
					(xy 31.0134 5.6134) (xy 31.0134 5.5626) (xy 30.9626 5.5626) (xy 30.9626 5.6134)
				)
			)
		)
	)
	(footprint ""
		(layer "B.Cu")
		(at 3.3655 11.176 90)
		(property "Reference" "R388"
			(at 0 0 90)
			(layer "B.SilkS")
			(hide yes)
			(effects
				(font
					(size 1.27 1.27)
				)
				(justify mirror)
			)
		)
		(property "Value" "0"
			(at 0.148158 1.3462 0)
			(unlocked yes)
			(layer "B.Fab")
			(hide yes)
			(effects
				(font
					(size 1.27 0.9652)
					(thickness 0.000001)
				)
				(justify left mirror)
			)
		)
		(property "Device Type" "REST1111"
			(at 0.148158 1.3462 0)
			(unlocked yes)
			(layer "B.Fab")
			(hide yes)
			(effects
				(font
					(size 1.27 0.9652)
					(thickness 0.000001)
				)
				(justify left mirror)
			)
		)
		(duplicate_pad_numbers_are_jumpers no)
		(fp_poly
			(pts
				(xy -0.635 1.0668) (xy -0.635 -1.0668) (xy 0.635 -1.0668) (xy 0.635 1.0668)
			)
			(stroke
				(width 0)
				(type default)
			)
			(fill no)
			(layer "B.CrtYd")
		)
		(fp_line
			(start 0.254 -0.508)
			(end -0.254 -0.508)
			(stroke
				(width 0.0254)
				(type default)
			)
			(layer "B.Fab")
		)
		(fp_line
			(start -0.254 -0.508)
			(end -0.254 0.508)
			(stroke
				(width 0.0254)
				(type default)
			)
			(layer "B.Fab")
		)
		(fp_line
			(start 0.254 0.508)
			(end 0.254 -0.508)
			(stroke
				(width 0.0254)
				(type default)
			)
			(layer "B.Fab")
		)
		(fp_line
			(start -0.254 0.508)
			(end 0.254 0.508)
			(stroke
				(width 0.0254)
				(type default)
			)
			(layer "B.Fab")
		)
		(pad "1" smd rect
			(at 0 -0.4191 270)
			(size 0.508 0.5334)
			(layers "B.Cu" "B.Mask" "B.Paste")
			(net "NWK1_I2C_SDA")
		)
		(pad "2" smd rect
			(at 0 0.4191 270)
			(size 0.508 0.5334)
			(layers "B.Cu" "B.Mask" "B.Paste")
			(net "MUX_NFP_GPIO3_NWK1_I2C_SDA")
		)
		(zone
			(layer "B.Cu")
			(hatch none 0.5)
			(connect_pads
				(clearance 0)
			)
			(min_thickness 0.25)
			(keepout
				(tracks not_allowed)
				(vias allowed)
				(pads allowed)
				(copperpour not_allowed)
				(footprints allowed)
			)
			(placement
				(enabled no)
				(sheetname "")
			)
			(fill
				(thermal_gap 0.5)
				(thermal_bridge_width 0.5)
				(island_removal_mode 0)
			)
			(polygon
				(pts
					(xy 3.3401 11.2014) (xy 3.3909 11.2014) (xy 3.3909 11.1506) (xy 3.3401 11.1506)
				)
			)
		)
	)
	(footprint ""
		(layer "B.Cu")
		(at 2.54 13.716)
		(property "Reference" "U21"
			(at -4.09067 1.27 270)
			(unlocked yes)
			(layer "B.SilkS")
			(effects
				(font
					(size 0.7874 0.5842)
					(thickness 0.127)
				)
				(justify left mirror)
			)
		)
		(property "Value" "*"
			(at 0.4826 -0.148107 0)
			(unlocked yes)
			(layer "B.Fab")
			(hide yes)
			(effects
				(font
					(size 1.27 0.9652)
					(thickness 0.000001)
				)
				(justify left mirror)
			)
		)
		(property "Device Type" "ICSO0128"
			(at 0.4826 -0.148107 0)
			(unlocked yes)
			(layer "B.Fab")
			(hide yes)
			(effects
				(font
					(size 1.27 0.9652)
					(thickness 0.000001)
				)
				(justify left mirror)
			)
		)
		(duplicate_pad_numbers_are_jumpers no)
		(fp_line
			(start -2.159 -1.651)
			(end -2.159 -0.762)
			(stroke
				(width 0.1524)
				(type default)
			)
			(layer "B.SilkS")
		)
		(fp_line
			(start -2.159 1.651)
			(end -2.159 0.762)
			(stroke
				(width 0.1524)
				(type default)
			)
			(layer "B.SilkS")
		)
		(fp_line
			(start -1.778 -1.651)
			(end -2.159 -1.651)
			(stroke
				(width 0.1524)
				(type default)
			)
			(layer "B.SilkS")
		)
		(fp_line
			(start -1.778 1.651)
			(end -2.159 1.651)
			(stroke
				(width 0.1524)
				(type default)
			)
			(layer "B.SilkS")
		)
		(fp_line
			(start 1.778 -1.651)
			(end 2.159 -1.651)
			(stroke
				(width 0.1524)
				(type default)
			)
			(layer "B.SilkS")
		)
		(fp_line
			(start 1.778 1.651)
			(end 2.159 1.143)
			(stroke
				(width 0.1524)
				(type default)
			)
			(layer "B.SilkS")
		)
		(fp_line
			(start 1.778 1.651)
			(end 2.159 1.651)
			(stroke
				(width 0.1524)
				(type default)
			)
			(layer "B.SilkS")
		)
		(fp_line
			(start 2.159 -1.651)
			(end 2.159 -0.762)
			(stroke
				(width 0.1524)
				(type default)
			)
			(layer "B.SilkS")
		)
		(fp_line
			(start 2.159 1.651)
			(end 2.159 0.762)
			(stroke
				(width 0.1524)
				(type default)
			)
			(layer "B.SilkS")
		)
		(fp_circle
			(center 2.032 2.159)
			(end 2.286 2.159)
			(stroke
				(width 0.1524)
				(type default)
			)
			(fill no)
			(layer "B.SilkS")
		)
		(fp_poly
			(pts
				(xy 2.667 2.159) (xy -2.667 2.159) (xy -2.667 -2.159) (xy 2.667 -2.159)
			)
			(stroke
				(width 0)
				(type default)
			)
			(fill no)
			(layer "B.CrtYd")
		)
		(fp_line
			(start -1.8034 -1.2954)
			(end 1.8034 -1.2954)
			(stroke
				(width 0.1524)
				(type default)
			)
			(layer "B.Fab")
		)
		(fp_line
			(start -1.8034 1.2954)
			(end -1.8034 -1.2954)
			(stroke
				(width 0.1524)
				(type default)
			)
			(layer "B.Fab")
		)
		(fp_line
			(start 1.8034 -1.2954)
			(end 1.8034 1.2954)
			(stroke
				(width 0.1524)
				(type default)
			)
			(layer "B.Fab")
		)
		(fp_line
			(start 1.8034 1.2954)
			(end -1.8034 1.2954)
			(stroke
				(width 0.1524)
				(type default)
			)
			(layer "B.Fab")
		)
		(fp_circle
			(center 1.27 0.762)
			(end 1.553997 0.762)
			(stroke
				(width 0.1524)
				(type default)
			)
			(fill no)
			(layer "B.Fab")
		)
		(fp_text user "9"
			(at -2.3749 -0.472872 0)
			(unlocked yes)
			(layer "B.SilkS")
			(effects
				(font
					(size 0.7874 0.5842)
					(thickness 0.127)
				)
				(justify left mirror)
			)
		)
		(fp_text user "8"
			(at -2.3749 0.670154 0)
			(unlocked yes)
			(layer "B.SilkS")
			(effects
				(font
					(size 0.7874 0.5842)
					(thickness 0.127)
				)
				(justify left mirror)
			)
		)
		(fp_text user "10"
			(at -2.159 -1.75133 0)
			(unlocked yes)
			(layer "B.SilkS")
			(effects
				(font
					(size 0.7874 0.5842)
					(thickness 0.127)
				)
				(justify left mirror)
			)
		)
		(fp_text user "7"
			(at -2.159 1.67767 0)
			(unlocked yes)
			(layer "B.SilkS")
			(effects
				(font
					(size 0.7874 0.5842)
					(thickness 0.127)
				)
				(justify left mirror)
			)
		)
		(fp_text user "1"
			(at 2.667 0.53467 0)
			(unlocked yes)
			(layer "B.SilkS")
			(effects
				(font
					(size 0.7874 0.5842)
					(thickness 0.127)
				)
				(justify left mirror)
			)
		)
		(fp_text user "2"
			(at 2.921 2.18567 0)
			(unlocked yes)
			(layer "B.SilkS")
			(effects
				(font
					(size 0.7874 0.5842)
					(thickness 0.127)
				)
				(justify left mirror)
			)
		)
		(fp_text user "15"
			(at 3.048 -2.25933 0)
			(unlocked yes)
			(layer "B.SilkS")
			(effects
				(font
					(size 0.7874 0.5842)
					(thickness 0.127)
				)
				(justify left mirror)
			)
		)
		(fp_text user "16"
			(at 3.52933 -0.381 270)
			(unlocked yes)
			(layer "B.SilkS")
			(effects
				(font
					(size 0.7874 0.5842)
					(thickness 0.127)
				)
				(justify left mirror)
			)
		)
		(pad "1" smd custom
			(at 1.7018 0.250012 270)
			(size 0.06985 0.06985)
			(layers "B.Cu" "B.Mask" "B.Paste")
			(net "13N4351")
			(options
				(clearance outline)
				(anchor circle)
			)
			(primitives
				(gr_poly
					(pts
						(xy 0.1397 -0.4064)
						(arc
							(start 0.1397 0.2667)
							(mid 0 0.4064)
							(end -0.1397 0.2667)
						)
						(xy -0.1397 -0.4064)
					)
					(width 0)
					(fill yes)
				)
			)
		)
		(pad "2" smd custom
			(at 1.25001 1.1938 180)
			(size 0.06985 0.06985)
			(layers "B.Cu" "B.Mask" "B.Paste")
			(net "_NC_U21_74CBTLV_1B1")
			(options
				(clearance outline)
				(anchor circle)
			)
			(primitives
				(gr_poly
					(pts
						(xy 0.1397 -0.4064)
						(arc
							(start 0.1397 0.2667)
							(mid 0 0.4064)
							(end -0.1397 0.2667)
						)
						(xy -0.1397 -0.4064)
					)
					(width 0)
					(fill yes)
				)
			)
		)
		(pad "3" smd custom
			(at 0.750011 1.1938 180)
			(size 0.06985 0.06985)
			(layers "B.Cu" "B.Mask" "B.Paste")
			(net "MUX_NFP_GPIO0_NWK0_I2C_SCL")
			(options
				(clearance outline)
				(anchor circle)
			)
			(primitives
				(gr_poly
					(pts
						(xy 0.1397 -0.4064)
						(arc
							(start 0.1397 0.2667)
							(mid 0 0.4064)
							(end -0.1397 0.2667)
						)
						(xy -0.1397 -0.4064)
					)
					(width 0)
					(fill yes)
				)
			)
		)
		(pad "4" smd custom
			(at 0.250012 1.1938 180)
			(size 0.06985 0.06985)
			(layers "B.Cu" "B.Mask" "B.Paste")
			(net "NWK0_I2C_SCL")
			(options
				(clearance outline)
				(anchor circle)
			)
			(primitives
				(gr_poly
					(pts
						(xy 0.1397 -0.4064)
						(arc
							(start 0.1397 0.2667)
							(mid 0 0.4064)
							(end -0.1397 0.2667)
						)
						(xy -0.1397 -0.4064)
					)
					(width 0)
					(fill yes)
				)
			)
		)
		(pad "5" smd custom
			(at -0.250012 1.1938 180)
			(size 0.06985 0.06985)
			(layers "B.Cu" "B.Mask" "B.Paste")
			(net "_NC_U21_74CBTLV_2B1")
			(options
				(clearance outline)
				(anchor circle)
			)
			(primitives
				(gr_poly
					(pts
						(xy 0.1397 -0.4064)
						(arc
							(start 0.1397 0.2667)
							(mid 0 0.4064)
							(end -0.1397 0.2667)
						)
						(xy -0.1397 -0.4064)
					)
					(width 0)
					(fill yes)
				)
			)
		)
		(pad "6" smd custom
			(at -0.750011 1.1938 180)
			(size 0.06985 0.06985)
			(layers "B.Cu" "B.Mask" "B.Paste")
			(net "MUX_NFP_GPIO1_NWK0_I2C_SDA")
			(options
				(clearance outline)
				(anchor circle)
			)
			(primitives
				(gr_poly
					(pts
						(xy 0.1397 -0.4064)
						(arc
							(start 0.1397 0.2667)
							(mid 0 0.4064)
							(end -0.1397 0.2667)
						)
						(xy -0.1397 -0.4064)
					)
					(width 0)
					(fill yes)
				)
			)
		)
		(pad "7" smd custom
			(at -1.25001 1.1938 180)
			(size 0.06985 0.06985)
			(layers "B.Cu" "B.Mask" "B.Paste")
			(net "NWK0_I2C_SDA")
			(options
				(clearance outline)
				(anchor circle)
			)
			(primitives
				(gr_poly
					(pts
						(xy 0.1397 -0.4064)
						(arc
							(start 0.1397 0.2667)
							(mid 0 0.4064)
							(end -0.1397 0.2667)
						)
						(xy -0.1397 -0.4064)
					)
					(width 0)
					(fill yes)
				)
			)
		)
		(pad "8" smd custom
			(at -1.7018 0.250012 90)
			(size 0.06985 0.06985)
			(layers "B.Cu" "B.Mask" "B.Paste")
			(net "GND")
			(options
				(clearance outline)
				(anchor circle)
			)
			(primitives
				(gr_poly
					(pts
						(xy 0.1397 -0.4064)
						(arc
							(start 0.1397 0.2667)
							(mid 0 0.4064)
							(end -0.1397 0.2667)
						)
						(xy -0.1397 -0.4064)
					)
					(width 0)
					(fill yes)
				)
			)
		)
		(pad "9" smd custom
			(at -1.7018 -0.250012 90)
			(size 0.06985 0.06985)
			(layers "B.Cu" "B.Mask" "B.Paste")
			(net "NWK1_I2C_SCL")
			(options
				(clearance outline)
				(anchor circle)
			)
			(primitives
				(gr_poly
					(pts
						(xy 0.1397 -0.4064)
						(arc
							(start 0.1397 0.2667)
							(mid 0 0.4064)
							(end -0.1397 0.2667)
						)
						(xy -0.1397 -0.4064)
					)
					(width 0)
					(fill yes)
				)
			)
		)
		(pad "10" smd custom
			(at -1.25001 -1.1938)
			(size 0.06985 0.06985)
			(layers "B.Cu" "B.Mask" "B.Paste")
			(net "MUX_NFP_GPIO2_NWK1_I2C_SCL")
			(options
				(clearance outline)
				(anchor circle)
			)
			(primitives
				(gr_poly
					(pts
						(xy 0.1397 -0.4064)
						(arc
							(start 0.1397 0.2667)
							(mid 0 0.4064)
							(end -0.1397 0.2667)
						)
						(xy -0.1397 -0.4064)
					)
					(width 0)
					(fill yes)
				)
			)
		)
		(pad "11" smd custom
			(at -0.750011 -1.1938)
			(size 0.06985 0.06985)
			(layers "B.Cu" "B.Mask" "B.Paste")
			(net "_NC_U21_74CBTLV_3B1")
			(options
				(clearance outline)
				(anchor circle)
			)
			(primitives
				(gr_poly
					(pts
						(xy 0.1397 -0.4064)
						(arc
							(start 0.1397 0.2667)
							(mid 0 0.4064)
							(end -0.1397 0.2667)
						)
						(xy -0.1397 -0.4064)
					)
					(width 0)
					(fill yes)
				)
			)
		)
		(pad "12" smd custom
			(at -0.250012 -1.1938)
			(size 0.06985 0.06985)
			(layers "B.Cu" "B.Mask" "B.Paste")
			(net "NWK1_I2C_SDA")
			(options
				(clearance outline)
				(anchor circle)
			)
			(primitives
				(gr_poly
					(pts
						(xy 0.1397 -0.4064)
						(arc
							(start 0.1397 0.2667)
							(mid 0 0.4064)
							(end -0.1397 0.2667)
						)
						(xy -0.1397 -0.4064)
					)
					(width 0)
					(fill yes)
				)
			)
		)
		(pad "13" smd custom
			(at 0.250012 -1.1938)
			(size 0.06985 0.06985)
			(layers "B.Cu" "B.Mask" "B.Paste")
			(net "MUX_NFP_GPIO3_NWK1_I2C_SDA")
			(options
				(clearance outline)
				(anchor circle)
			)
			(primitives
				(gr_poly
					(pts
						(xy 0.1397 -0.4064)
						(arc
							(start 0.1397 0.2667)
							(mid 0 0.4064)
							(end -0.1397 0.2667)
						)
						(xy -0.1397 -0.4064)
					)
					(width 0)
					(fill yes)
				)
			)
		)
		(pad "14" smd custom
			(at 0.750011 -1.1938)
			(size 0.06985 0.06985)
			(layers "B.Cu" "B.Mask" "B.Paste")
			(net "_NC_U21_74CBTLV_4B1")
			(options
				(clearance outline)
				(anchor circle)
			)
			(primitives
				(gr_poly
					(pts
						(xy 0.1397 -0.4064)
						(arc
							(start 0.1397 0.2667)
							(mid 0 0.4064)
							(end -0.1397 0.2667)
						)
						(xy -0.1397 -0.4064)
					)
					(width 0)
					(fill yes)
				)
			)
		)
		(pad "15" smd custom
			(at 1.25001 -1.1938)
			(size 0.06985 0.06985)
			(layers "B.Cu" "B.Mask" "B.Paste")
			(net "13N4347")
			(options
				(clearance outline)
				(anchor circle)
			)
			(primitives
				(gr_poly
					(pts
						(xy 0.1397 -0.4064)
						(arc
							(start 0.1397 0.2667)
							(mid 0 0.4064)
							(end -0.1397 0.2667)
						)
						(xy -0.1397 -0.4064)
					)
					(width 0)
					(fill yes)
				)
			)
		)
		(pad "16" smd custom
			(at 1.7018 -0.250012 270)
			(size 0.06985 0.06985)
			(layers "B.Cu" "B.Mask" "B.Paste")
			(net "EXT_3.3V")
			(options
				(clearance outline)
				(anchor circle)
			)
			(primitives
				(gr_poly
					(pts
						(xy 0.1397 -0.4064)
						(arc
							(start 0.1397 0.2667)
							(mid 0 0.4064)
							(end -0.1397 0.2667)
						)
						(xy -0.1397 -0.4064)
					)
					(width 0)
					(fill yes)
				)
			)
		)
		(pad "17" smd rect
			(at 0 0 180)
			(size 1.9812 0.9652)
			(layers "B.Cu" "B.Mask" "B.Paste")
			(net "GND")
		)
		(zone
			(layer "B.Cu")
			(hatch none 0.5)
			(connect_pads
				(clearance 0)
			)
			(min_thickness 0.25)
			(keepout
				(tracks allowed)
				(vias not_allowed)
				(pads allowed)
				(copperpour not_allowed)
				(footprints allowed)
			)
			(placement
				(enabled no)
				(sheetname "")
			)
			(fill
				(thermal_gap 0.5)
				(thermal_bridge_width 0.5)
				(island_removal_mode 0)
			)
			(polygon
				(pts
					(arc
						(start 4.9022 15.875)
						(mid 4.2418 15.875)
						(end 4.9022 15.875)
					)
				)
			)
		)
	)
	(footprint ""
		(layer "B.Cu")
		(at 46.237017 9.542018)
		(property "Reference" "R319"
			(at 0 0 0)
			(layer "B.SilkS")
			(hide yes)
			(effects
				(font
					(size 1.27 1.27)
				)
				(justify mirror)
			)
		)
		(property "Value" ""
			(at 0 0 0)
			(layer "B.Fab")
			(effects
				(font
					(size 1.27 1.27)
				)
				(justify mirror)
			)
		)
		(duplicate_pad_numbers_are_jumpers no)
		(fp_circle
			(center 0 0)
			(end 0.104648 0)
			(stroke
				(width 0.1016)
				(type default)
			)
			(fill no)
			(layer "B.SilkS")
		)
		(fp_poly
			(pts
				(xy 0.381 -0.889) (xy 0.381 0.889) (xy -0.381 0.889) (xy -0.381 -0.889)
			)
			(stroke
				(width 0)
				(type default)
			)
			(fill no)
			(layer "B.CrtYd")
		)
		(fp_line
			(start -0.508 -1.016)
			(end -0.508 1.016)
			(stroke
				(width 0.0254)
				(type default)
			)
			(layer "B.Fab")
		)
		(fp_line
			(start -0.508 1.016)
			(end 0.508 1.016)
			(stroke
				(width 0.0254)
				(type default)
			)
			(layer "B.Fab")
		)
		(fp_line
			(start 0.254 -1.016)
			(end -0.508 -1.016)
			(stroke
				(width 0.0254)
				(type default)
			)
			(layer "B.Fab")
		)
		(fp_line
			(start 0.508 -1.016)
			(end 0.254 -1.016)
			(stroke
				(width 0.0254)
				(type default)
			)
			(layer "B.Fab")
		)
		(fp_line
			(start 0.508 1.016)
			(end 0.508 -1.016)
			(stroke
				(width 0.0254)
				(type default)
			)
			(layer "B.Fab")
		)
		(pad "1" smd custom
			(at 0 -0.500126 180)
			(size 0.127 0.127)
			(layers "B.Cu" "B.Mask" "B.Paste")
			(net "GND")
			(options
				(clearance outline)
				(anchor circle)
			)
			(primitives
				(gr_poly
					(pts
						(xy -0.1778 0.254) (xy 0.1778 0.254) (xy 0.254 0.1778) (xy 0.254 -0.1778) (xy 0.1778 -0.254) (xy -0.1778 -0.254)
						(xy -0.254 -0.1778) (xy -0.254 0.1778)
					)
					(width 0)
					(fill yes)
				)
			)
		)
		(pad "2" smd custom
			(at 0 0.500126 180)
			(size 0.127 0.127)
			(layers "B.Cu" "B.Mask" "B.Paste")
			(net "NFP_SERDES012_SYSCLK_IN_P")
			(options
				(clearance outline)
				(anchor circle)
			)
			(primitives
				(gr_poly
					(pts
						(xy -0.1778 0.254) (xy 0.1778 0.254) (xy 0.254 0.1778) (xy 0.254 -0.1778) (xy 0.1778 -0.254) (xy -0.1778 -0.254)
						(xy -0.254 -0.1778) (xy -0.254 0.1778)
					)
					(width 0)
					(fill yes)
				)
			)
		)
	)
	(footprint ""
		(layer "B.Cu")
		(at 81.850992 6.698996)
		(property "Reference" "V1_A-A12"
			(at 0 0 0)
			(layer "B.SilkS")
			(hide yes)
			(effects
				(font
					(size 1.27 1.27)
				)
				(justify mirror)
			)
		)
		(property "Value" ""
			(at 0 0 0)
			(layer "B.Fab")
			(effects
				(font
					(size 1.27 1.27)
				)
				(justify mirror)
			)
		)
		(duplicate_pad_numbers_are_jumpers no)
		(pad "1" thru_hole circle
			(at 0 0 180)
			(size 0.4572 0.4572)
			(drill 0.20574)
			(layers "*.Cu" "*.Mask")
			(remove_unused_layers no)
			(net "DDR0_32A_A12")
			(clearance 0.1143)
			(thermal_gap 0.1143)
		)
	)
	(footprint ""
		(layer "B.Cu")
		(at 81.050994 1.899006)
		(property "Reference" "V1_A-BA0"
			(at 0 0 0)
			(layer "B.SilkS")
			(hide yes)
			(effects
				(font
					(size 1.27 1.27)
				)
				(justify mirror)
			)
		)
		(property "Value" ""
			(at 0 0 0)
			(layer "B.Fab")
			(effects
				(font
					(size 1.27 1.27)
				)
				(justify mirror)
			)
		)
		(duplicate_pad_numbers_are_jumpers no)
		(pad "1" thru_hole circle
			(at 0 0 180)
			(size 0.4572 0.4572)
			(drill 0.20574)
			(layers "*.Cu" "*.Mask")
			(remove_unused_layers no)
			(net "DDR0_32A_BA0")
			(clearance 0.1143)
			(thermal_gap 0.1143)
		)
	)
	(footprint ""
		(layer "B.Cu")
		(at 51.237007 12.542012)
		(property "Reference" "C77"
			(at -0.463677 2.316988 270)
			(unlocked yes)
			(layer "B.SilkS")
			(effects
				(font
					(size 0.7874 0.5842)
					(thickness 0.127)
				)
				(justify mirror)
			)
		)
		(property "Value" ""
			(at 0 0 0)
			(layer "B.Fab")
			(effects
				(font
					(size 1.27 1.27)
				)
				(justify mirror)
			)
		)
		(duplicate_pad_numbers_are_jumpers no)
		(fp_circle
			(center 0 0)
			(end 0.104648 0)
			(stroke
				(width 0.1016)
				(type default)
			)
			(fill no)
			(layer "B.SilkS")
		)
		(fp_poly
			(pts
				(xy 0.381 -0.889) (xy 0.381 0.889) (xy -0.381 0.889) (xy -0.381 -0.889)
			)
			(stroke
				(width 0)
				(type default)
			)
			(fill no)
			(layer "B.CrtYd")
		)
		(fp_line
			(start -0.508 -1.016)
			(end -0.508 1.016)
			(stroke
				(width 0.0254)
				(type default)
			)
			(layer "B.Fab")
		)
		(fp_line
			(start -0.508 1.016)
			(end 0.508 1.016)
			(stroke
				(width 0.0254)
				(type default)
			)
			(layer "B.Fab")
		)
		(fp_line
			(start 0.254 -1.016)
			(end -0.508 -1.016)
			(stroke
				(width 0.0254)
				(type default)
			)
			(layer "B.Fab")
		)
		(fp_line
			(start 0.508 -1.016)
			(end 0.254 -1.016)
			(stroke
				(width 0.0254)
				(type default)
			)
			(layer "B.Fab")
		)
		(fp_line
			(start 0.508 1.016)
			(end 0.508 -1.016)
			(stroke
				(width 0.0254)
				(type default)
			)
			(layer "B.Fab")
		)
		(pad "1" smd custom
			(at 0 -0.500126 180)
			(size 0.127 0.127)
			(layers "B.Cu" "B.Mask" "B.Paste")
			(net "VDD_CORE")
			(options
				(clearance outline)
				(anchor circle)
			)
			(primitives
				(gr_poly
					(pts
						(xy -0.1778 0.254) (xy 0.1778 0.254) (xy 0.254 0.1778) (xy 0.254 -0.1778) (xy 0.1778 -0.254) (xy -0.1778 -0.254)
						(xy -0.254 -0.1778) (xy -0.254 0.1778)
					)
					(width 0)
					(fill yes)
				)
			)
		)
		(pad "2" smd custom
			(at 0 0.500126 180)
			(size 0.127 0.127)
			(layers "B.Cu" "B.Mask" "B.Paste")
			(net "GND")
			(options
				(clearance outline)
				(anchor circle)
			)
			(primitives
				(gr_poly
					(pts
						(xy -0.1778 0.254) (xy 0.1778 0.254) (xy 0.254 0.1778) (xy 0.254 -0.1778) (xy 0.1778 -0.254) (xy -0.1778 -0.254)
						(xy -0.254 -0.1778) (xy -0.254 0.1778)
					)
					(width 0)
					(fill yes)
				)
			)
		)
	)
	(footprint ""
		(layer "B.Cu")
		(at 82.65099 25.813004)
		(property "Reference" "V3_A-A02"
			(at 0 0 0)
			(layer "B.SilkS")
			(hide yes)
			(effects
				(font
					(size 1.27 1.27)
				)
				(justify mirror)
			)
		)
		(property "Value" ""
			(at 0 0 0)
			(layer "B.Fab")
			(effects
				(font
					(size 1.27 1.27)
				)
				(justify mirror)
			)
		)
		(duplicate_pad_numbers_are_jumpers no)
		(pad "1" thru_hole circle
			(at 0 0 180)
			(size 0.4572 0.4572)
			(drill 0.20574)
			(layers "*.Cu" "*.Mask")
			(remove_unused_layers no)
			(net "DDR0_32A_A2")
			(clearance 0.1143)
			(thermal_gap 0.1143)
		)
	)
	(footprint ""
		(layer "B.Cu")
		(at 62.484 3.556 90)
		(property "Reference" "C279"
			(at 0.98933 0.762 0)
			(unlocked yes)
			(layer "B.SilkS")
			(effects
				(font
					(size 0.7874 0.5842)
					(thickness 0.127)
				)
				(justify left mirror)
			)
		)
		(property "Value" "22UF"
			(at 0.148158 1.7526 0)
			(unlocked yes)
			(layer "B.Fab")
			(hide yes)
			(effects
				(font
					(size 1.27 0.9652)
					(thickness 0.000001)
				)
				(justify left mirror)
			)
		)
		(property "Device Type" "CAPC0063"
			(at 0.148158 1.7526 0)
			(unlocked yes)
			(layer "B.Fab")
			(hide yes)
			(effects
				(font
					(size 1.27 0.9652)
					(thickness 0.000001)
				)
				(justify left mirror)
			)
		)
		(duplicate_pad_numbers_are_jumpers no)
		(fp_circle
			(center 0 0)
			(end 0 0.127)
			(stroke
				(width 0.2032)
				(type default)
			)
			(fill no)
			(layer "B.SilkS")
		)
		(fp_poly
			(pts
				(xy -0.7874 -1.6637) (xy 0.7874 -1.6637) (xy 0.7874 1.6637) (xy -0.7874 1.6637)
			)
			(stroke
				(width 0)
				(type default)
			)
			(fill no)
			(layer "B.CrtYd")
		)
		(fp_line
			(start 0.4064 -0.7874)
			(end -0.4064 -0.7874)
			(stroke
				(width 0.0254)
				(type default)
			)
			(layer "B.Fab")
		)
		(fp_line
			(start -0.4064 -0.7874)
			(end -0.4064 0.8128)
			(stroke
				(width 0.0254)
				(type default)
			)
			(layer "B.Fab")
		)
		(fp_line
			(start 0.4064 0.8128)
			(end 0.4064 -0.7874)
			(stroke
				(width 0.0254)
				(type default)
			)
			(layer "B.Fab")
		)
		(fp_line
			(start -0.4064 0.8128)
			(end 0.4064 0.8128)
			(stroke
				(width 0.0254)
				(type default)
			)
			(layer "B.Fab")
		)
		(pad "1" smd rect
			(at 0 -0.8001 270)
			(size 0.8636 0.9652)
			(layers "B.Cu" "B.Mask" "B.Paste")
			(net "VDDA_PCIE0")
		)
		(pad "2" smd rect
			(at 0 0.8001 270)
			(size 0.8636 0.9652)
			(layers "B.Cu" "B.Mask" "B.Paste")
			(net "GND")
		)
		(zone
			(layer "B.Cu")
			(hatch none 0.5)
			(connect_pads
				(clearance 0)
			)
			(min_thickness 0.25)
			(keepout
				(tracks not_allowed)
				(vias allowed)
				(pads allowed)
				(copperpour not_allowed)
				(footprints allowed)
			)
			(placement
				(enabled no)
				(sheetname "")
			)
			(fill
				(thermal_gap 0.5)
				(thermal_bridge_width 0.5)
				(island_removal_mode 0)
			)
			(polygon
				(pts
					(xy 62.23 3.4925) (xy 62.23 3.6195) (xy 62.738 3.6195) (xy 62.738 3.4925)
				)
			)
		)
	)
	(footprint ""
		(layer "B.Cu")
		(at 40.259 9.652 -90)
		(property "Reference" "R405"
			(at -0.73533 -0.762 0)
			(unlocked yes)
			(layer "B.SilkS")
			(effects
				(font
					(size 0.7874 0.5842)
					(thickness 0.127)
				)
				(justify left mirror)
			)
		)
		(property "Value" "4.75K"
			(at 0.148158 1.3462 180)
			(unlocked yes)
			(layer "B.Fab")
			(hide yes)
			(effects
				(font
					(size 1.27 0.9652)
					(thickness 0.000001)
				)
				(justify left mirror)
			)
		)
		(property "Device Type" "REST4024"
			(at 0.148158 1.3462 180)
			(unlocked yes)
			(layer "B.Fab")
			(hide yes)
			(effects
				(font
					(size 1.27 0.9652)
					(thickness 0.000001)
				)
				(justify left mirror)
			)
		)
		(duplicate_pad_numbers_are_jumpers no)
		(fp_poly
			(pts
				(xy -0.635 1.0668) (xy -0.635 -1.0668) (xy 0.635 -1.0668) (xy 0.635 1.0668)
			)
			(stroke
				(width 0)
				(type default)
			)
			(fill no)
			(layer "B.CrtYd")
		)
		(fp_line
			(start -0.254 0.508)
			(end 0.254 0.508)
			(stroke
				(width 0.0254)
				(type default)
			)
			(layer "B.Fab")
		)
		(fp_line
			(start 0.254 0.508)
			(end 0.254 -0.508)
			(stroke
				(width 0.0254)
				(type default)
			)
			(layer "B.Fab")
		)
		(fp_line
			(start -0.254 -0.508)
			(end -0.254 0.508)
			(stroke
				(width 0.0254)
				(type default)
			)
			(layer "B.Fab")
		)
		(fp_line
			(start 0.254 -0.508)
			(end -0.254 -0.508)
			(stroke
				(width 0.0254)
				(type default)
			)
			(layer "B.Fab")
		)
		(pad "1" smd rect
			(at 0 -0.4191 90)
			(size 0.508 0.5334)
			(layers "B.Cu" "B.Mask" "B.Paste")
			(net "VDD_3.3V")
		)
		(pad "2" smd rect
			(at 0 0.4191 90)
			(size 0.508 0.5334)
			(layers "B.Cu" "B.Mask" "B.Paste")
			(net "NFP_JTAG_ARM_TMS")
		)
		(zone
			(layer "B.Cu")
			(hatch none 0.5)
			(connect_pads
				(clearance 0)
			)
			(min_thickness 0.25)
			(keepout
				(tracks not_allowed)
				(vias allowed)
				(pads allowed)
				(copperpour not_allowed)
				(footprints allowed)
			)
			(placement
				(enabled no)
				(sheetname "")
			)
			(fill
				(thermal_gap 0.5)
				(thermal_bridge_width 0.5)
				(island_removal_mode 0)
			)
			(polygon
				(pts
					(xy 40.2844 9.6266) (xy 40.2336 9.6266) (xy 40.2336 9.6774) (xy 40.2844 9.6774)
				)
			)
		)
	)
	(footprint ""
		(layer "B.Cu")
		(at 44.73702 13.042011 90)
		(property "Reference" "C275"
			(at 0 0 90)
			(layer "B.SilkS")
			(hide yes)
			(effects
				(font
					(size 1.27 1.27)
				)
				(justify mirror)
			)
		)
		(property "Value" ""
			(at 0 0 90)
			(layer "B.Fab")
			(effects
				(font
					(size 1.27 1.27)
				)
				(justify mirror)
			)
		)
		(duplicate_pad_numbers_are_jumpers no)
		(fp_circle
			(center 0 0)
			(end 0 0.104648)
			(stroke
				(width 0.1016)
				(type default)
			)
			(fill no)
			(layer "B.SilkS")
		)
		(fp_poly
			(pts
				(xy 0.381 -0.889) (xy 0.381 0.889) (xy -0.381 0.889) (xy -0.381 -0.889)
			)
			(stroke
				(width 0)
				(type default)
			)
			(fill no)
			(layer "B.CrtYd")
		)
		(fp_line
			(start 0.508 -1.016)
			(end 0.254 -1.016)
			(stroke
				(width 0.0254)
				(type default)
			)
			(layer "B.Fab")
		)
		(fp_line
			(start 0.254 -1.016)
			(end -0.508 -1.016)
			(stroke
				(width 0.0254)
				(type default)
			)
			(layer "B.Fab")
		)
		(fp_line
			(start -0.508 -1.016)
			(end -0.508 1.016)
			(stroke
				(width 0.0254)
				(type default)
			)
			(layer "B.Fab")
		)
		(fp_line
			(start 0.508 1.016)
			(end 0.508 -1.016)
			(stroke
				(width 0.0254)
				(type default)
			)
			(layer "B.Fab")
		)
		(fp_line
			(start -0.508 1.016)
			(end 0.508 1.016)
			(stroke
				(width 0.0254)
				(type default)
			)
			(layer "B.Fab")
		)
		(pad "1" smd custom
			(at 0 -0.500126 270)
			(size 0.127 0.127)
			(layers "B.Cu" "B.Mask" "B.Paste")
			(net "VDD_3.3V")
			(options
				(clearance outline)
				(anchor circle)
			)
			(primitives
				(gr_poly
					(pts
						(xy -0.1778 0.254) (xy 0.1778 0.254) (xy 0.254 0.1778) (xy 0.254 -0.1778) (xy 0.1778 -0.254) (xy -0.1778 -0.254)
						(xy -0.254 -0.1778) (xy -0.254 0.1778)
					)
					(width 0)
					(fill yes)
				)
			)
		)
		(pad "2" smd custom
			(at 0 0.500126 270)
			(size 0.127 0.127)
			(layers "B.Cu" "B.Mask" "B.Paste")
			(net "GND")
			(options
				(clearance outline)
				(anchor circle)
			)
			(primitives
				(gr_poly
					(pts
						(xy -0.1778 0.254) (xy 0.1778 0.254) (xy 0.254 0.1778) (xy 0.254 -0.1778) (xy 0.1778 -0.254) (xy -0.1778 -0.254)
						(xy -0.254 -0.1778) (xy -0.254 0.1778)
					)
					(width 0)
					(fill yes)
				)
			)
		)
	)
	(footprint ""
		(layer "B.Cu")
		(at 61.737011 9.042019 90)
		(property "Reference" "C170"
			(at 0 0 90)
			(layer "B.SilkS")
			(hide yes)
			(effects
				(font
					(size 1.27 1.27)
				)
				(justify mirror)
			)
		)
		(property "Value" ""
			(at 0 0 90)
			(layer "B.Fab")
			(effects
				(font
					(size 1.27 1.27)
				)
				(justify mirror)
			)
		)
		(duplicate_pad_numbers_are_jumpers no)
		(fp_circle
			(center 0 0)
			(end 0 0.104648)
			(stroke
				(width 0.1016)
				(type default)
			)
			(fill no)
			(layer "B.SilkS")
		)
		(fp_poly
			(pts
				(xy 0.381 -0.889) (xy 0.381 0.889) (xy -0.381 0.889) (xy -0.381 -0.889)
			)
			(stroke
				(width 0)
				(type default)
			)
			(fill no)
			(layer "B.CrtYd")
		)
		(fp_line
			(start 0.508 -1.016)
			(end 0.254 -1.016)
			(stroke
				(width 0.0254)
				(type default)
			)
			(layer "B.Fab")
		)
		(fp_line
			(start 0.254 -1.016)
			(end -0.508 -1.016)
			(stroke
				(width 0.0254)
				(type default)
			)
			(layer "B.Fab")
		)
		(fp_line
			(start -0.508 -1.016)
			(end -0.508 1.016)
			(stroke
				(width 0.0254)
				(type default)
			)
			(layer "B.Fab")
		)
		(fp_line
			(start 0.508 1.016)
			(end 0.508 -1.016)
			(stroke
				(width 0.0254)
				(type default)
			)
			(layer "B.Fab")
		)
		(fp_line
			(start -0.508 1.016)
			(end 0.508 1.016)
			(stroke
				(width 0.0254)
				(type default)
			)
			(layer "B.Fab")
		)
		(pad "1" smd custom
			(at 0 -0.500126 270)
			(size 0.127 0.127)
			(layers "B.Cu" "B.Mask" "B.Paste")
			(net "VDDA_PCIE0")
			(options
				(clearance outline)
				(anchor circle)
			)
			(primitives
				(gr_poly
					(pts
						(xy -0.1778 0.254) (xy 0.1778 0.254) (xy 0.254 0.1778) (xy 0.254 -0.1778) (xy 0.1778 -0.254) (xy -0.1778 -0.254)
						(xy -0.254 -0.1778) (xy -0.254 0.1778)
					)
					(width 0)
					(fill yes)
				)
			)
		)
		(pad "2" smd custom
			(at 0 0.500126 270)
			(size 0.127 0.127)
			(layers "B.Cu" "B.Mask" "B.Paste")
			(net "GND")
			(options
				(clearance outline)
				(anchor circle)
			)
			(primitives
				(gr_poly
					(pts
						(xy -0.1778 0.254) (xy 0.1778 0.254) (xy 0.254 0.1778) (xy 0.254 -0.1778) (xy 0.1778 -0.254) (xy -0.1778 -0.254)
						(xy -0.254 -0.1778) (xy -0.254 0.1778)
					)
					(width 0)
					(fill yes)
				)
			)
		)
	)
	(footprint ""
		(layer "B.Cu")
		(at 84.250987 6.698996)
		(property "Reference" "V1_A-A14"
			(at 0 0 0)
			(layer "B.SilkS")
			(hide yes)
			(effects
				(font
					(size 1.27 1.27)
				)
				(justify mirror)
			)
		)
		(property "Value" ""
			(at 0 0 0)
			(layer "B.Fab")
			(effects
				(font
					(size 1.27 1.27)
				)
				(justify mirror)
			)
		)
		(duplicate_pad_numbers_are_jumpers no)
		(pad "1" thru_hole circle
			(at 0 0 180)
			(size 0.4572 0.4572)
			(drill 0.20574)
			(layers "*.Cu" "*.Mask")
			(remove_unused_layers no)
			(net "DDR0_32A_A14")
			(clearance 0.1143)
			(thermal_gap 0.1143)
		)
	)
	(footprint ""
		(layer "B.Cu")
		(at 69.236971 13.54201 180)
		(property "Reference" "C192"
			(at 0 0 0)
			(layer "B.SilkS")
			(hide yes)
			(effects
				(font
					(size 1.27 1.27)
				)
				(justify mirror)
			)
		)
		(property "Value" ""
			(at 0 0 0)
			(layer "B.Fab")
			(effects
				(font
					(size 1.27 1.27)
				)
				(justify mirror)
			)
		)
		(duplicate_pad_numbers_are_jumpers no)
		(fp_circle
			(center 0 0)
			(end -0.104648 0)
			(stroke
				(width 0.1016)
				(type default)
			)
			(fill no)
			(layer "B.SilkS")
		)
		(fp_poly
			(pts
				(xy 0.381 -0.889) (xy 0.381 0.889) (xy -0.381 0.889) (xy -0.381 -0.889)
			)
			(stroke
				(width 0)
				(type default)
			)
			(fill no)
			(layer "B.CrtYd")
		)
		(fp_line
			(start 0.508 1.016)
			(end 0.508 -1.016)
			(stroke
				(width 0.0254)
				(type default)
			)
			(layer "B.Fab")
		)
		(fp_line
			(start 0.508 -1.016)
			(end 0.254 -1.016)
			(stroke
				(width 0.0254)
				(type default)
			)
			(layer "B.Fab")
		)
		(fp_line
			(start 0.254 -1.016)
			(end -0.508 -1.016)
			(stroke
				(width 0.0254)
				(type default)
			)
			(layer "B.Fab")
		)
		(fp_line
			(start -0.508 1.016)
			(end 0.508 1.016)
			(stroke
				(width 0.0254)
				(type default)
			)
			(layer "B.Fab")
		)
		(fp_line
			(start -0.508 -1.016)
			(end -0.508 1.016)
			(stroke
				(width 0.0254)
				(type default)
			)
			(layer "B.Fab")
		)
		(pad "1" smd custom
			(at 0 -0.500126)
			(size 0.127 0.127)
			(layers "B.Cu" "B.Mask" "B.Paste")
			(net "DDR_VDDQ")
			(options
				(clearance outline)
				(anchor circle)
			)
			(primitives
				(gr_poly
					(pts
						(xy -0.1778 0.254) (xy 0.1778 0.254) (xy 0.254 0.1778) (xy 0.254 -0.1778) (xy 0.1778 -0.254) (xy -0.1778 -0.254)
						(xy -0.254 -0.1778) (xy -0.254 0.1778)
					)
					(width 0)
					(fill yes)
				)
			)
		)
		(pad "2" smd custom
			(at 0 0.500126)
			(size 0.127 0.127)
			(layers "B.Cu" "B.Mask" "B.Paste")
			(net "GND")
			(options
				(clearance outline)
				(anchor circle)
			)
			(primitives
				(gr_poly
					(pts
						(xy -0.1778 0.254) (xy 0.1778 0.254) (xy 0.254 0.1778) (xy 0.254 -0.1778) (xy 0.1778 -0.254) (xy -0.1778 -0.254)
						(xy -0.254 -0.1778) (xy -0.254 0.1778)
					)
					(width 0)
					(fill yes)
				)
			)
		)
	)
	(footprint ""
		(layer "B.Cu")
		(at 43.237023 18.542)
		(property "Reference" "C273"
			(at 0 0 0)
			(layer "B.SilkS")
			(hide yes)
			(effects
				(font
					(size 1.27 1.27)
				)
				(justify mirror)
			)
		)
		(property "Value" ""
			(at 0 0 0)
			(layer "B.Fab")
			(effects
				(font
					(size 1.27 1.27)
				)
				(justify mirror)
			)
		)
		(duplicate_pad_numbers_are_jumpers no)
		(fp_circle
			(center 0 0)
			(end 0.104648 0)
			(stroke
				(width 0.1016)
				(type default)
			)
			(fill no)
			(layer "B.SilkS")
		)
		(fp_poly
			(pts
				(xy 0.381 -0.889) (xy 0.381 0.889) (xy -0.381 0.889) (xy -0.381 -0.889)
			)
			(stroke
				(width 0)
				(type default)
			)
			(fill no)
			(layer "B.CrtYd")
		)
		(fp_line
			(start -0.508 -1.016)
			(end -0.508 1.016)
			(stroke
				(width 0.0254)
				(type default)
			)
			(layer "B.Fab")
		)
		(fp_line
			(start -0.508 1.016)
			(end 0.508 1.016)
			(stroke
				(width 0.0254)
				(type default)
			)
			(layer "B.Fab")
		)
		(fp_line
			(start 0.254 -1.016)
			(end -0.508 -1.016)
			(stroke
				(width 0.0254)
				(type default)
			)
			(layer "B.Fab")
		)
		(fp_line
			(start 0.508 -1.016)
			(end 0.254 -1.016)
			(stroke
				(width 0.0254)
				(type default)
			)
			(layer "B.Fab")
		)
		(fp_line
			(start 0.508 1.016)
			(end 0.508 -1.016)
			(stroke
				(width 0.0254)
				(type default)
			)
			(layer "B.Fab")
		)
		(pad "1" smd custom
			(at 0 -0.500126 180)
			(size 0.127 0.127)
			(layers "B.Cu" "B.Mask" "B.Paste")
			(net "VDD_1.8V")
			(options
				(clearance outline)
				(anchor circle)
			)
			(primitives
				(gr_poly
					(pts
						(xy -0.1778 0.254) (xy 0.1778 0.254) (xy 0.254 0.1778) (xy 0.254 -0.1778) (xy 0.1778 -0.254) (xy -0.1778 -0.254)
						(xy -0.254 -0.1778) (xy -0.254 0.1778)
					)
					(width 0)
					(fill yes)
				)
			)
		)
		(pad "2" smd custom
			(at 0 0.500126 180)
			(size 0.127 0.127)
			(layers "B.Cu" "B.Mask" "B.Paste")
			(net "GND")
			(options
				(clearance outline)
				(anchor circle)
			)
			(primitives
				(gr_poly
					(pts
						(xy -0.1778 0.254) (xy 0.1778 0.254) (xy 0.254 0.1778) (xy 0.254 -0.1778) (xy 0.1778 -0.254) (xy -0.1778 -0.254)
						(xy -0.254 -0.1778) (xy -0.254 0.1778)
					)
					(width 0)
					(fill yes)
				)
			)
		)
	)
	(footprint ""
		(layer "B.Cu")
		(at 72.251011 5.898998)
		(property "Reference" "V_A-DQ13"
			(at 0 0 0)
			(layer "B.SilkS")
			(hide yes)
			(effects
				(font
					(size 1.27 1.27)
				)
				(justify mirror)
			)
		)
		(property "Value" ""
			(at 0 0 0)
			(layer "B.Fab")
			(effects
				(font
					(size 1.27 1.27)
				)
				(justify mirror)
			)
		)
		(duplicate_pad_numbers_are_jumpers no)
		(pad "1" thru_hole circle
			(at 0 0 180)
			(size 0.4572 0.4572)
			(drill 0.20574)
			(layers "*.Cu" "*.Mask")
			(remove_unused_layers no)
			(net "DDR0_32A_DQ13")
			(clearance 0.1143)
			(thermal_gap 0.1143)
		)
	)
	(footprint ""
		(layer "B.Cu")
		(at 60.736988 12.042013 90)
		(property "Reference" "R144"
			(at 0 0 90)
			(layer "B.SilkS")
			(hide yes)
			(effects
				(font
					(size 1.27 1.27)
				)
				(justify mirror)
			)
		)
		(property "Value" ""
			(at 0 0 90)
			(layer "B.Fab")
			(effects
				(font
					(size 1.27 1.27)
				)
				(justify mirror)
			)
		)
		(duplicate_pad_numbers_are_jumpers no)
		(fp_circle
			(center 0 0)
			(end 0 0.104648)
			(stroke
				(width 0.1016)
				(type default)
			)
			(fill no)
			(layer "B.SilkS")
		)
		(fp_poly
			(pts
				(xy 0.381 -0.889) (xy 0.381 0.889) (xy -0.381 0.889) (xy -0.381 -0.889)
			)
			(stroke
				(width 0)
				(type default)
			)
			(fill no)
			(layer "B.CrtYd")
		)
		(fp_line
			(start 0.508 -1.016)
			(end 0.254 -1.016)
			(stroke
				(width 0.0254)
				(type default)
			)
			(layer "B.Fab")
		)
		(fp_line
			(start 0.254 -1.016)
			(end -0.508 -1.016)
			(stroke
				(width 0.0254)
				(type default)
			)
			(layer "B.Fab")
		)
		(fp_line
			(start -0.508 -1.016)
			(end -0.508 1.016)
			(stroke
				(width 0.0254)
				(type default)
			)
			(layer "B.Fab")
		)
		(fp_line
			(start 0.508 1.016)
			(end 0.508 -1.016)
			(stroke
				(width 0.0254)
				(type default)
			)
			(layer "B.Fab")
		)
		(fp_line
			(start -0.508 1.016)
			(end 0.508 1.016)
			(stroke
				(width 0.0254)
				(type default)
			)
			(layer "B.Fab")
		)
		(pad "1" smd custom
			(at 0 -0.500126 270)
			(size 0.127 0.127)
			(layers "B.Cu" "B.Mask" "B.Paste")
			(net "VDD_CORE")
			(options
				(clearance outline)
				(anchor circle)
			)
			(primitives
				(gr_poly
					(pts
						(xy -0.1778 0.254) (xy 0.1778 0.254) (xy 0.254 0.1778) (xy 0.254 -0.1778) (xy 0.1778 -0.254) (xy -0.1778 -0.254)
						(xy -0.254 -0.1778) (xy -0.254 0.1778)
					)
					(width 0)
					(fill yes)
				)
			)
		)
		(pad "2" smd custom
			(at 0 0.500126 270)
			(size 0.127 0.127)
			(layers "B.Cu" "B.Mask" "B.Paste")
			(net "VDDA_DDR0_32A")
			(options
				(clearance outline)
				(anchor circle)
			)
			(primitives
				(gr_poly
					(pts
						(xy -0.1778 0.254) (xy 0.1778 0.254) (xy 0.254 0.1778) (xy 0.254 -0.1778) (xy 0.1778 -0.254) (xy -0.1778 -0.254)
						(xy -0.254 -0.1778) (xy -0.254 0.1778)
					)
					(width 0)
					(fill yes)
				)
			)
		)
	)
	(footprint ""
		(layer "B.Cu")
		(at 23.495 7.874)
		(property "Reference" "R26"
			(at 0 0 0)
			(layer "B.SilkS")
			(hide yes)
			(effects
				(font
					(size 1.27 1.27)
				)
				(justify mirror)
			)
		)
		(property "Value" "4.75K"
			(at 0.148158 1.3462 270)
			(unlocked yes)
			(layer "B.Fab")
			(hide yes)
			(effects
				(font
					(size 1.27 0.9652)
					(thickness 0.000001)
				)
				(justify left mirror)
			)
		)
		(property "Device Type" "REST4024"
			(at 0.148158 1.3462 270)
			(unlocked yes)
			(layer "B.Fab")
			(hide yes)
			(effects
				(font
					(size 1.27 0.9652)
					(thickness 0.000001)
				)
				(justify left mirror)
			)
		)
		(duplicate_pad_numbers_are_jumpers no)
		(fp_poly
			(pts
				(xy -0.635 1.0668) (xy -0.635 -1.0668) (xy 0.635 -1.0668) (xy 0.635 1.0668)
			)
			(stroke
				(width 0)
				(type default)
			)
			(fill no)
			(layer "B.CrtYd")
		)
		(fp_line
			(start -0.254 -0.508)
			(end -0.254 0.508)
			(stroke
				(width 0.0254)
				(type default)
			)
			(layer "B.Fab")
		)
		(fp_line
			(start -0.254 0.508)
			(end 0.254 0.508)
			(stroke
				(width 0.0254)
				(type default)
			)
			(layer "B.Fab")
		)
		(fp_line
			(start 0.254 -0.508)
			(end -0.254 -0.508)
			(stroke
				(width 0.0254)
				(type default)
			)
			(layer "B.Fab")
		)
		(fp_line
			(start 0.254 0.508)
			(end 0.254 -0.508)
			(stroke
				(width 0.0254)
				(type default)
			)
			(layer "B.Fab")
		)
		(pad "1" smd rect
			(at 0 -0.4191 180)
			(size 0.508 0.5334)
			(layers "B.Cu" "B.Mask" "B.Paste")
			(net "VDD_3.3V")
		)
		(pad "2" smd rect
			(at 0 0.4191 180)
			(size 0.508 0.5334)
			(layers "B.Cu" "B.Mask" "B.Paste")
			(net "NFP_CFG_SPI_FLASH_SCK")
		)
		(zone
			(layer "B.Cu")
			(hatch none 0.5)
			(connect_pads
				(clearance 0)
			)
			(min_thickness 0.25)
			(keepout
				(tracks not_allowed)
				(vias allowed)
				(pads allowed)
				(copperpour not_allowed)
				(footprints allowed)
			)
			(placement
				(enabled no)
				(sheetname "")
			)
			(fill
				(thermal_gap 0.5)
				(thermal_bridge_width 0.5)
				(island_removal_mode 0)
			)
			(polygon
				(pts
					(xy 23.4696 7.8486) (xy 23.4696 7.8994) (xy 23.5204 7.8994) (xy 23.5204 7.8486)
				)
			)
		)
	)
	(footprint ""
		(layer "B.Cu")
		(at 84.250987 25.813004)
		(property "Reference" "V3_A-A13"
			(at 0 0 0)
			(layer "B.SilkS")
			(hide yes)
			(effects
				(font
					(size 1.27 1.27)
				)
				(justify mirror)
			)
		)
		(property "Value" ""
			(at 0 0 0)
			(layer "B.Fab")
			(effects
				(font
					(size 1.27 1.27)
				)
				(justify mirror)
			)
		)
		(duplicate_pad_numbers_are_jumpers no)
		(pad "1" thru_hole circle
			(at 0 0 180)
			(size 0.4572 0.4572)
			(drill 0.20574)
			(layers "*.Cu" "*.Mask")
			(remove_unused_layers no)
			(net "DDR0_32A_A13")
			(clearance 0.1143)
			(thermal_gap 0.1143)
		)
	)
	(footprint ""
		(layer "B.Cu")
		(at 56.8452 35.56 -90)
		(property "Reference" "C11"
			(at -1.87833 -1.4478 0)
			(unlocked yes)
			(layer "B.SilkS")
			(effects
				(font
					(size 0.7874 0.5842)
					(thickness 0.127)
				)
				(justify left mirror)
			)
		)
		(property "Value" "22UF"
			(at 0.148158 1.7526 180)
			(unlocked yes)
			(layer "B.Fab")
			(hide yes)
			(effects
				(font
					(size 1.27 0.9652)
					(thickness 0.000001)
				)
				(justify left mirror)
			)
		)
		(property "Device Type" "CAPC0063"
			(at 0.148158 1.7526 180)
			(unlocked yes)
			(layer "B.Fab")
			(hide yes)
			(effects
				(font
					(size 1.27 0.9652)
					(thickness 0.000001)
				)
				(justify left mirror)
			)
		)
		(duplicate_pad_numbers_are_jumpers no)
		(fp_circle
			(center 0 0)
			(end 0 -0.127)
			(stroke
				(width 0.2032)
				(type default)
			)
			(fill no)
			(layer "B.SilkS")
		)
		(fp_poly
			(pts
				(xy -0.7874 -1.6637) (xy 0.7874 -1.6637) (xy 0.7874 1.6637) (xy -0.7874 1.6637)
			)
			(stroke
				(width 0)
				(type default)
			)
			(fill no)
			(layer "B.CrtYd")
		)
		(fp_line
			(start -0.4064 0.8128)
			(end 0.4064 0.8128)
			(stroke
				(width 0.0254)
				(type default)
			)
			(layer "B.Fab")
		)
		(fp_line
			(start 0.4064 0.8128)
			(end 0.4064 -0.7874)
			(stroke
				(width 0.0254)
				(type default)
			)
			(layer "B.Fab")
		)
		(fp_line
			(start -0.4064 -0.7874)
			(end -0.4064 0.8128)
			(stroke
				(width 0.0254)
				(type default)
			)
			(layer "B.Fab")
		)
		(fp_line
			(start 0.4064 -0.7874)
			(end -0.4064 -0.7874)
			(stroke
				(width 0.0254)
				(type default)
			)
			(layer "B.Fab")
		)
		(pad "1" smd rect
			(at 0 -0.8001 90)
			(size 0.8636 0.9652)
			(layers "B.Cu" "B.Mask" "B.Paste")
			(net "VDD_CORE")
		)
		(pad "2" smd rect
			(at 0 0.8001 90)
			(size 0.8636 0.9652)
			(layers "B.Cu" "B.Mask" "B.Paste")
			(net "GND")
		)
		(zone
			(layer "B.Cu")
			(hatch none 0.5)
			(connect_pads
				(clearance 0)
			)
			(min_thickness 0.25)
			(keepout
				(tracks not_allowed)
				(vias allowed)
				(pads allowed)
				(copperpour not_allowed)
				(footprints allowed)
			)
			(placement
				(enabled no)
				(sheetname "")
			)
			(fill
				(thermal_gap 0.5)
				(thermal_bridge_width 0.5)
				(island_removal_mode 0)
			)
			(polygon
				(pts
					(xy 57.0992 35.6235) (xy 57.0992 35.4965) (xy 56.5912 35.4965) (xy 56.5912 35.6235)
				)
			)
		)
	)
	(footprint ""
		(layer "B.Cu")
		(at 37.084 48.641)
		(property "Reference" "TP2"
			(at 2.13233 3.429 270)
			(unlocked yes)
			(layer "B.SilkS")
			(effects
				(font
					(size 0.7874 0.5842)
					(thickness 0.127)
				)
				(justify left mirror)
			)
		)
		(property "Value" "*"
			(at 0.4826 -0.14732 0)
			(unlocked yes)
			(layer "B.Fab")
			(hide yes)
			(effects
				(font
					(size 1.27 0.9652)
					(thickness 0.000001)
				)
				(justify left mirror)
			)
		)
		(property "Device Type" "TP_SMALL"
			(at 0.4826 -0.14732 0)
			(unlocked yes)
			(layer "B.Fab")
			(hide yes)
			(effects
				(font
					(size 1.27 0.9652)
					(thickness 0.000001)
				)
				(justify left mirror)
			)
		)
		(duplicate_pad_numbers_are_jumpers no)
		(fp_line
			(start -0.8636 -0.8636)
			(end 0.8636 -0.8636)
			(stroke
				(width 0.1524)
				(type default)
			)
			(layer "B.SilkS")
		)
		(fp_line
			(start -0.8636 0.8636)
			(end -0.8636 -0.8636)
			(stroke
				(width 0.1524)
				(type default)
			)
			(layer "B.SilkS")
		)
		(fp_line
			(start 0.8636 -0.8636)
			(end 0.8636 0.8636)
			(stroke
				(width 0.1524)
				(type default)
			)
			(layer "B.SilkS")
		)
		(fp_line
			(start 0.8636 0.8636)
			(end -0.8636 0.8636)
			(stroke
				(width 0.1524)
				(type default)
			)
			(layer "B.SilkS")
		)
		(fp_poly
			(pts
				(xy 0.635 -0.635) (xy 0.635 0.635) (xy -0.635 0.635) (xy -0.635 -0.635)
			)
			(stroke
				(width 0)
				(type default)
			)
			(fill no)
			(layer "B.CrtYd")
		)
		(pad "1" smd rect
			(at 0 0 180)
			(size 1.27 1.27)
			(layers "B.Cu" "B.Mask" "B.Paste")
			(net "CNTRL_SPI_MOSI")
		)
	)
	(footprint ""
		(layer "B.Cu")
		(at 83.450989 7.498994)
		(property "Reference" "V1_A-A06"
			(at 0 0 0)
			(layer "B.SilkS")
			(hide yes)
			(effects
				(font
					(size 1.27 1.27)
				)
				(justify mirror)
			)
		)
		(property "Value" ""
			(at 0 0 0)
			(layer "B.Fab")
			(effects
				(font
					(size 1.27 1.27)
				)
				(justify mirror)
			)
		)
		(duplicate_pad_numbers_are_jumpers no)
		(pad "1" thru_hole circle
			(at 0 0 180)
			(size 0.4572 0.4572)
			(drill 0.20574)
			(layers "*.Cu" "*.Mask")
			(remove_unused_layers no)
			(net "DDR0_32A_A6")
			(clearance 0.1143)
			(thermal_gap 0.1143)
		)
	)
	(footprint ""
		(layer "B.Cu")
		(at 5.334 12.827 180)
		(property "Reference" "C285"
			(at -1.62433 -1.778 270)
			(unlocked yes)
			(layer "B.SilkS")
			(effects
				(font
					(size 0.7874 0.5842)
					(thickness 0.127)
				)
				(justify left mirror)
			)
		)
		(property "Value" "0.1UF"
			(at 0.091846 0.2921 90)
			(unlocked yes)
			(layer "B.Fab")
			(hide yes)
			(effects
				(font
					(size 0.7874 0.5842)
					(thickness 0.2032)
				)
				(justify left mirror)
			)
		)
		(property "Device Type" "CAPC0073"
			(at 0.091846 0.2921 90)
			(unlocked yes)
			(layer "B.Fab")
			(hide yes)
			(effects
				(font
					(size 0.7874 0.5842)
					(thickness 0.2032)
				)
				(justify left mirror)
			)
		)
		(duplicate_pad_numbers_are_jumpers no)
		(fp_poly
			(pts
				(xy -0.635 1.0668) (xy -0.635 -1.0668) (xy 0.635 -1.0668) (xy 0.635 1.0668)
			)
			(stroke
				(width 0)
				(type default)
			)
			(fill no)
			(layer "B.CrtYd")
		)
		(fp_line
			(start 0.254 0.508)
			(end 0.254 -0.508)
			(stroke
				(width 0.0254)
				(type default)
			)
			(layer "B.Fab")
		)
		(fp_line
			(start 0.254 -0.508)
			(end -0.254 -0.508)
			(stroke
				(width 0.0254)
				(type default)
			)
			(layer "B.Fab")
		)
		(fp_line
			(start -0.254 0.508)
			(end 0.254 0.508)
			(stroke
				(width 0.0254)
				(type default)
			)
			(layer "B.Fab")
		)
		(fp_line
			(start -0.254 -0.508)
			(end -0.254 0.508)
			(stroke
				(width 0.0254)
				(type default)
			)
			(layer "B.Fab")
		)
		(pad "1" smd rect
			(at 0 -0.4191)
			(size 0.508 0.5334)
			(layers "B.Cu" "B.Mask" "B.Paste")
			(net "EXT_3.3V")
		)
		(pad "2" smd rect
			(at 0 0.4191)
			(size 0.508 0.5334)
			(layers "B.Cu" "B.Mask" "B.Paste")
			(net "GND")
		)
		(zone
			(layer "B.Cu")
			(hatch none 0.5)
			(connect_pads
				(clearance 0)
			)
			(min_thickness 0.25)
			(keepout
				(tracks not_allowed)
				(vias allowed)
				(pads allowed)
				(copperpour not_allowed)
				(footprints allowed)
			)
			(placement
				(enabled no)
				(sheetname "")
			)
			(fill
				(thermal_gap 0.5)
				(thermal_bridge_width 0.5)
				(island_removal_mode 0)
			)
			(polygon
				(pts
					(xy 5.3594 12.8524) (xy 5.3594 12.8016) (xy 5.3086 12.8016) (xy 5.3086 12.8524)
				)
			)
		)
	)
	(footprint ""
		(layer "B.Cu")
		(at 43.737022 25.041987 90)
		(property "Reference" "C25"
			(at 0.123317 2.490978 0)
			(unlocked yes)
			(layer "B.SilkS")
			(effects
				(font
					(size 0.7874 0.5842)
					(thickness 0.127)
				)
				(justify mirror)
			)
		)
		(property "Value" ""
			(at 0 0 90)
			(layer "B.Fab")
			(effects
				(font
					(size 1.27 1.27)
				)
				(justify mirror)
			)
		)
		(duplicate_pad_numbers_are_jumpers no)
		(fp_circle
			(center 0 0)
			(end 0 0.104648)
			(stroke
				(width 0.1016)
				(type default)
			)
			(fill no)
			(layer "B.SilkS")
		)
		(fp_poly
			(pts
				(xy 0.381 -0.889) (xy 0.381 0.889) (xy -0.381 0.889) (xy -0.381 -0.889)
			)
			(stroke
				(width 0)
				(type default)
			)
			(fill no)
			(layer "B.CrtYd")
		)
		(fp_line
			(start 0.508 -1.016)
			(end 0.254 -1.016)
			(stroke
				(width 0.0254)
				(type default)
			)
			(layer "B.Fab")
		)
		(fp_line
			(start 0.254 -1.016)
			(end -0.508 -1.016)
			(stroke
				(width 0.0254)
				(type default)
			)
			(layer "B.Fab")
		)
		(fp_line
			(start -0.508 -1.016)
			(end -0.508 1.016)
			(stroke
				(width 0.0254)
				(type default)
			)
			(layer "B.Fab")
		)
		(fp_line
			(start 0.508 1.016)
			(end 0.508 -1.016)
			(stroke
				(width 0.0254)
				(type default)
			)
			(layer "B.Fab")
		)
		(fp_line
			(start -0.508 1.016)
			(end 0.508 1.016)
			(stroke
				(width 0.0254)
				(type default)
			)
			(layer "B.Fab")
		)
		(pad "1" smd custom
			(at 0 -0.500126 270)
			(size 0.127 0.127)
			(layers "B.Cu" "B.Mask" "B.Paste")
			(net "VDDA_PLL")
			(options
				(clearance outline)
				(anchor circle)
			)
			(primitives
				(gr_poly
					(pts
						(xy -0.1778 0.254) (xy 0.1778 0.254) (xy 0.254 0.1778) (xy 0.254 -0.1778) (xy 0.1778 -0.254) (xy -0.1778 -0.254)
						(xy -0.254 -0.1778) (xy -0.254 0.1778)
					)
					(width 0)
					(fill yes)
				)
			)
		)
		(pad "2" smd custom
			(at 0 0.500126 270)
			(size 0.127 0.127)
			(layers "B.Cu" "B.Mask" "B.Paste")
			(net "GND")
			(options
				(clearance outline)
				(anchor circle)
			)
			(primitives
				(gr_poly
					(pts
						(xy -0.1778 0.254) (xy 0.1778 0.254) (xy 0.254 0.1778) (xy 0.254 -0.1778) (xy 0.1778 -0.254) (xy -0.1778 -0.254)
						(xy -0.254 -0.1778) (xy -0.254 0.1778)
					)
					(width 0)
					(fill yes)
				)
			)
		)
	)
	(footprint ""
		(layer "B.Cu")
		(at 58.236993 29.541978)
		(property "Reference" "C199"
			(at 0 0 0)
			(layer "B.SilkS")
			(hide yes)
			(effects
				(font
					(size 1.27 1.27)
				)
				(justify mirror)
			)
		)
		(property "Value" ""
			(at 0 0 0)
			(layer "B.Fab")
			(effects
				(font
					(size 1.27 1.27)
				)
				(justify mirror)
			)
		)
		(duplicate_pad_numbers_are_jumpers no)
		(fp_circle
			(center 0 0)
			(end 0.104648 0)
			(stroke
				(width 0.1016)
				(type default)
			)
			(fill no)
			(layer "B.SilkS")
		)
		(fp_poly
			(pts
				(xy 0.381 -0.889) (xy 0.381 0.889) (xy -0.381 0.889) (xy -0.381 -0.889)
			)
			(stroke
				(width 0)
				(type default)
			)
			(fill no)
			(layer "B.CrtYd")
		)
		(fp_line
			(start -0.508 -1.016)
			(end -0.508 1.016)
			(stroke
				(width 0.0254)
				(type default)
			)
			(layer "B.Fab")
		)
		(fp_line
			(start -0.508 1.016)
			(end 0.508 1.016)
			(stroke
				(width 0.0254)
				(type default)
			)
			(layer "B.Fab")
		)
		(fp_line
			(start 0.254 -1.016)
			(end -0.508 -1.016)
			(stroke
				(width 0.0254)
				(type default)
			)
			(layer "B.Fab")
		)
		(fp_line
			(start 0.508 -1.016)
			(end 0.254 -1.016)
			(stroke
				(width 0.0254)
				(type default)
			)
			(layer "B.Fab")
		)
		(fp_line
			(start 0.508 1.016)
			(end 0.508 -1.016)
			(stroke
				(width 0.0254)
				(type default)
			)
			(layer "B.Fab")
		)
		(pad "1" smd custom
			(at 0 -0.500126 180)
			(size 0.127 0.127)
			(layers "B.Cu" "B.Mask" "B.Paste")
			(net "VDD_CORE")
			(options
				(clearance outline)
				(anchor circle)
			)
			(primitives
				(gr_poly
					(pts
						(xy -0.1778 0.254) (xy 0.1778 0.254) (xy 0.254 0.1778) (xy 0.254 -0.1778) (xy 0.1778 -0.254) (xy -0.1778 -0.254)
						(xy -0.254 -0.1778) (xy -0.254 0.1778)
					)
					(width 0)
					(fill yes)
				)
			)
		)
		(pad "2" smd custom
			(at 0 0.500126 180)
			(size 0.127 0.127)
			(layers "B.Cu" "B.Mask" "B.Paste")
			(net "GND")
			(options
				(clearance outline)
				(anchor circle)
			)
			(primitives
				(gr_poly
					(pts
						(xy -0.1778 0.254) (xy 0.1778 0.254) (xy 0.254 0.1778) (xy 0.254 -0.1778) (xy 0.1778 -0.254) (xy -0.1778 -0.254)
						(xy -0.254 -0.1778) (xy -0.254 0.1778)
					)
					(width 0)
					(fill yes)
				)
			)
		)
	)
	(footprint ""
		(layer "B.Cu")
		(at 24.765 7.874)
		(property "Reference" "R27"
			(at 0.98933 -0.635 270)
			(unlocked yes)
			(layer "B.SilkS")
			(effects
				(font
					(size 0.7874 0.5842)
					(thickness 0.127)
				)
				(justify left mirror)
			)
		)
		(property "Value" "4.75K"
			(at 0.148158 1.3462 270)
			(unlocked yes)
			(layer "B.Fab")
			(hide yes)
			(effects
				(font
					(size 1.27 0.9652)
					(thickness 0.000001)
				)
				(justify left mirror)
			)
		)
		(property "Device Type" "REST4024"
			(at 0.148158 1.3462 270)
			(unlocked yes)
			(layer "B.Fab")
			(hide yes)
			(effects
				(font
					(size 1.27 0.9652)
					(thickness 0.000001)
				)
				(justify left mirror)
			)
		)
		(duplicate_pad_numbers_are_jumpers no)
		(fp_poly
			(pts
				(xy -0.635 1.0668) (xy -0.635 -1.0668) (xy 0.635 -1.0668) (xy 0.635 1.0668)
			)
			(stroke
				(width 0)
				(type default)
			)
			(fill no)
			(layer "B.CrtYd")
		)
		(fp_line
			(start -0.254 -0.508)
			(end -0.254 0.508)
			(stroke
				(width 0.0254)
				(type default)
			)
			(layer "B.Fab")
		)
		(fp_line
			(start -0.254 0.508)
			(end 0.254 0.508)
			(stroke
				(width 0.0254)
				(type default)
			)
			(layer "B.Fab")
		)
		(fp_line
			(start 0.254 -0.508)
			(end -0.254 -0.508)
			(stroke
				(width 0.0254)
				(type default)
			)
			(layer "B.Fab")
		)
		(fp_line
			(start 0.254 0.508)
			(end 0.254 -0.508)
			(stroke
				(width 0.0254)
				(type default)
			)
			(layer "B.Fab")
		)
		(pad "1" smd rect
			(at 0 -0.4191 180)
			(size 0.508 0.5334)
			(layers "B.Cu" "B.Mask" "B.Paste")
			(net "VDD_3.3V")
		)
		(pad "2" smd rect
			(at 0 0.4191 180)
			(size 0.508 0.5334)
			(layers "B.Cu" "B.Mask" "B.Paste")
			(net "NFP_CFG_SPI_FLASH_MOSI")
		)
		(zone
			(layer "B.Cu")
			(hatch none 0.5)
			(connect_pads
				(clearance 0)
			)
			(min_thickness 0.25)
			(keepout
				(tracks not_allowed)
				(vias allowed)
				(pads allowed)
				(copperpour not_allowed)
				(footprints allowed)
			)
			(placement
				(enabled no)
				(sheetname "")
			)
			(fill
				(thermal_gap 0.5)
				(thermal_bridge_width 0.5)
				(island_removal_mode 0)
			)
			(polygon
				(pts
					(xy 24.7396 7.8486) (xy 24.7396 7.8994) (xy 24.7904 7.8994) (xy 24.7904 7.8486)
				)
			)
		)
	)
	(footprint ""
		(layer "B.Cu")
		(at 81.850992 29.812996)
		(property "Reference" "V3_A-A12"
			(at 0 0 0)
			(layer "B.SilkS")
			(hide yes)
			(effects
				(font
					(size 1.27 1.27)
				)
				(justify mirror)
			)
		)
		(property "Value" ""
			(at 0 0 0)
			(layer "B.Fab")
			(effects
				(font
					(size 1.27 1.27)
				)
				(justify mirror)
			)
		)
		(duplicate_pad_numbers_are_jumpers no)
		(pad "1" thru_hole circle
			(at 0 0 180)
			(size 0.4572 0.4572)
			(drill 0.20574)
			(layers "*.Cu" "*.Mask")
			(remove_unused_layers no)
			(net "DDR0_32A_A12")
			(clearance 0.1143)
			(thermal_gap 0.1143)
		)
	)
	(footprint ""
		(layer "B.Cu")
		(at 83.450989 14.256004)
		(property "Reference" "V2_A-A09"
			(at 0 0 0)
			(layer "B.SilkS")
			(hide yes)
			(effects
				(font
					(size 1.27 1.27)
				)
				(justify mirror)
			)
		)
		(property "Value" ""
			(at 0 0 0)
			(layer "B.Fab")
			(effects
				(font
					(size 1.27 1.27)
				)
				(justify mirror)
			)
		)
		(duplicate_pad_numbers_are_jumpers no)
		(pad "1" thru_hole circle
			(at 0 0 180)
			(size 0.4572 0.4572)
			(drill 0.20574)
			(layers "*.Cu" "*.Mask")
			(remove_unused_layers no)
			(net "DDR0_32A_A9")
			(clearance 0.1143)
			(thermal_gap 0.1143)
		)
	)
	(footprint ""
		(layer "B.Cu")
		(at 31.1912 27.686 -90)
		(property "Reference" "C122"
			(at 0.40767 0.9652 0)
			(unlocked yes)
			(layer "B.SilkS")
			(effects
				(font
					(size 0.7874 0.5842)
					(thickness 0.127)
				)
				(justify left mirror)
			)
		)
		(property "Value" "0.1UF"
			(at 0.091846 0.2921 180)
			(unlocked yes)
			(layer "B.Fab")
			(hide yes)
			(effects
				(font
					(size 0.7874 0.5842)
					(thickness 0.2032)
				)
				(justify left mirror)
			)
		)
		(property "Device Type" "CAPC0073"
			(at 0.091846 0.2921 180)
			(unlocked yes)
			(layer "B.Fab")
			(hide yes)
			(effects
				(font
					(size 0.7874 0.5842)
					(thickness 0.2032)
				)
				(justify left mirror)
			)
		)
		(duplicate_pad_numbers_are_jumpers no)
		(fp_poly
			(pts
				(xy -0.635 1.0668) (xy -0.635 -1.0668) (xy 0.635 -1.0668) (xy 0.635 1.0668)
			)
			(stroke
				(width 0)
				(type default)
			)
			(fill no)
			(layer "B.CrtYd")
		)
		(fp_line
			(start -0.254 0.508)
			(end 0.254 0.508)
			(stroke
				(width 0.0254)
				(type default)
			)
			(layer "B.Fab")
		)
		(fp_line
			(start 0.254 0.508)
			(end 0.254 -0.508)
			(stroke
				(width 0.0254)
				(type default)
			)
			(layer "B.Fab")
		)
		(fp_line
			(start -0.254 -0.508)
			(end -0.254 0.508)
			(stroke
				(width 0.0254)
				(type default)
			)
			(layer "B.Fab")
		)
		(fp_line
			(start 0.254 -0.508)
			(end -0.254 -0.508)
			(stroke
				(width 0.0254)
				(type default)
			)
			(layer "B.Fab")
		)
		(pad "1" smd rect
			(at 0 -0.4191 90)
			(size 0.508 0.5334)
			(layers "B.Cu" "B.Mask" "B.Paste")
			(net "EXT_3.3V")
		)
		(pad "2" smd rect
			(at 0 0.4191 90)
			(size 0.508 0.5334)
			(layers "B.Cu" "B.Mask" "B.Paste")
			(net "GND")
		)
		(zone
			(layer "B.Cu")
			(hatch none 0.5)
			(connect_pads
				(clearance 0)
			)
			(min_thickness 0.25)
			(keepout
				(tracks not_allowed)
				(vias allowed)
				(pads allowed)
				(copperpour not_allowed)
				(footprints allowed)
			)
			(placement
				(enabled no)
				(sheetname "")
			)
			(fill
				(thermal_gap 0.5)
				(thermal_bridge_width 0.5)
				(island_removal_mode 0)
			)
			(polygon
				(pts
					(xy 31.2166 27.6606) (xy 31.1658 27.6606) (xy 31.1658 27.7114) (xy 31.2166 27.7114)
				)
			)
		)
	)
	(footprint ""
		(layer "B.Cu")
		(at 54.483 0.762 180)
		(property "Reference" "C145"
			(at 0.145212 0.8763 270)
			(unlocked yes)
			(layer "B.SilkS")
			(effects
				(font
					(size 0.7874 0.5842)
					(thickness 0.127)
				)
				(justify left mirror)
			)
		)
		(property "Value" "0.22UF"
			(at 0.091846 0.2921 90)
			(unlocked yes)
			(layer "B.Fab")
			(hide yes)
			(effects
				(font
					(size 0.7874 0.5842)
					(thickness 0.2032)
				)
				(justify left mirror)
			)
		)
		(property "Device Type" "CAPC0062"
			(at 0.091846 0.2921 90)
			(unlocked yes)
			(layer "B.Fab")
			(hide yes)
			(effects
				(font
					(size 0.7874 0.5842)
					(thickness 0.2032)
				)
				(justify left mirror)
			)
		)
		(duplicate_pad_numbers_are_jumpers no)
		(fp_poly
			(pts
				(xy -0.635 1.0668) (xy -0.635 -1.0668) (xy 0.635 -1.0668) (xy 0.635 1.0668)
			)
			(stroke
				(width 0)
				(type default)
			)
			(fill no)
			(layer "B.CrtYd")
		)
		(fp_line
			(start 0.254 0.508)
			(end 0.254 -0.508)
			(stroke
				(width 0.0254)
				(type default)
			)
			(layer "B.Fab")
		)
		(fp_line
			(start 0.254 -0.508)
			(end -0.254 -0.508)
			(stroke
				(width 0.0254)
				(type default)
			)
			(layer "B.Fab")
		)
		(fp_line
			(start -0.254 0.508)
			(end 0.254 0.508)
			(stroke
				(width 0.0254)
				(type default)
			)
			(layer "B.Fab")
		)
		(fp_line
			(start -0.254 -0.508)
			(end -0.254 0.508)
			(stroke
				(width 0.0254)
				(type default)
			)
			(layer "B.Fab")
		)
		(pad "1" smd rect
			(at 0 -0.4191)
			(size 0.508 0.5334)
			(layers "B.Cu" "B.Mask" "B.Paste")
			(net "_NFP_PCIE0_PER4_P")
		)
		(pad "2" smd rect
			(at 0 0.4191)
			(size 0.508 0.5334)
			(layers "B.Cu" "B.Mask" "B.Paste")
			(net "NFP_PCIE0_PER4_P")
		)
		(zone
			(layer "B.Cu")
			(hatch none 0.5)
			(connect_pads
				(clearance 0)
			)
			(min_thickness 0.25)
			(keepout
				(tracks not_allowed)
				(vias allowed)
				(pads allowed)
				(copperpour not_allowed)
				(footprints allowed)
			)
			(placement
				(enabled no)
				(sheetname "")
			)
			(fill
				(thermal_gap 0.5)
				(thermal_bridge_width 0.5)
				(island_removal_mode 0)
			)
			(polygon
				(pts
					(xy 54.5084 0.7874) (xy 54.5084 0.7366) (xy 54.4576 0.7366) (xy 54.4576 0.7874)
				)
			)
		)
	)
	(footprint ""
		(layer "B.Cu")
		(at 33.655 32.639)
		(property "Reference" "R177"
			(at -0.02667 4.318 270)
			(unlocked yes)
			(layer "B.SilkS")
			(effects
				(font
					(size 0.7874 0.5842)
					(thickness 0.127)
				)
				(justify left mirror)
			)
		)
		(property "Value" "0"
			(at 0.148158 1.3462 270)
			(unlocked yes)
			(layer "B.Fab")
			(hide yes)
			(effects
				(font
					(size 1.27 0.9652)
					(thickness 0.000001)
				)
				(justify left mirror)
			)
		)
		(property "Device Type" "REST1111"
			(at 0.148158 1.3462 270)
			(unlocked yes)
			(layer "B.Fab")
			(hide yes)
			(effects
				(font
					(size 1.27 0.9652)
					(thickness 0.000001)
				)
				(justify left mirror)
			)
		)
		(duplicate_pad_numbers_are_jumpers no)
		(fp_poly
			(pts
				(xy -0.635 1.0668) (xy -0.635 -1.0668) (xy 0.635 -1.0668) (xy 0.635 1.0668)
			)
			(stroke
				(width 0)
				(type default)
			)
			(fill no)
			(layer "B.CrtYd")
		)
		(fp_line
			(start -0.254 -0.508)
			(end -0.254 0.508)
			(stroke
				(width 0.0254)
				(type default)
			)
			(layer "B.Fab")
		)
		(fp_line
			(start -0.254 0.508)
			(end 0.254 0.508)
			(stroke
				(width 0.0254)
				(type default)
			)
			(layer "B.Fab")
		)
		(fp_line
			(start 0.254 -0.508)
			(end -0.254 -0.508)
			(stroke
				(width 0.0254)
				(type default)
			)
			(layer "B.Fab")
		)
		(fp_line
			(start 0.254 0.508)
			(end 0.254 -0.508)
			(stroke
				(width 0.0254)
				(type default)
			)
			(layer "B.Fab")
		)
		(pad "1" smd rect
			(at 0 -0.4191 180)
			(size 0.508 0.5334)
			(layers "B.Cu" "B.Mask" "B.Paste")
			(net "NFP_CORE_VID5")
		)
		(pad "2" smd rect
			(at 0 0.4191 180)
			(size 0.508 0.5334)
			(layers "B.Cu" "B.Mask" "B.Paste")
			(net "_NFP_CORE_VID5")
		)
		(zone
			(layer "B.Cu")
			(hatch none 0.5)
			(connect_pads
				(clearance 0)
			)
			(min_thickness 0.25)
			(keepout
				(tracks not_allowed)
				(vias allowed)
				(pads allowed)
				(copperpour not_allowed)
				(footprints allowed)
			)
			(placement
				(enabled no)
				(sheetname "")
			)
			(fill
				(thermal_gap 0.5)
				(thermal_bridge_width 0.5)
				(island_removal_mode 0)
			)
			(polygon
				(pts
					(xy 33.6296 32.6136) (xy 33.6296 32.6644) (xy 33.6804 32.6644) (xy 33.6804 32.6136)
				)
			)
		)
	)
	(footprint ""
		(layer "B.Cu")
		(at 54.737 21.072094 -90)
		(property "Reference" "L7"
			(at -1.006094 -0.10033 270)
			(unlocked yes)
			(layer "B.SilkS")
			(effects
				(font
					(size 0.7874 0.5842)
					(thickness 0.127)
				)
				(justify left mirror)
			)
		)
		(property "Value" ""
			(at 0 0 90)
			(layer "B.Fab")
			(effects
				(font
					(size 1.27 1.27)
				)
				(justify mirror)
			)
		)
		(duplicate_pad_numbers_are_jumpers no)
		(fp_line
			(start -0.0254 0.127)
			(end 0.0254 0.127)
			(stroke
				(width 0.1016)
				(type default)
			)
			(layer "B.SilkS")
		)
		(fp_line
			(start 0.0254 0.127)
			(end 0.0254 -0.127)
			(stroke
				(width 0.1016)
				(type default)
			)
			(layer "B.SilkS")
		)
		(fp_line
			(start -0.0254 -0.127)
			(end -0.0254 0.127)
			(stroke
				(width 0.1016)
				(type default)
			)
			(layer "B.SilkS")
		)
		(fp_line
			(start 0.0254 -0.127)
			(end -0.0254 -0.127)
			(stroke
				(width 0.1016)
				(type default)
			)
			(layer "B.SilkS")
		)
		(fp_poly
			(pts
				(xy -0.889 -0.4953) (xy -0.889 0.4953) (xy 0.889 0.4953) (xy 0.889 -0.4953)
			)
			(stroke
				(width 0)
				(type default)
			)
			(fill no)
			(layer "B.CrtYd")
		)
		(fp_line
			(start -0.508 0.254)
			(end -0.508 -0.254)
			(stroke
				(width 0.0254)
				(type default)
			)
			(layer "B.Fab")
		)
		(fp_line
			(start 0.508 0.254)
			(end -0.508 0.254)
			(stroke
				(width 0.0254)
				(type default)
			)
			(layer "B.Fab")
		)
		(fp_line
			(start -0.508 -0.254)
			(end 0.508 -0.254)
			(stroke
				(width 0.0254)
				(type default)
			)
			(layer "B.Fab")
		)
		(fp_line
			(start 0.508 -0.254)
			(end 0.508 0.254)
			(stroke
				(width 0.0254)
				(type default)
			)
			(layer "B.Fab")
		)
		(pad "1" smd rect
			(at 0.4699 0 90)
			(size 0.5334 0.508)
			(layers "B.Cu" "B.Mask" "B.Paste")
			(net "DDR_1.8V")
		)
		(pad "2" smd rect
			(at -0.4699 0 90)
			(size 0.5334 0.508)
			(layers "B.Cu" "B.Mask" "B.Paste")
			(net "VDDA_DDR0_32A")
		)
	)
	(footprint ""
		(layer "B.Cu")
		(at 81.850992 19.055994)
		(property "Reference" "V2_A-BA1"
			(at 0 0 0)
			(layer "B.SilkS")
			(hide yes)
			(effects
				(font
					(size 1.27 1.27)
				)
				(justify mirror)
			)
		)
		(property "Value" ""
			(at 0 0 0)
			(layer "B.Fab")
			(effects
				(font
					(size 1.27 1.27)
				)
				(justify mirror)
			)
		)
		(duplicate_pad_numbers_are_jumpers no)
		(pad "1" thru_hole circle
			(at 0 0 180)
			(size 0.4572 0.4572)
			(drill 0.20574)
			(layers "*.Cu" "*.Mask")
			(remove_unused_layers no)
			(net "DDR0_32A_BA1")
			(clearance 0.1143)
			(thermal_gap 0.1143)
		)
	)
	(footprint ""
		(layer "B.Cu")
		(at 73.851008 2.699004)
		(property "Reference" "V_A-DM1"
			(at 0 0 0)
			(layer "B.SilkS")
			(hide yes)
			(effects
				(font
					(size 1.27 1.27)
				)
				(justify mirror)
			)
		)
		(property "Value" ""
			(at 0 0 0)
			(layer "B.Fab")
			(effects
				(font
					(size 1.27 1.27)
				)
				(justify mirror)
			)
		)
		(duplicate_pad_numbers_are_jumpers no)
		(pad "1" thru_hole circle
			(at 0 0 180)
			(size 0.4572 0.4572)
			(drill 0.20574)
			(layers "*.Cu" "*.Mask")
			(remove_unused_layers no)
			(net "DDR0_32A_DM1")
			(clearance 0.1143)
			(thermal_gap 0.1143)
		)
	)
	(footprint ""
		(layer "B.Cu")
		(at 33.401 28.321 180)
		(property "Reference" "R159"
			(at 0 0 0)
			(layer "B.SilkS")
			(hide yes)
			(effects
				(font
					(size 1.27 1.27)
				)
				(justify mirror)
			)
		)
		(property "Value" "0"
			(at 0.148158 1.3462 90)
			(unlocked yes)
			(layer "B.Fab")
			(hide yes)
			(effects
				(font
					(size 1.27 0.9652)
					(thickness 0.000001)
				)
				(justify left mirror)
			)
		)
		(property "Device Type" "REST1111"
			(at 0.148158 1.3462 90)
			(unlocked yes)
			(layer "B.Fab")
			(hide yes)
			(effects
				(font
					(size 1.27 0.9652)
					(thickness 0.000001)
				)
				(justify left mirror)
			)
		)
		(duplicate_pad_numbers_are_jumpers no)
		(fp_poly
			(pts
				(xy -0.635 1.0668) (xy -0.635 -1.0668) (xy 0.635 -1.0668) (xy 0.635 1.0668)
			)
			(stroke
				(width 0)
				(type default)
			)
			(fill no)
			(layer "B.CrtYd")
		)
		(fp_line
			(start 0.254 0.508)
			(end 0.254 -0.508)
			(stroke
				(width 0.0254)
				(type default)
			)
			(layer "B.Fab")
		)
		(fp_line
			(start 0.254 -0.508)
			(end -0.254 -0.508)
			(stroke
				(width 0.0254)
				(type default)
			)
			(layer "B.Fab")
		)
		(fp_line
			(start -0.254 0.508)
			(end 0.254 0.508)
			(stroke
				(width 0.0254)
				(type default)
			)
			(layer "B.Fab")
		)
		(fp_line
			(start -0.254 -0.508)
			(end -0.254 0.508)
			(stroke
				(width 0.0254)
				(type default)
			)
			(layer "B.Fab")
		)
		(pad "1" smd rect
			(at 0 -0.4191)
			(size 0.508 0.5334)
			(layers "B.Cu" "B.Mask" "B.Paste")
			(net "CPLD_PGRM_JTAG_TDI")
		)
		(pad "2" smd rect
			(at 0 0.4191)
			(size 0.508 0.5334)
			(layers "B.Cu" "B.Mask" "B.Paste")
			(net "CPLD_PGRM_JTAG_TDO")
		)
		(zone
			(layer "B.Cu")
			(hatch none 0.5)
			(connect_pads
				(clearance 0)
			)
			(min_thickness 0.25)
			(keepout
				(tracks not_allowed)
				(vias allowed)
				(pads allowed)
				(copperpour not_allowed)
				(footprints allowed)
			)
			(placement
				(enabled no)
				(sheetname "")
			)
			(fill
				(thermal_gap 0.5)
				(thermal_bridge_width 0.5)
				(island_removal_mode 0)
			)
			(polygon
				(pts
					(xy 33.4264 28.3464) (xy 33.4264 28.2956) (xy 33.3756 28.2956) (xy 33.3756 28.3464)
				)
			)
		)
	)
	(footprint ""
		(layer "B.Cu")
		(at 72.251011 15.056002)
		(property "Reference" "V_A-DQ29"
			(at 0 0 0)
			(layer "B.SilkS")
			(hide yes)
			(effects
				(font
					(size 1.27 1.27)
				)
				(justify mirror)
			)
		)
		(property "Value" ""
			(at 0 0 0)
			(layer "B.Fab")
			(effects
				(font
					(size 1.27 1.27)
				)
				(justify mirror)
			)
		)
		(duplicate_pad_numbers_are_jumpers no)
		(pad "1" thru_hole circle
			(at 0 0 180)
			(size 0.4572 0.4572)
			(drill 0.20574)
			(layers "*.Cu" "*.Mask")
			(remove_unused_layers no)
			(net "DDR0_32A_DQ29")
			(clearance 0.1143)
			(thermal_gap 0.1143)
		)
	)
	(footprint ""
		(layer "B.Cu")
		(at 73.851008 3.499002)
		(property "Reference" "V_A-DQ09"
			(at 0 0 0)
			(layer "B.SilkS")
			(hide yes)
			(effects
				(font
					(size 1.27 1.27)
				)
				(justify mirror)
			)
		)
		(property "Value" ""
			(at 0 0 0)
			(layer "B.Fab")
			(effects
				(font
					(size 1.27 1.27)
				)
				(justify mirror)
			)
		)
		(duplicate_pad_numbers_are_jumpers no)
		(pad "1" thru_hole circle
			(at 0 0 180)
			(size 0.4572 0.4572)
			(drill 0.20574)
			(layers "*.Cu" "*.Mask")
			(remove_unused_layers no)
			(net "DDR0_32A_DQ9")
			(clearance 0.1143)
			(thermal_gap 0.1143)
		)
	)
	(footprint ""
		(layer "B.Cu")
		(at 38.608 39.751)
		(property "Reference" "TP33"
			(at 1.524 1.55067 0)
			(unlocked yes)
			(layer "B.SilkS")
			(effects
				(font
					(size 0.7874 0.5842)
					(thickness 0.127)
				)
				(justify left mirror)
			)
		)
		(property "Value" "*"
			(at 0.4826 -0.14732 0)
			(unlocked yes)
			(layer "B.Fab")
			(hide yes)
			(effects
				(font
					(size 1.27 0.9652)
					(thickness 0.000001)
				)
				(justify left mirror)
			)
		)
		(property "Device Type" "TP_SMALL"
			(at 0.4826 -0.14732 0)
			(unlocked yes)
			(layer "B.Fab")
			(hide yes)
			(effects
				(font
					(size 1.27 0.9652)
					(thickness 0.000001)
				)
				(justify left mirror)
			)
		)
		(duplicate_pad_numbers_are_jumpers no)
		(fp_line
			(start -0.8636 -0.8636)
			(end 0.8636 -0.8636)
			(stroke
				(width 0.1524)
				(type default)
			)
			(layer "B.SilkS")
		)
		(fp_line
			(start -0.8636 0.8636)
			(end -0.8636 -0.8636)
			(stroke
				(width 0.1524)
				(type default)
			)
			(layer "B.SilkS")
		)
		(fp_line
			(start 0.8636 -0.8636)
			(end 0.8636 0.8636)
			(stroke
				(width 0.1524)
				(type default)
			)
			(layer "B.SilkS")
		)
		(fp_line
			(start 0.8636 0.8636)
			(end -0.8636 0.8636)
			(stroke
				(width 0.1524)
				(type default)
			)
			(layer "B.SilkS")
		)
		(fp_poly
			(pts
				(xy 0.635 -0.635) (xy 0.635 0.635) (xy -0.635 0.635) (xy -0.635 -0.635)
			)
			(stroke
				(width 0)
				(type default)
			)
			(fill no)
			(layer "B.CrtYd")
		)
		(pad "1" smd rect
			(at 0 0 180)
			(size 1.27 1.27)
			(layers "B.Cu" "B.Mask" "B.Paste")
			(net "GH_PHASE2")
		)
	)
	(footprint ""
		(layer "B.Cu")
		(at 39.237031 11.542014)
		(property "Reference" "R42"
			(at -0.909701 -0.493014 270)
			(unlocked yes)
			(layer "B.SilkS")
			(effects
				(font
					(size 0.7874 0.5842)
					(thickness 0.127)
				)
				(justify mirror)
			)
		)
		(property "Value" ""
			(at 0 0 0)
			(layer "B.Fab")
			(effects
				(font
					(size 1.27 1.27)
				)
				(justify mirror)
			)
		)
		(duplicate_pad_numbers_are_jumpers no)
		(fp_circle
			(center 0 0)
			(end 0.104648 0)
			(stroke
				(width 0.1016)
				(type default)
			)
			(fill no)
			(layer "B.SilkS")
		)
		(fp_poly
			(pts
				(xy 0.381 -0.889) (xy 0.381 0.889) (xy -0.381 0.889) (xy -0.381 -0.889)
			)
			(stroke
				(width 0)
				(type default)
			)
			(fill no)
			(layer "B.CrtYd")
		)
		(fp_line
			(start -0.508 -1.016)
			(end -0.508 1.016)
			(stroke
				(width 0.0254)
				(type default)
			)
			(layer "B.Fab")
		)
		(fp_line
			(start -0.508 1.016)
			(end 0.508 1.016)
			(stroke
				(width 0.0254)
				(type default)
			)
			(layer "B.Fab")
		)
		(fp_line
			(start 0.254 -1.016)
			(end -0.508 -1.016)
			(stroke
				(width 0.0254)
				(type default)
			)
			(layer "B.Fab")
		)
		(fp_line
			(start 0.508 -1.016)
			(end 0.254 -1.016)
			(stroke
				(width 0.0254)
				(type default)
			)
			(layer "B.Fab")
		)
		(fp_line
			(start 0.508 1.016)
			(end 0.508 -1.016)
			(stroke
				(width 0.0254)
				(type default)
			)
			(layer "B.Fab")
		)
		(pad "1" smd custom
			(at 0 -0.500126 180)
			(size 0.127 0.127)
			(layers "B.Cu" "B.Mask" "B.Paste")
			(net "VDD_3.3V")
			(options
				(clearance outline)
				(anchor circle)
			)
			(primitives
				(gr_poly
					(pts
						(xy -0.1778 0.254) (xy 0.1778 0.254) (xy 0.254 0.1778) (xy 0.254 -0.1778) (xy 0.1778 -0.254) (xy -0.1778 -0.254)
						(xy -0.254 -0.1778) (xy -0.254 0.1778)
					)
					(width 0)
					(fill yes)
				)
			)
		)
		(pad "2" smd custom
			(at 0 0.500126 180)
			(size 0.127 0.127)
			(layers "B.Cu" "B.Mask" "B.Paste")
			(net "PGRM_JTAG_TMS")
			(options
				(clearance outline)
				(anchor circle)
			)
			(primitives
				(gr_poly
					(pts
						(xy -0.1778 0.254) (xy 0.1778 0.254) (xy 0.254 0.1778) (xy 0.254 -0.1778) (xy 0.1778 -0.254) (xy -0.1778 -0.254)
						(xy -0.254 -0.1778) (xy -0.254 0.1778)
					)
					(width 0)
					(fill yes)
				)
			)
		)
	)
	(footprint ""
		(layer "B.Cu")
		(at 49.237011 9.542018)
		(property "Reference" "C171"
			(at 0 0 0)
			(layer "B.SilkS")
			(hide yes)
			(effects
				(font
					(size 1.27 1.27)
				)
				(justify mirror)
			)
		)
		(property "Value" ""
			(at 0 0 0)
			(layer "B.Fab")
			(effects
				(font
					(size 1.27 1.27)
				)
				(justify mirror)
			)
		)
		(duplicate_pad_numbers_are_jumpers no)
		(fp_circle
			(center 0 0)
			(end 0.104648 0)
			(stroke
				(width 0.1016)
				(type default)
			)
			(fill no)
			(layer "B.SilkS")
		)
		(fp_poly
			(pts
				(xy 0.381 -0.889) (xy 0.381 0.889) (xy -0.381 0.889) (xy -0.381 -0.889)
			)
			(stroke
				(width 0)
				(type default)
			)
			(fill no)
			(layer "B.CrtYd")
		)
		(fp_line
			(start -0.508 -1.016)
			(end -0.508 1.016)
			(stroke
				(width 0.0254)
				(type default)
			)
			(layer "B.Fab")
		)
		(fp_line
			(start -0.508 1.016)
			(end 0.508 1.016)
			(stroke
				(width 0.0254)
				(type default)
			)
			(layer "B.Fab")
		)
		(fp_line
			(start 0.254 -1.016)
			(end -0.508 -1.016)
			(stroke
				(width 0.0254)
				(type default)
			)
			(layer "B.Fab")
		)
		(fp_line
			(start 0.508 -1.016)
			(end 0.254 -1.016)
			(stroke
				(width 0.0254)
				(type default)
			)
			(layer "B.Fab")
		)
		(fp_line
			(start 0.508 1.016)
			(end 0.508 -1.016)
			(stroke
				(width 0.0254)
				(type default)
			)
			(layer "B.Fab")
		)
		(pad "1" smd custom
			(at 0 -0.500126 180)
			(size 0.127 0.127)
			(layers "B.Cu" "B.Mask" "B.Paste")
			(net "VDDA_SERDES")
			(options
				(clearance outline)
				(anchor circle)
			)
			(primitives
				(gr_poly
					(pts
						(xy -0.1778 0.254) (xy 0.1778 0.254) (xy 0.254 0.1778) (xy 0.254 -0.1778) (xy 0.1778 -0.254) (xy -0.1778 -0.254)
						(xy -0.254 -0.1778) (xy -0.254 0.1778)
					)
					(width 0)
					(fill yes)
				)
			)
		)
		(pad "2" smd custom
			(at 0 0.500126 180)
			(size 0.127 0.127)
			(layers "B.Cu" "B.Mask" "B.Paste")
			(net "GND")
			(options
				(clearance outline)
				(anchor circle)
			)
			(primitives
				(gr_poly
					(pts
						(xy -0.1778 0.254) (xy 0.1778 0.254) (xy 0.254 0.1778) (xy 0.254 -0.1778) (xy 0.1778 -0.254) (xy -0.1778 -0.254)
						(xy -0.254 -0.1778) (xy -0.254 0.1778)
					)
					(width 0)
					(fill yes)
				)
			)
		)
	)
	(footprint ""
		(layer "B.Cu")
		(at 84.250987 29.812996)
		(property "Reference" "V3_A-A14"
			(at 0 0 0)
			(layer "B.SilkS")
			(hide yes)
			(effects
				(font
					(size 1.27 1.27)
				)
				(justify mirror)
			)
		)
		(property "Value" ""
			(at 0 0 0)
			(layer "B.Fab")
			(effects
				(font
					(size 1.27 1.27)
				)
				(justify mirror)
			)
		)
		(duplicate_pad_numbers_are_jumpers no)
		(pad "1" thru_hole circle
			(at 0 0 180)
			(size 0.4572 0.4572)
			(drill 0.20574)
			(layers "*.Cu" "*.Mask")
			(remove_unused_layers no)
			(net "DDR0_32A_A14")
			(clearance 0.1143)
			(thermal_gap 0.1143)
		)
	)
	(footprint ""
		(layer "B.Cu")
		(at 37.4015 26.416)
		(property "Reference" "L13"
			(at 1.2065 -0.73533 0)
			(unlocked yes)
			(layer "B.SilkS")
			(effects
				(font
					(size 0.7874 0.5842)
					(thickness 0.127)
				)
				(justify left mirror)
			)
		)
		(property "Value" ""
			(at 0 0 0)
			(layer "B.Fab")
			(effects
				(font
					(size 1.27 1.27)
				)
				(justify mirror)
			)
		)
		(duplicate_pad_numbers_are_jumpers no)
		(fp_line
			(start -0.0254 -0.127)
			(end -0.0254 0.127)
			(stroke
				(width 0.1016)
				(type default)
			)
			(layer "B.SilkS")
		)
		(fp_line
			(start -0.0254 0.127)
			(end 0.0254 0.127)
			(stroke
				(width 0.1016)
				(type default)
			)
			(layer "B.SilkS")
		)
		(fp_line
			(start 0.0254 -0.127)
			(end -0.0254 -0.127)
			(stroke
				(width 0.1016)
				(type default)
			)
			(layer "B.SilkS")
		)
		(fp_line
			(start 0.0254 0.127)
			(end 0.0254 -0.127)
			(stroke
				(width 0.1016)
				(type default)
			)
			(layer "B.SilkS")
		)
		(fp_poly
			(pts
				(xy -0.889 -0.4953) (xy -0.889 0.4953) (xy 0.889 0.4953) (xy 0.889 -0.4953)
			)
			(stroke
				(width 0)
				(type default)
			)
			(fill no)
			(layer "B.CrtYd")
		)
		(fp_line
			(start -0.508 -0.254)
			(end 0.508 -0.254)
			(stroke
				(width 0.0254)
				(type default)
			)
			(layer "B.Fab")
		)
		(fp_line
			(start -0.508 0.254)
			(end -0.508 -0.254)
			(stroke
				(width 0.0254)
				(type default)
			)
			(layer "B.Fab")
		)
		(fp_line
			(start 0.508 -0.254)
			(end 0.508 0.254)
			(stroke
				(width 0.0254)
				(type default)
			)
			(layer "B.Fab")
		)
		(fp_line
			(start 0.508 0.254)
			(end -0.508 0.254)
			(stroke
				(width 0.0254)
				(type default)
			)
			(layer "B.Fab")
		)
		(pad "1" smd rect
			(at 0.4699 0 180)
			(size 0.5334 0.508)
			(layers "B.Cu" "B.Mask" "B.Paste")
			(net "VDD_1.5V")
		)
		(pad "2" smd rect
			(at -0.4699 0 180)
			(size 0.5334 0.508)
			(layers "B.Cu" "B.Mask" "B.Paste")
			(net "VDDA_PLL")
		)
	)
	(footprint ""
		(layer "B.Cu")
		(at 83.450989 25.813004)
		(property "Reference" "V3_A-A09"
			(at 0 0 0)
			(layer "B.SilkS")
			(hide yes)
			(effects
				(font
					(size 1.27 1.27)
				)
				(justify mirror)
			)
		)
		(property "Value" ""
			(at 0 0 0)
			(layer "B.Fab")
			(effects
				(font
					(size 1.27 1.27)
				)
				(justify mirror)
			)
		)
		(duplicate_pad_numbers_are_jumpers no)
		(pad "1" thru_hole circle
			(at 0 0 180)
			(size 0.4572 0.4572)
			(drill 0.20574)
			(layers "*.Cu" "*.Mask")
			(remove_unused_layers no)
			(net "DDR0_32A_A9")
			(clearance 0.1143)
			(thermal_gap 0.1143)
		)
	)
	(footprint ""
		(layer "B.Cu")
		(at 82.65099 25.013006)
		(property "Reference" "V3_A-A05"
			(at 0 0 0)
			(layer "B.SilkS")
			(hide yes)
			(effects
				(font
					(size 1.27 1.27)
				)
				(justify mirror)
			)
		)
		(property "Value" ""
			(at 0 0 0)
			(layer "B.Fab")
			(effects
				(font
					(size 1.27 1.27)
				)
				(justify mirror)
			)
		)
		(duplicate_pad_numbers_are_jumpers no)
		(pad "1" thru_hole circle
			(at 0 0 180)
			(size 0.4572 0.4572)
			(drill 0.20574)
			(layers "*.Cu" "*.Mask")
			(remove_unused_layers no)
			(net "DDR0_32A_A5")
			(clearance 0.1143)
			(thermal_gap 0.1143)
		)
	)
	(footprint ""
		(layer "B.Cu")
		(at 49.403 0.762 180)
		(property "Reference" "C151"
			(at 0.145212 0.8763 270)
			(unlocked yes)
			(layer "B.SilkS")
			(effects
				(font
					(size 0.7874 0.5842)
					(thickness 0.127)
				)
				(justify left mirror)
			)
		)
		(property "Value" "0.22UF"
			(at 0.091846 0.2921 90)
			(unlocked yes)
			(layer "B.Fab")
			(hide yes)
			(effects
				(font
					(size 0.7874 0.5842)
					(thickness 0.2032)
				)
				(justify left mirror)
			)
		)
		(property "Device Type" "CAPC0062"
			(at 0.091846 0.2921 90)
			(unlocked yes)
			(layer "B.Fab")
			(hide yes)
			(effects
				(font
					(size 0.7874 0.5842)
					(thickness 0.2032)
				)
				(justify left mirror)
			)
		)
		(duplicate_pad_numbers_are_jumpers no)
		(fp_poly
			(pts
				(xy -0.635 1.0668) (xy -0.635 -1.0668) (xy 0.635 -1.0668) (xy 0.635 1.0668)
			)
			(stroke
				(width 0)
				(type default)
			)
			(fill no)
			(layer "B.CrtYd")
		)
		(fp_line
			(start 0.254 0.508)
			(end 0.254 -0.508)
			(stroke
				(width 0.0254)
				(type default)
			)
			(layer "B.Fab")
		)
		(fp_line
			(start 0.254 -0.508)
			(end -0.254 -0.508)
			(stroke
				(width 0.0254)
				(type default)
			)
			(layer "B.Fab")
		)
		(fp_line
			(start -0.254 0.508)
			(end 0.254 0.508)
			(stroke
				(width 0.0254)
				(type default)
			)
			(layer "B.Fab")
		)
		(fp_line
			(start -0.254 -0.508)
			(end -0.254 0.508)
			(stroke
				(width 0.0254)
				(type default)
			)
			(layer "B.Fab")
		)
		(pad "1" smd rect
			(at 0 -0.4191)
			(size 0.508 0.5334)
			(layers "B.Cu" "B.Mask" "B.Paste")
			(net "_NFP_PCIE0_PER7_P")
		)
		(pad "2" smd rect
			(at 0 0.4191)
			(size 0.508 0.5334)
			(layers "B.Cu" "B.Mask" "B.Paste")
			(net "NFP_PCIE0_PER7_P")
		)
		(zone
			(layer "B.Cu")
			(hatch none 0.5)
			(connect_pads
				(clearance 0)
			)
			(min_thickness 0.25)
			(keepout
				(tracks not_allowed)
				(vias allowed)
				(pads allowed)
				(copperpour not_allowed)
				(footprints allowed)
			)
			(placement
				(enabled no)
				(sheetname "")
			)
			(fill
				(thermal_gap 0.5)
				(thermal_bridge_width 0.5)
				(island_removal_mode 0)
			)
			(polygon
				(pts
					(xy 49.4284 0.7874) (xy 49.4284 0.7366) (xy 49.3776 0.7366) (xy 49.3776 0.7874)
				)
			)
		)
	)
	(footprint ""
		(layer "B.Cu")
		(at 82.65099 14.256004)
		(property "Reference" "V2_A-A02"
			(at 0 0 0)
			(layer "B.SilkS")
			(hide yes)
			(effects
				(font
					(size 1.27 1.27)
				)
				(justify mirror)
			)
		)
		(property "Value" ""
			(at 0 0 0)
			(layer "B.Fab")
			(effects
				(font
					(size 1.27 1.27)
				)
				(justify mirror)
			)
		)
		(duplicate_pad_numbers_are_jumpers no)
		(pad "1" thru_hole circle
			(at 0 0 180)
			(size 0.4572 0.4572)
			(drill 0.20574)
			(layers "*.Cu" "*.Mask")
			(remove_unused_layers no)
			(net "DDR0_32A_A2")
			(clearance 0.1143)
			(thermal_gap 0.1143)
		)
	)
	(footprint ""
		(layer "B.Cu")
		(at 68.236973 17.542002 180)
		(property "Reference" "C76"
			(at -0.951357 -0.491998 270)
			(unlocked yes)
			(layer "B.SilkS")
			(effects
				(font
					(size 0.7874 0.5842)
					(thickness 0.127)
				)
				(justify mirror)
			)
		)
		(property "Value" ""
			(at 0 0 0)
			(layer "B.Fab")
			(effects
				(font
					(size 1.27 1.27)
				)
				(justify mirror)
			)
		)
		(duplicate_pad_numbers_are_jumpers no)
		(fp_circle
			(center 0 0)
			(end -0.104648 0)
			(stroke
				(width 0.1016)
				(type default)
			)
			(fill no)
			(layer "B.SilkS")
		)
		(fp_poly
			(pts
				(xy 0.381 -0.889) (xy 0.381 0.889) (xy -0.381 0.889) (xy -0.381 -0.889)
			)
			(stroke
				(width 0)
				(type default)
			)
			(fill no)
			(layer "B.CrtYd")
		)
		(fp_line
			(start 0.508 1.016)
			(end 0.508 -1.016)
			(stroke
				(width 0.0254)
				(type default)
			)
			(layer "B.Fab")
		)
		(fp_line
			(start 0.508 -1.016)
			(end 0.254 -1.016)
			(stroke
				(width 0.0254)
				(type default)
			)
			(layer "B.Fab")
		)
		(fp_line
			(start 0.254 -1.016)
			(end -0.508 -1.016)
			(stroke
				(width 0.0254)
				(type default)
			)
			(layer "B.Fab")
		)
		(fp_line
			(start -0.508 1.016)
			(end 0.508 1.016)
			(stroke
				(width 0.0254)
				(type default)
			)
			(layer "B.Fab")
		)
		(fp_line
			(start -0.508 -1.016)
			(end -0.508 1.016)
			(stroke
				(width 0.0254)
				(type default)
			)
			(layer "B.Fab")
		)
		(pad "1" smd custom
			(at 0 -0.500126)
			(size 0.127 0.127)
			(layers "B.Cu" "B.Mask" "B.Paste")
			(net "DDR_VDDQ")
			(options
				(clearance outline)
				(anchor circle)
			)
			(primitives
				(gr_poly
					(pts
						(xy -0.1778 0.254) (xy 0.1778 0.254) (xy 0.254 0.1778) (xy 0.254 -0.1778) (xy 0.1778 -0.254) (xy -0.1778 -0.254)
						(xy -0.254 -0.1778) (xy -0.254 0.1778)
					)
					(width 0)
					(fill yes)
				)
			)
		)
		(pad "2" smd custom
			(at 0 0.500126)
			(size 0.127 0.127)
			(layers "B.Cu" "B.Mask" "B.Paste")
			(net "GND")
			(options
				(clearance outline)
				(anchor circle)
			)
			(primitives
				(gr_poly
					(pts
						(xy -0.1778 0.254) (xy 0.1778 0.254) (xy 0.254 0.1778) (xy 0.254 -0.1778) (xy 0.1778 -0.254) (xy -0.1778 -0.254)
						(xy -0.254 -0.1778) (xy -0.254 0.1778)
					)
					(width 0)
					(fill yes)
				)
			)
		)
	)
	(footprint ""
		(layer "B.Cu")
		(at 37.592 21.971 -90)
		(property "Reference" "R204"
			(at 0 0 90)
			(layer "B.SilkS")
			(hide yes)
			(effects
				(font
					(size 1.27 1.27)
				)
				(justify mirror)
			)
		)
		(property "Value" "39.0"
			(at 0.148158 1.3462 180)
			(unlocked yes)
			(layer "B.Fab")
			(hide yes)
			(effects
				(font
					(size 1.27 0.9652)
					(thickness 0.000001)
				)
				(justify left mirror)
			)
		)
		(property "Device Type" "REST0108"
			(at 0.148158 1.3462 180)
			(unlocked yes)
			(layer "B.Fab")
			(hide yes)
			(effects
				(font
					(size 1.27 0.9652)
					(thickness 0.000001)
				)
				(justify left mirror)
			)
		)
		(duplicate_pad_numbers_are_jumpers no)
		(fp_poly
			(pts
				(xy -0.635 1.0668) (xy -0.635 -1.0668) (xy 0.635 -1.0668) (xy 0.635 1.0668)
			)
			(stroke
				(width 0)
				(type default)
			)
			(fill no)
			(layer "B.CrtYd")
		)
		(fp_line
			(start -0.254 0.508)
			(end 0.254 0.508)
			(stroke
				(width 0.0254)
				(type default)
			)
			(layer "B.Fab")
		)
		(fp_line
			(start 0.254 0.508)
			(end 0.254 -0.508)
			(stroke
				(width 0.0254)
				(type default)
			)
			(layer "B.Fab")
		)
		(fp_line
			(start -0.254 -0.508)
			(end -0.254 0.508)
			(stroke
				(width 0.0254)
				(type default)
			)
			(layer "B.Fab")
		)
		(fp_line
			(start 0.254 -0.508)
			(end -0.254 -0.508)
			(stroke
				(width 0.0254)
				(type default)
			)
			(layer "B.Fab")
		)
		(pad "1" smd rect
			(at 0 -0.4191 90)
			(size 0.508 0.5334)
			(layers "B.Cu" "B.Mask" "B.Paste")
			(net "_NFP_ARM_SPI_FLASH_SCK")
		)
		(pad "2" smd rect
			(at 0 0.4191 90)
			(size 0.508 0.5334)
			(layers "B.Cu" "B.Mask" "B.Paste")
			(net "NFP_ARM_SPI_FLASH_SCK")
		)
		(zone
			(layer "B.Cu")
			(hatch none 0.5)
			(connect_pads
				(clearance 0)
			)
			(min_thickness 0.25)
			(keepout
				(tracks not_allowed)
				(vias allowed)
				(pads allowed)
				(copperpour not_allowed)
				(footprints allowed)
			)
			(placement
				(enabled no)
				(sheetname "")
			)
			(fill
				(thermal_gap 0.5)
				(thermal_bridge_width 0.5)
				(island_removal_mode 0)
			)
			(polygon
				(pts
					(xy 37.6174 21.9456) (xy 37.5666 21.9456) (xy 37.5666 21.9964) (xy 37.6174 21.9964)
				)
			)
		)
	)
	(footprint ""
		(layer "B.Cu")
		(at 61.736986 15.042007 90)
		(property "Reference" "R283"
			(at 0 0 90)
			(layer "B.SilkS")
			(hide yes)
			(effects
				(font
					(size 1.27 1.27)
				)
				(justify mirror)
			)
		)
		(property "Value" ""
			(at 0 0 90)
			(layer "B.Fab")
			(effects
				(font
					(size 1.27 1.27)
				)
				(justify mirror)
			)
		)
		(duplicate_pad_numbers_are_jumpers no)
		(fp_circle
			(center 0 0)
			(end 0 0.104648)
			(stroke
				(width 0.1016)
				(type default)
			)
			(fill no)
			(layer "B.SilkS")
		)
		(fp_poly
			(pts
				(xy 0.381 -0.889) (xy 0.381 0.889) (xy -0.381 0.889) (xy -0.381 -0.889)
			)
			(stroke
				(width 0)
				(type default)
			)
			(fill no)
			(layer "B.CrtYd")
		)
		(fp_line
			(start 0.508 -1.016)
			(end 0.254 -1.016)
			(stroke
				(width 0.0254)
				(type default)
			)
			(layer "B.Fab")
		)
		(fp_line
			(start 0.254 -1.016)
			(end -0.508 -1.016)
			(stroke
				(width 0.0254)
				(type default)
			)
			(layer "B.Fab")
		)
		(fp_line
			(start -0.508 -1.016)
			(end -0.508 1.016)
			(stroke
				(width 0.0254)
				(type default)
			)
			(layer "B.Fab")
		)
		(fp_line
			(start 0.508 1.016)
			(end 0.508 -1.016)
			(stroke
				(width 0.0254)
				(type default)
			)
			(layer "B.Fab")
		)
		(fp_line
			(start -0.508 1.016)
			(end 0.508 1.016)
			(stroke
				(width 0.0254)
				(type default)
			)
			(layer "B.Fab")
		)
		(pad "1" smd custom
			(at 0 -0.500126 270)
			(size 0.127 0.127)
			(layers "B.Cu" "B.Mask" "B.Paste")
			(net "GND")
			(options
				(clearance outline)
				(anchor circle)
			)
			(primitives
				(gr_poly
					(pts
						(xy -0.1778 0.254) (xy 0.1778 0.254) (xy 0.254 0.1778) (xy 0.254 -0.1778) (xy 0.1778 -0.254) (xy -0.1778 -0.254)
						(xy -0.254 -0.1778) (xy -0.254 0.1778)
					)
					(width 0)
					(fill yes)
				)
			)
		)
		(pad "2" smd custom
			(at 0 0.500126 270)
			(size 0.127 0.127)
			(layers "B.Cu" "B.Mask" "B.Paste")
			(net "DDR0_32A_VREF")
			(options
				(clearance outline)
				(anchor circle)
			)
			(primitives
				(gr_poly
					(pts
						(xy -0.1778 0.254) (xy 0.1778 0.254) (xy 0.254 0.1778) (xy 0.254 -0.1778) (xy 0.1778 -0.254) (xy -0.1778 -0.254)
						(xy -0.254 -0.1778) (xy -0.254 0.1778)
					)
					(width 0)
					(fill yes)
				)
			)
		)
	)
	(footprint ""
		(layer "B.Cu")
		(at 68.236973 6.542024)
		(property "Reference" "R146"
			(at -1.207643 0.823976 270)
			(unlocked yes)
			(layer "B.SilkS")
			(effects
				(font
					(size 0.7874 0.5842)
					(thickness 0.127)
				)
				(justify mirror)
			)
		)
		(property "Value" ""
			(at 0 0 0)
			(layer "B.Fab")
			(effects
				(font
					(size 1.27 1.27)
				)
				(justify mirror)
			)
		)
		(duplicate_pad_numbers_are_jumpers no)
		(fp_circle
			(center 0 0)
			(end 0.104648 0)
			(stroke
				(width 0.1016)
				(type default)
			)
			(fill no)
			(layer "B.SilkS")
		)
		(fp_poly
			(pts
				(xy 0.381 -0.889) (xy 0.381 0.889) (xy -0.381 0.889) (xy -0.381 -0.889)
			)
			(stroke
				(width 0)
				(type default)
			)
			(fill no)
			(layer "B.CrtYd")
		)
		(fp_line
			(start -0.508 -1.016)
			(end -0.508 1.016)
			(stroke
				(width 0.0254)
				(type default)
			)
			(layer "B.Fab")
		)
		(fp_line
			(start -0.508 1.016)
			(end 0.508 1.016)
			(stroke
				(width 0.0254)
				(type default)
			)
			(layer "B.Fab")
		)
		(fp_line
			(start 0.254 -1.016)
			(end -0.508 -1.016)
			(stroke
				(width 0.0254)
				(type default)
			)
			(layer "B.Fab")
		)
		(fp_line
			(start 0.508 -1.016)
			(end 0.254 -1.016)
			(stroke
				(width 0.0254)
				(type default)
			)
			(layer "B.Fab")
		)
		(fp_line
			(start 0.508 1.016)
			(end 0.508 -1.016)
			(stroke
				(width 0.0254)
				(type default)
			)
			(layer "B.Fab")
		)
		(pad "1" smd custom
			(at 0 -0.500126 180)
			(size 0.127 0.127)
			(layers "B.Cu" "B.Mask" "B.Paste")
			(net "GND")
			(options
				(clearance outline)
				(anchor circle)
			)
			(primitives
				(gr_poly
					(pts
						(xy -0.1778 0.254) (xy 0.1778 0.254) (xy 0.254 0.1778) (xy 0.254 -0.1778) (xy 0.1778 -0.254) (xy -0.1778 -0.254)
						(xy -0.254 -0.1778) (xy -0.254 0.1778)
					)
					(width 0)
					(fill yes)
				)
			)
		)
		(pad "2" smd custom
			(at 0 0.500126 180)
			(size 0.127 0.127)
			(layers "B.Cu" "B.Mask" "B.Paste")
			(net "DDR_VDDQ")
			(options
				(clearance outline)
				(anchor circle)
			)
			(primitives
				(gr_poly
					(pts
						(xy -0.1778 0.254) (xy 0.1778 0.254) (xy 0.254 0.1778) (xy 0.254 -0.1778) (xy 0.1778 -0.254) (xy -0.1778 -0.254)
						(xy -0.254 -0.1778) (xy -0.254 0.1778)
					)
					(width 0)
					(fill yes)
				)
			)
		)
	)
	(footprint ""
		(layer "B.Cu")
		(at 22.352 13.589)
		(property "Reference" "R24"
			(at 0 0 0)
			(layer "B.SilkS")
			(hide yes)
			(effects
				(font
					(size 1.27 1.27)
				)
				(justify mirror)
			)
		)
		(property "Value" "4.75K"
			(at 0.148158 1.3462 270)
			(unlocked yes)
			(layer "B.Fab")
			(hide yes)
			(effects
				(font
					(size 1.27 0.9652)
					(thickness 0.000001)
				)
				(justify left mirror)
			)
		)
		(property "Device Type" "REST4024"
			(at 0.148158 1.3462 270)
			(unlocked yes)
			(layer "B.Fab")
			(hide yes)
			(effects
				(font
					(size 1.27 0.9652)
					(thickness 0.000001)
				)
				(justify left mirror)
			)
		)
		(duplicate_pad_numbers_are_jumpers no)
		(fp_poly
			(pts
				(xy -0.635 1.0668) (xy -0.635 -1.0668) (xy 0.635 -1.0668) (xy 0.635 1.0668)
			)
			(stroke
				(width 0)
				(type default)
			)
			(fill no)
			(layer "B.CrtYd")
		)
		(fp_line
			(start -0.254 -0.508)
			(end -0.254 0.508)
			(stroke
				(width 0.0254)
				(type default)
			)
			(layer "B.Fab")
		)
		(fp_line
			(start -0.254 0.508)
			(end 0.254 0.508)
			(stroke
				(width 0.0254)
				(type default)
			)
			(layer "B.Fab")
		)
		(fp_line
			(start 0.254 -0.508)
			(end -0.254 -0.508)
			(stroke
				(width 0.0254)
				(type default)
			)
			(layer "B.Fab")
		)
		(fp_line
			(start 0.254 0.508)
			(end 0.254 -0.508)
			(stroke
				(width 0.0254)
				(type default)
			)
			(layer "B.Fab")
		)
		(pad "1" smd rect
			(at 0 -0.4191 180)
			(size 0.508 0.5334)
			(layers "B.Cu" "B.Mask" "B.Paste")
			(net "VDD_3.3V")
		)
		(pad "2" smd rect
			(at 0 0.4191 180)
			(size 0.508 0.5334)
			(layers "B.Cu" "B.Mask" "B.Paste")
			(net "NFP_CFG_SPI_FLASH_MISO")
		)
		(zone
			(layer "B.Cu")
			(hatch none 0.5)
			(connect_pads
				(clearance 0)
			)
			(min_thickness 0.25)
			(keepout
				(tracks not_allowed)
				(vias allowed)
				(pads allowed)
				(copperpour not_allowed)
				(footprints allowed)
			)
			(placement
				(enabled no)
				(sheetname "")
			)
			(fill
				(thermal_gap 0.5)
				(thermal_bridge_width 0.5)
				(island_removal_mode 0)
			)
			(polygon
				(pts
					(xy 22.3266 13.5636) (xy 22.3266 13.6144) (xy 22.3774 13.6144) (xy 22.3774 13.5636)
				)
			)
		)
	)
	(footprint ""
		(layer "B.Cu")
		(at 72.251011 17.455998)
		(property "Reference" "V_A-DQ26"
			(at 0 0 0)
			(layer "B.SilkS")
			(hide yes)
			(effects
				(font
					(size 1.27 1.27)
				)
				(justify mirror)
			)
		)
		(property "Value" ""
			(at 0 0 0)
			(layer "B.Fab")
			(effects
				(font
					(size 1.27 1.27)
				)
				(justify mirror)
			)
		)
		(duplicate_pad_numbers_are_jumpers no)
		(pad "1" thru_hole circle
			(at 0 0 180)
			(size 0.4572 0.4572)
			(drill 0.20574)
			(layers "*.Cu" "*.Mask")
			(remove_unused_layers no)
			(net "DDR0_32A_DQ26")
			(clearance 0.1143)
			(thermal_gap 0.1143)
		)
	)
	(footprint ""
		(layer "B.Cu")
		(at 74.651006 29.812996)
		(property "Reference" "V_A-DM4"
			(at 0 0 0)
			(layer "B.SilkS")
			(hide yes)
			(effects
				(font
					(size 1.27 1.27)
				)
				(justify mirror)
			)
		)
		(property "Value" ""
			(at 0 0 0)
			(layer "B.Fab")
			(effects
				(font
					(size 1.27 1.27)
				)
				(justify mirror)
			)
		)
		(duplicate_pad_numbers_are_jumpers no)
		(pad "1" thru_hole circle
			(at 0 0 180)
			(size 0.4572 0.4572)
			(drill 0.20574)
			(layers "*.Cu" "*.Mask")
			(remove_unused_layers no)
			(net "DDR0_32A_DM4")
			(clearance 0.1143)
			(thermal_gap 0.1143)
		)
	)
	(footprint ""
		(layer "B.Cu")
		(at 80.01 41.5036 180)
		(property "Reference" "C165"
			(at -0.635 1.34493 0)
			(unlocked yes)
			(layer "B.SilkS")
			(effects
				(font
					(size 0.7874 0.5842)
					(thickness 0.127)
				)
				(justify left mirror)
			)
		)
		(property "Value" "0.22UF"
			(at 0.091846 0.2921 90)
			(unlocked yes)
			(layer "B.Fab")
			(hide yes)
			(effects
				(font
					(size 0.7874 0.5842)
					(thickness 0.2032)
				)
				(justify left mirror)
			)
		)
		(property "Device Type" "CAPC0062"
			(at 0.091846 0.2921 90)
			(unlocked yes)
			(layer "B.Fab")
			(hide yes)
			(effects
				(font
					(size 0.7874 0.5842)
					(thickness 0.2032)
				)
				(justify left mirror)
			)
		)
		(duplicate_pad_numbers_are_jumpers no)
		(fp_poly
			(pts
				(xy -0.635 1.0668) (xy -0.635 -1.0668) (xy 0.635 -1.0668) (xy 0.635 1.0668)
			)
			(stroke
				(width 0)
				(type default)
			)
			(fill no)
			(layer "B.CrtYd")
		)
		(fp_line
			(start 0.254 0.508)
			(end 0.254 -0.508)
			(stroke
				(width 0.0254)
				(type default)
			)
			(layer "B.Fab")
		)
		(fp_line
			(start 0.254 -0.508)
			(end -0.254 -0.508)
			(stroke
				(width 0.0254)
				(type default)
			)
			(layer "B.Fab")
		)
		(fp_line
			(start -0.254 0.508)
			(end 0.254 0.508)
			(stroke
				(width 0.0254)
				(type default)
			)
			(layer "B.Fab")
		)
		(fp_line
			(start -0.254 -0.508)
			(end -0.254 0.508)
			(stroke
				(width 0.0254)
				(type default)
			)
			(layer "B.Fab")
		)
		(pad "1" smd rect
			(at 0 -0.4191)
			(size 0.508 0.5334)
			(layers "B.Cu" "B.Mask" "B.Paste")
			(net "11N2202")
		)
		(pad "2" smd rect
			(at 0 0.4191)
			(size 0.508 0.5334)
			(layers "B.Cu" "B.Mask" "B.Paste")
			(net "GND")
		)
		(zone
			(layer "B.Cu")
			(hatch none 0.5)
			(connect_pads
				(clearance 0)
			)
			(min_thickness 0.25)
			(keepout
				(tracks not_allowed)
				(vias allowed)
				(pads allowed)
				(copperpour not_allowed)
				(footprints allowed)
			)
			(placement
				(enabled no)
				(sheetname "")
			)
			(fill
				(thermal_gap 0.5)
				(thermal_bridge_width 0.5)
				(island_removal_mode 0)
			)
			(polygon
				(pts
					(xy 80.0354 41.529) (xy 80.0354 41.4782) (xy 79.9846 41.4782) (xy 79.9846 41.529)
				)
			)
		)
	)
	(footprint ""
		(layer "B.Cu")
		(at 40.737028 23.041991 90)
		(property "Reference" "C86"
			(at 1.425321 -0.605028 0)
			(unlocked yes)
			(layer "B.SilkS")
			(effects
				(font
					(size 0.7874 0.5842)
					(thickness 0.127)
				)
				(justify mirror)
			)
		)
		(property "Value" ""
			(at 0 0 90)
			(layer "B.Fab")
			(effects
				(font
					(size 1.27 1.27)
				)
				(justify mirror)
			)
		)
		(duplicate_pad_numbers_are_jumpers no)
		(fp_circle
			(center 0 0)
			(end 0 0.104648)
			(stroke
				(width 0.1016)
				(type default)
			)
			(fill no)
			(layer "B.SilkS")
		)
		(fp_poly
			(pts
				(xy 0.381 -0.889) (xy 0.381 0.889) (xy -0.381 0.889) (xy -0.381 -0.889)
			)
			(stroke
				(width 0)
				(type default)
			)
			(fill no)
			(layer "B.CrtYd")
		)
		(fp_line
			(start 0.508 -1.016)
			(end 0.254 -1.016)
			(stroke
				(width 0.0254)
				(type default)
			)
			(layer "B.Fab")
		)
		(fp_line
			(start 0.254 -1.016)
			(end -0.508 -1.016)
			(stroke
				(width 0.0254)
				(type default)
			)
			(layer "B.Fab")
		)
		(fp_line
			(start -0.508 -1.016)
			(end -0.508 1.016)
			(stroke
				(width 0.0254)
				(type default)
			)
			(layer "B.Fab")
		)
		(fp_line
			(start 0.508 1.016)
			(end 0.508 -1.016)
			(stroke
				(width 0.0254)
				(type default)
			)
			(layer "B.Fab")
		)
		(fp_line
			(start -0.508 1.016)
			(end 0.508 1.016)
			(stroke
				(width 0.0254)
				(type default)
			)
			(layer "B.Fab")
		)
		(pad "1" smd custom
			(at 0 -0.500126 270)
			(size 0.127 0.127)
			(layers "B.Cu" "B.Mask" "B.Paste")
			(net "VDDA_TS0")
			(options
				(clearance outline)
				(anchor circle)
			)
			(primitives
				(gr_poly
					(pts
						(xy -0.1778 0.254) (xy 0.1778 0.254) (xy 0.254 0.1778) (xy 0.254 -0.1778) (xy 0.1778 -0.254) (xy -0.1778 -0.254)
						(xy -0.254 -0.1778) (xy -0.254 0.1778)
					)
					(width 0)
					(fill yes)
				)
			)
		)
		(pad "2" smd custom
			(at 0 0.500126 270)
			(size 0.127 0.127)
			(layers "B.Cu" "B.Mask" "B.Paste")
			(net "GND")
			(options
				(clearance outline)
				(anchor circle)
			)
			(primitives
				(gr_poly
					(pts
						(xy -0.1778 0.254) (xy 0.1778 0.254) (xy 0.254 0.1778) (xy 0.254 -0.1778) (xy 0.1778 -0.254) (xy -0.1778 -0.254)
						(xy -0.254 -0.1778) (xy -0.254 0.1778)
					)
					(width 0)
					(fill yes)
				)
			)
		)
	)
	(footprint ""
		(layer "B.Cu")
		(at 1.2319 16.129 90)
		(property "Reference" "R386"
			(at -0.28067 -1.1049 0)
			(unlocked yes)
			(layer "B.SilkS")
			(effects
				(font
					(size 0.7874 0.5842)
					(thickness 0.127)
				)
				(justify left mirror)
			)
		)
		(property "Value" "0"
			(at 0.148158 1.3462 0)
			(unlocked yes)
			(layer "B.Fab")
			(hide yes)
			(effects
				(font
					(size 1.27 0.9652)
					(thickness 0.000001)
				)
				(justify left mirror)
			)
		)
		(property "Device Type" "REST1111"
			(at 0.148158 1.3462 0)
			(unlocked yes)
			(layer "B.Fab")
			(hide yes)
			(effects
				(font
					(size 1.27 0.9652)
					(thickness 0.000001)
				)
				(justify left mirror)
			)
		)
		(duplicate_pad_numbers_are_jumpers no)
		(fp_poly
			(pts
				(xy -0.635 1.0668) (xy -0.635 -1.0668) (xy 0.635 -1.0668) (xy 0.635 1.0668)
			)
			(stroke
				(width 0)
				(type default)
			)
			(fill no)
			(layer "B.CrtYd")
		)
		(fp_line
			(start 0.254 -0.508)
			(end -0.254 -0.508)
			(stroke
				(width 0.0254)
				(type default)
			)
			(layer "B.Fab")
		)
		(fp_line
			(start -0.254 -0.508)
			(end -0.254 0.508)
			(stroke
				(width 0.0254)
				(type default)
			)
			(layer "B.Fab")
		)
		(fp_line
			(start 0.254 0.508)
			(end 0.254 -0.508)
			(stroke
				(width 0.0254)
				(type default)
			)
			(layer "B.Fab")
		)
		(fp_line
			(start -0.254 0.508)
			(end 0.254 0.508)
			(stroke
				(width 0.0254)
				(type default)
			)
			(layer "B.Fab")
		)
		(pad "1" smd rect
			(at 0 -0.4191 270)
			(size 0.508 0.5334)
			(layers "B.Cu" "B.Mask" "B.Paste")
			(net "NWK0_I2C_SDA")
		)
		(pad "2" smd rect
			(at 0 0.4191 270)
			(size 0.508 0.5334)
			(layers "B.Cu" "B.Mask" "B.Paste")
			(net "MUX_NFP_GPIO1_NWK0_I2C_SDA")
		)
		(zone
			(layer "B.Cu")
			(hatch none 0.5)
			(connect_pads
				(clearance 0)
			)
			(min_thickness 0.25)
			(keepout
				(tracks not_allowed)
				(vias allowed)
				(pads allowed)
				(copperpour not_allowed)
				(footprints allowed)
			)
			(placement
				(enabled no)
				(sheetname "")
			)
			(fill
				(thermal_gap 0.5)
				(thermal_bridge_width 0.5)
				(island_removal_mode 0)
			)
			(polygon
				(pts
					(xy 1.2065 16.1544) (xy 1.2573 16.1544) (xy 1.2573 16.1036) (xy 1.2065 16.1036)
				)
			)
		)
	)
	(footprint ""
		(layer "B.Cu")
		(at 58.389012 0.762 180)
		(property "Reference" "C158"
			(at 0.145212 0.8763 270)
			(unlocked yes)
			(layer "B.SilkS")
			(effects
				(font
					(size 0.7874 0.5842)
					(thickness 0.127)
				)
				(justify left mirror)
			)
		)
		(property "Value" "0.22UF"
			(at 0.091846 0.2921 90)
			(unlocked yes)
			(layer "B.Fab")
			(hide yes)
			(effects
				(font
					(size 0.7874 0.5842)
					(thickness 0.2032)
				)
				(justify left mirror)
			)
		)
		(property "Device Type" "CAPC0062"
			(at 0.091846 0.2921 90)
			(unlocked yes)
			(layer "B.Fab")
			(hide yes)
			(effects
				(font
					(size 0.7874 0.5842)
					(thickness 0.2032)
				)
				(justify left mirror)
			)
		)
		(duplicate_pad_numbers_are_jumpers no)
		(fp_poly
			(pts
				(xy -0.635 1.0668) (xy -0.635 -1.0668) (xy 0.635 -1.0668) (xy 0.635 1.0668)
			)
			(stroke
				(width 0)
				(type default)
			)
			(fill no)
			(layer "B.CrtYd")
		)
		(fp_line
			(start 0.254 0.508)
			(end 0.254 -0.508)
			(stroke
				(width 0.0254)
				(type default)
			)
			(layer "B.Fab")
		)
		(fp_line
			(start 0.254 -0.508)
			(end -0.254 -0.508)
			(stroke
				(width 0.0254)
				(type default)
			)
			(layer "B.Fab")
		)
		(fp_line
			(start -0.254 0.508)
			(end 0.254 0.508)
			(stroke
				(width 0.0254)
				(type default)
			)
			(layer "B.Fab")
		)
		(fp_line
			(start -0.254 -0.508)
			(end -0.254 0.508)
			(stroke
				(width 0.0254)
				(type default)
			)
			(layer "B.Fab")
		)
		(pad "1" smd rect
			(at 0 -0.4191)
			(size 0.508 0.5334)
			(layers "B.Cu" "B.Mask" "B.Paste")
			(net "_NFP_PCIE0_PER2_N")
		)
		(pad "2" smd rect
			(at 0 0.4191)
			(size 0.508 0.5334)
			(layers "B.Cu" "B.Mask" "B.Paste")
			(net "NFP_PCIE0_PER2_N")
		)
		(zone
			(layer "B.Cu")
			(hatch none 0.5)
			(connect_pads
				(clearance 0)
			)
			(min_thickness 0.25)
			(keepout
				(tracks not_allowed)
				(vias allowed)
				(pads allowed)
				(copperpour not_allowed)
				(footprints allowed)
			)
			(placement
				(enabled no)
				(sheetname "")
			)
			(fill
				(thermal_gap 0.5)
				(thermal_bridge_width 0.5)
				(island_removal_mode 0)
			)
			(polygon
				(pts
					(xy 58.414412 0.7874) (xy 58.414412 0.7366) (xy 58.363612 0.7366) (xy 58.363612 0.7874)
				)
			)
		)
	)
	(footprint ""
		(layer "B.Cu")
		(at 26.289 10.414 90)
		(property "Reference" "R148"
			(at 0 0 90)
			(layer "B.SilkS")
			(hide yes)
			(effects
				(font
					(size 1.27 1.27)
				)
				(justify mirror)
			)
		)
		(property "Value" "0"
			(at 0.148158 1.3462 0)
			(unlocked yes)
			(layer "B.Fab")
			(hide yes)
			(effects
				(font
					(size 1.27 0.9652)
					(thickness 0.000001)
				)
				(justify left mirror)
			)
		)
		(property "Device Type" "REST1111"
			(at 0.148158 1.3462 0)
			(unlocked yes)
			(layer "B.Fab")
			(hide yes)
			(effects
				(font
					(size 1.27 0.9652)
					(thickness 0.000001)
				)
				(justify left mirror)
			)
		)
		(duplicate_pad_numbers_are_jumpers no)
		(fp_poly
			(pts
				(xy -0.635 1.0668) (xy -0.635 -1.0668) (xy 0.635 -1.0668) (xy 0.635 1.0668)
			)
			(stroke
				(width 0)
				(type default)
			)
			(fill no)
			(layer "B.CrtYd")
		)
		(fp_line
			(start 0.254 -0.508)
			(end -0.254 -0.508)
			(stroke
				(width 0.0254)
				(type default)
			)
			(layer "B.Fab")
		)
		(fp_line
			(start -0.254 -0.508)
			(end -0.254 0.508)
			(stroke
				(width 0.0254)
				(type default)
			)
			(layer "B.Fab")
		)
		(fp_line
			(start 0.254 0.508)
			(end 0.254 -0.508)
			(stroke
				(width 0.0254)
				(type default)
			)
			(layer "B.Fab")
		)
		(fp_line
			(start -0.254 0.508)
			(end 0.254 0.508)
			(stroke
				(width 0.0254)
				(type default)
			)
			(layer "B.Fab")
		)
		(pad "1" smd rect
			(at 0 -0.4191 270)
			(size 0.508 0.5334)
			(layers "B.Cu" "B.Mask" "B.Paste")
			(net "PGRM_JTAG_TDI")
		)
		(pad "2" smd rect
			(at 0 0.4191 270)
			(size 0.508 0.5334)
			(layers "B.Cu" "B.Mask" "B.Paste")
			(net "PGRM_JTAG_TDO")
		)
		(zone
			(layer "B.Cu")
			(hatch none 0.5)
			(connect_pads
				(clearance 0)
			)
			(min_thickness 0.25)
			(keepout
				(tracks not_allowed)
				(vias allowed)
				(pads allowed)
				(copperpour not_allowed)
				(footprints allowed)
			)
			(placement
				(enabled no)
				(sheetname "")
			)
			(fill
				(thermal_gap 0.5)
				(thermal_bridge_width 0.5)
				(island_removal_mode 0)
			)
			(polygon
				(pts
					(xy 26.2636 10.4394) (xy 26.3144 10.4394) (xy 26.3144 10.3886) (xy 26.2636 10.3886)
				)
			)
		)
	)
	(footprint ""
		(layer "B.Cu")
		(at 30.734 22.225 180)
		(property "Reference" "R55"
			(at 0 0 0)
			(layer "B.SilkS")
			(hide yes)
			(effects
				(font
					(size 1.27 1.27)
				)
				(justify mirror)
			)
		)
		(property "Value" "4.75K"
			(at 0.148158 1.3462 90)
			(unlocked yes)
			(layer "B.Fab")
			(hide yes)
			(effects
				(font
					(size 1.27 0.9652)
					(thickness 0.000001)
				)
				(justify left mirror)
			)
		)
		(property "Device Type" "REST4024"
			(at 0.148158 1.3462 90)
			(unlocked yes)
			(layer "B.Fab")
			(hide yes)
			(effects
				(font
					(size 1.27 0.9652)
					(thickness 0.000001)
				)
				(justify left mirror)
			)
		)
		(duplicate_pad_numbers_are_jumpers no)
		(fp_poly
			(pts
				(xy -0.635 1.0668) (xy -0.635 -1.0668) (xy 0.635 -1.0668) (xy 0.635 1.0668)
			)
			(stroke
				(width 0)
				(type default)
			)
			(fill no)
			(layer "B.CrtYd")
		)
		(fp_line
			(start 0.254 0.508)
			(end 0.254 -0.508)
			(stroke
				(width 0.0254)
				(type default)
			)
			(layer "B.Fab")
		)
		(fp_line
			(start 0.254 -0.508)
			(end -0.254 -0.508)
			(stroke
				(width 0.0254)
				(type default)
			)
			(layer "B.Fab")
		)
		(fp_line
			(start -0.254 0.508)
			(end 0.254 0.508)
			(stroke
				(width 0.0254)
				(type default)
			)
			(layer "B.Fab")
		)
		(fp_line
			(start -0.254 -0.508)
			(end -0.254 0.508)
			(stroke
				(width 0.0254)
				(type default)
			)
			(layer "B.Fab")
		)
		(pad "1" smd rect
			(at 0 -0.4191)
			(size 0.508 0.5334)
			(layers "B.Cu" "B.Mask" "B.Paste")
			(net "CPLD_VERSION_1")
		)
		(pad "2" smd rect
			(at 0 0.4191)
			(size 0.508 0.5334)
			(layers "B.Cu" "B.Mask" "B.Paste")
			(net "GND")
		)
		(zone
			(layer "B.Cu")
			(hatch none 0.5)
			(connect_pads
				(clearance 0)
			)
			(min_thickness 0.25)
			(keepout
				(tracks not_allowed)
				(vias allowed)
				(pads allowed)
				(copperpour not_allowed)
				(footprints allowed)
			)
			(placement
				(enabled no)
				(sheetname "")
			)
			(fill
				(thermal_gap 0.5)
				(thermal_bridge_width 0.5)
				(island_removal_mode 0)
			)
			(polygon
				(pts
					(xy 30.7594 22.2504) (xy 30.7594 22.1996) (xy 30.7086 22.1996) (xy 30.7086 22.2504)
				)
			)
		)
	)
	(footprint ""
		(layer "B.Cu")
		(at 83.450989 13.456006)
		(property "Reference" "V2_A-A07"
			(at 0 0 0)
			(layer "B.SilkS")
			(hide yes)
			(effects
				(font
					(size 1.27 1.27)
				)
				(justify mirror)
			)
		)
		(property "Value" ""
			(at 0 0 0)
			(layer "B.Fab")
			(effects
				(font
					(size 1.27 1.27)
				)
				(justify mirror)
			)
		)
		(duplicate_pad_numbers_are_jumpers no)
		(pad "1" thru_hole circle
			(at 0 0 180)
			(size 0.4572 0.4572)
			(drill 0.20574)
			(layers "*.Cu" "*.Mask")
			(remove_unused_layers no)
			(net "DDR0_32A_A7")
			(clearance 0.1143)
			(thermal_gap 0.1143)
		)
	)
	(footprint ""
		(layer "B.Cu")
		(at 5.207 8.001)
		(property "Reference" "TP27"
			(at 1.49733 0.508 270)
			(unlocked yes)
			(layer "B.SilkS")
			(effects
				(font
					(size 0.7874 0.5842)
					(thickness 0.127)
				)
				(justify left mirror)
			)
		)
		(property "Value" "*"
			(at 0.4826 -0.14732 0)
			(unlocked yes)
			(layer "B.Fab")
			(hide yes)
			(effects
				(font
					(size 1.27 0.9652)
					(thickness 0.000001)
				)
				(justify left mirror)
			)
		)
		(property "Device Type" "TP_SMALL"
			(at 0.4826 -0.14732 0)
			(unlocked yes)
			(layer "B.Fab")
			(hide yes)
			(effects
				(font
					(size 1.27 0.9652)
					(thickness 0.000001)
				)
				(justify left mirror)
			)
		)
		(duplicate_pad_numbers_are_jumpers no)
		(fp_line
			(start -0.8636 -0.8636)
			(end 0.8636 -0.8636)
			(stroke
				(width 0.1524)
				(type default)
			)
			(layer "B.SilkS")
		)
		(fp_line
			(start -0.8636 0.8636)
			(end -0.8636 -0.8636)
			(stroke
				(width 0.1524)
				(type default)
			)
			(layer "B.SilkS")
		)
		(fp_line
			(start 0.8636 -0.8636)
			(end 0.8636 0.8636)
			(stroke
				(width 0.1524)
				(type default)
			)
			(layer "B.SilkS")
		)
		(fp_line
			(start 0.8636 0.8636)
			(end -0.8636 0.8636)
			(stroke
				(width 0.1524)
				(type default)
			)
			(layer "B.SilkS")
		)
		(fp_poly
			(pts
				(xy 0.635 -0.635) (xy 0.635 0.635) (xy -0.635 0.635) (xy -0.635 -0.635)
			)
			(stroke
				(width 0)
				(type default)
			)
			(fill no)
			(layer "B.CrtYd")
		)
		(pad "1" smd rect
			(at 0 0 180)
			(size 1.27 1.27)
			(layers "B.Cu" "B.Mask" "B.Paste")
			(net "PGRM_JTAG_TCK")
		)
	)
	(footprint ""
		(layer "B.Cu")
		(at 63.119 41.0845)
		(property "Reference" "R116"
			(at 0.86233 2.6035 270)
			(unlocked yes)
			(layer "B.SilkS")
			(effects
				(font
					(size 0.7874 0.5842)
					(thickness 0.127)
				)
				(justify left mirror)
			)
		)
		(property "Value" "2.2"
			(at 0.148158 1.7526 270)
			(unlocked yes)
			(layer "B.Fab")
			(hide yes)
			(effects
				(font
					(size 1.27 0.9652)
					(thickness 0.000001)
				)
				(justify left mirror)
			)
		)
		(property "Device Type" "REST0145"
			(at 0.148158 1.7526 270)
			(unlocked yes)
			(layer "B.Fab")
			(hide yes)
			(effects
				(font
					(size 1.27 0.9652)
					(thickness 0.000001)
				)
				(justify left mirror)
			)
		)
		(duplicate_pad_numbers_are_jumpers no)
		(fp_circle
			(center 0 0)
			(end 0.127 0)
			(stroke
				(width 0.2032)
				(type default)
			)
			(fill no)
			(layer "B.SilkS")
		)
		(fp_poly
			(pts
				(xy -0.7874 -1.6637) (xy 0.7874 -1.6637) (xy 0.7874 1.6637) (xy -0.7874 1.6637)
			)
			(stroke
				(width 0)
				(type default)
			)
			(fill no)
			(layer "B.CrtYd")
		)
		(fp_line
			(start -0.4064 -0.8128)
			(end -0.4064 0.8128)
			(stroke
				(width 0.0254)
				(type default)
			)
			(layer "B.Fab")
		)
		(fp_line
			(start -0.4064 0.8128)
			(end 0.4064 0.8128)
			(stroke
				(width 0.0254)
				(type default)
			)
			(layer "B.Fab")
		)
		(fp_line
			(start 0.4064 -0.8128)
			(end -0.4064 -0.8128)
			(stroke
				(width 0.0254)
				(type default)
			)
			(layer "B.Fab")
		)
		(fp_line
			(start 0.4064 0.8128)
			(end 0.4064 -0.8128)
			(stroke
				(width 0.0254)
				(type default)
			)
			(layer "B.Fab")
		)
		(pad "1" smd rect
			(at 0 -0.8001 180)
			(size 0.762 0.9652)
			(layers "B.Cu" "B.Mask" "B.Paste")
			(net "10N2224")
		)
		(pad "2" smd rect
			(at 0 0.8001 180)
			(size 0.762 0.9652)
			(layers "B.Cu" "B.Mask" "B.Paste")
			(net "L_1_CORE_PHASE")
		)
		(zone
			(layer "B.Cu")
			(hatch none 0.5)
			(connect_pads
				(clearance 0)
			)
			(min_thickness 0.25)
			(keepout
				(tracks not_allowed)
				(vias allowed)
				(pads allowed)
				(copperpour not_allowed)
				(footprints allowed)
			)
			(placement
				(enabled no)
				(sheetname "")
			)
			(fill
				(thermal_gap 0.5)
				(thermal_bridge_width 0.5)
				(island_removal_mode 0)
			)
			(polygon
				(pts
					(xy 63.1825 40.8305) (xy 63.0555 40.8305) (xy 63.0555 41.3385) (xy 63.1825 41.3385)
				)
			)
		)
	)
	(footprint ""
		(layer "B.Cu")
		(at 40.259 39.751)
		(property "Reference" "TP31"
			(at 1.49733 0.254 270)
			(unlocked yes)
			(layer "B.SilkS")
			(effects
				(font
					(size 0.7874 0.5842)
					(thickness 0.127)
				)
				(justify left mirror)
			)
		)
		(property "Value" "*"
			(at 0.4826 -0.14732 0)
			(unlocked yes)
			(layer "B.Fab")
			(hide yes)
			(effects
				(font
					(size 1.27 0.9652)
					(thickness 0.000001)
				)
				(justify left mirror)
			)
		)
		(property "Device Type" "TP_SMALL"
			(at 0.4826 -0.14732 0)
			(unlocked yes)
			(layer "B.Fab")
			(hide yes)
			(effects
				(font
					(size 1.27 0.9652)
					(thickness 0.000001)
				)
				(justify left mirror)
			)
		)
		(duplicate_pad_numbers_are_jumpers no)
		(fp_line
			(start -0.8636 -0.8636)
			(end 0.8636 -0.8636)
			(stroke
				(width 0.1524)
				(type default)
			)
			(layer "B.SilkS")
		)
		(fp_line
			(start -0.8636 0.8636)
			(end -0.8636 -0.8636)
			(stroke
				(width 0.1524)
				(type default)
			)
			(layer "B.SilkS")
		)
		(fp_line
			(start 0.8636 -0.8636)
			(end 0.8636 0.8636)
			(stroke
				(width 0.1524)
				(type default)
			)
			(layer "B.SilkS")
		)
		(fp_line
			(start 0.8636 0.8636)
			(end -0.8636 0.8636)
			(stroke
				(width 0.1524)
				(type default)
			)
			(layer "B.SilkS")
		)
		(fp_poly
			(pts
				(xy 0.635 -0.635) (xy 0.635 0.635) (xy -0.635 0.635) (xy -0.635 -0.635)
			)
			(stroke
				(width 0)
				(type default)
			)
			(fill no)
			(layer "B.CrtYd")
		)
		(pad "1" smd rect
			(at 0 0 180)
			(size 1.27 1.27)
			(layers "B.Cu" "B.Mask" "B.Paste")
			(net "GL_PHASE2")
		)
	)
	(footprint ""
		(layer "B.Cu")
		(at 52.48656 0.762 180)
		(property "Reference" "C148"
			(at 0.145212 0.8763 270)
			(unlocked yes)
			(layer "B.SilkS")
			(effects
				(font
					(size 0.7874 0.5842)
					(thickness 0.127)
				)
				(justify left mirror)
			)
		)
		(property "Value" "0.22UF"
			(at 0.091846 0.2921 90)
			(unlocked yes)
			(layer "B.Fab")
			(hide yes)
			(effects
				(font
					(size 0.7874 0.5842)
					(thickness 0.2032)
				)
				(justify left mirror)
			)
		)
		(property "Device Type" "CAPC0062"
			(at 0.091846 0.2921 90)
			(unlocked yes)
			(layer "B.Fab")
			(hide yes)
			(effects
				(font
					(size 0.7874 0.5842)
					(thickness 0.2032)
				)
				(justify left mirror)
			)
		)
		(duplicate_pad_numbers_are_jumpers no)
		(fp_poly
			(pts
				(xy -0.635 1.0668) (xy -0.635 -1.0668) (xy 0.635 -1.0668) (xy 0.635 1.0668)
			)
			(stroke
				(width 0)
				(type default)
			)
			(fill no)
			(layer "B.CrtYd")
		)
		(fp_line
			(start 0.254 0.508)
			(end 0.254 -0.508)
			(stroke
				(width 0.0254)
				(type default)
			)
			(layer "B.Fab")
		)
		(fp_line
			(start 0.254 -0.508)
			(end -0.254 -0.508)
			(stroke
				(width 0.0254)
				(type default)
			)
			(layer "B.Fab")
		)
		(fp_line
			(start -0.254 0.508)
			(end 0.254 0.508)
			(stroke
				(width 0.0254)
				(type default)
			)
			(layer "B.Fab")
		)
		(fp_line
			(start -0.254 -0.508)
			(end -0.254 0.508)
			(stroke
				(width 0.0254)
				(type default)
			)
			(layer "B.Fab")
		)
		(pad "1" smd rect
			(at 0 -0.4191)
			(size 0.508 0.5334)
			(layers "B.Cu" "B.Mask" "B.Paste")
			(net "_NFP_PCIE0_PER5_N")
		)
		(pad "2" smd rect
			(at 0 0.4191)
			(size 0.508 0.5334)
			(layers "B.Cu" "B.Mask" "B.Paste")
			(net "NFP_PCIE0_PER5_N")
		)
		(zone
			(layer "B.Cu")
			(hatch none 0.5)
			(connect_pads
				(clearance 0)
			)
			(min_thickness 0.25)
			(keepout
				(tracks not_allowed)
				(vias allowed)
				(pads allowed)
				(copperpour not_allowed)
				(footprints allowed)
			)
			(placement
				(enabled no)
				(sheetname "")
			)
			(fill
				(thermal_gap 0.5)
				(thermal_bridge_width 0.5)
				(island_removal_mode 0)
			)
			(polygon
				(pts
					(xy 52.51196 0.7874) (xy 52.51196 0.7366) (xy 52.46116 0.7366) (xy 52.46116 0.7874)
				)
			)
		)
	)
	(footprint ""
		(layer "B.Cu")
		(at 56.388 0.762 180)
		(property "Reference" "C160"
			(at 0.145212 0.8763 270)
			(unlocked yes)
			(layer "B.SilkS")
			(effects
				(font
					(size 0.7874 0.5842)
					(thickness 0.127)
				)
				(justify left mirror)
			)
		)
		(property "Value" "0.22UF"
			(at 0.091846 0.2921 90)
			(unlocked yes)
			(layer "B.Fab")
			(hide yes)
			(effects
				(font
					(size 0.7874 0.5842)
					(thickness 0.2032)
				)
				(justify left mirror)
			)
		)
		(property "Device Type" "CAPC0062"
			(at 0.091846 0.2921 90)
			(unlocked yes)
			(layer "B.Fab")
			(hide yes)
			(effects
				(font
					(size 0.7874 0.5842)
					(thickness 0.2032)
				)
				(justify left mirror)
			)
		)
		(duplicate_pad_numbers_are_jumpers no)
		(fp_poly
			(pts
				(xy -0.635 1.0668) (xy -0.635 -1.0668) (xy 0.635 -1.0668) (xy 0.635 1.0668)
			)
			(stroke
				(width 0)
				(type default)
			)
			(fill no)
			(layer "B.CrtYd")
		)
		(fp_line
			(start 0.254 0.508)
			(end 0.254 -0.508)
			(stroke
				(width 0.0254)
				(type default)
			)
			(layer "B.Fab")
		)
		(fp_line
			(start 0.254 -0.508)
			(end -0.254 -0.508)
			(stroke
				(width 0.0254)
				(type default)
			)
			(layer "B.Fab")
		)
		(fp_line
			(start -0.254 0.508)
			(end 0.254 0.508)
			(stroke
				(width 0.0254)
				(type default)
			)
			(layer "B.Fab")
		)
		(fp_line
			(start -0.254 -0.508)
			(end -0.254 0.508)
			(stroke
				(width 0.0254)
				(type default)
			)
			(layer "B.Fab")
		)
		(pad "1" smd rect
			(at 0 -0.4191)
			(size 0.508 0.5334)
			(layers "B.Cu" "B.Mask" "B.Paste")
			(net "_NFP_PCIE0_PER3_N")
		)
		(pad "2" smd rect
			(at 0 0.4191)
			(size 0.508 0.5334)
			(layers "B.Cu" "B.Mask" "B.Paste")
			(net "NFP_PCIE0_PER3_N")
		)
		(zone
			(layer "B.Cu")
			(hatch none 0.5)
			(connect_pads
				(clearance 0)
			)
			(min_thickness 0.25)
			(keepout
				(tracks not_allowed)
				(vias allowed)
				(pads allowed)
				(copperpour not_allowed)
				(footprints allowed)
			)
			(placement
				(enabled no)
				(sheetname "")
			)
			(fill
				(thermal_gap 0.5)
				(thermal_bridge_width 0.5)
				(island_removal_mode 0)
			)
			(polygon
				(pts
					(xy 56.4134 0.7874) (xy 56.4134 0.7366) (xy 56.3626 0.7366) (xy 56.3626 0.7874)
				)
			)
		)
	)
	(footprint ""
		(layer "B.Cu")
		(at 67.818 40.64 90)
		(property "Reference" "U6"
			(at -4.5085 -0.508 0)
			(unlocked yes)
			(layer "B.SilkS")
			(effects
				(font
					(size 1.27 0.9652)
					(thickness 0.1524)
				)
				(justify left mirror)
			)
		)
		(property "Value" "*"
			(at 0.2921 1.813154 90)
			(unlocked yes)
			(layer "B.Fab")
			(hide yes)
			(effects
				(font
					(size 0.7874 0.5842)
					(thickness 0.2032)
				)
				(justify left mirror)
			)
		)
		(property "Device Type" "TRAN0026"
			(at 0.2921 1.813154 90)
			(unlocked yes)
			(layer "B.Fab")
			(hide yes)
			(effects
				(font
					(size 0.7874 0.5842)
					(thickness 0.2032)
				)
				(justify left mirror)
			)
		)
		(duplicate_pad_numbers_are_jumpers no)
		(fp_line
			(start 3.302 -3.302)
			(end 3.302 -2.667)
			(stroke
				(width 0.1524)
				(type default)
			)
			(layer "B.SilkS")
		)
		(fp_line
			(start 2.667 -3.302)
			(end 3.302 -3.302)
			(stroke
				(width 0.1524)
				(type default)
			)
			(layer "B.SilkS")
		)
		(fp_line
			(start -3.302 2.667)
			(end -3.302 3.302)
			(stroke
				(width 0.1524)
				(type default)
			)
			(layer "B.SilkS")
		)
		(fp_line
			(start -3.302 3.302)
			(end -2.667 3.302)
			(stroke
				(width 0.1524)
				(type default)
			)
			(layer "B.SilkS")
		)
		(fp_circle
			(center 3.81508 -2.4638)
			(end 3.81508 -2.179803)
			(stroke
				(width 0.1524)
				(type default)
			)
			(fill no)
			(layer "B.SilkS")
		)
		(fp_poly
			(pts
				(xy 0 -2.032) (xy 0 -0.127) (xy -0.889 -0.127) (xy -0.889 -2.032)
			)
			(stroke
				(width 0)
				(type default)
			)
			(fill yes)
			(layer "B.Paste")
		)
		(fp_poly
			(pts
				(xy -2.032 -2.032) (xy -2.032 -0.127) (xy -1.143 -0.127) (xy -1.143 -2.032)
			)
			(stroke
				(width 0)
				(type default)
			)
			(fill yes)
			(layer "B.Paste")
		)
		(fp_poly
			(pts
				(xy 0 2.032) (xy 0 0.127) (xy -0.889 0.127) (xy -0.889 2.032)
			)
			(stroke
				(width 0)
				(type default)
			)
			(fill yes)
			(layer "B.Paste")
		)
		(fp_poly
			(pts
				(xy -2.032 2.032) (xy -2.032 0.127) (xy -1.143 0.127) (xy -1.143 2.032)
			)
			(stroke
				(width 0)
				(type default)
			)
			(fill yes)
			(layer "B.Paste")
		)
		(fp_poly
			(pts
				(xy -3.937 -2.54) (xy -3.937 3.937) (xy 2.54 3.937) (xy 3.937 3.937) (xy 3.937 2.54) (xy 3.937 -3.937)
				(xy -2.54 -3.937) (xy -3.937 -3.937)
			)
			(stroke
				(width 0)
				(type default)
			)
			(fill no)
			(layer "B.CrtYd")
		)
		(fp_line
			(start 3.048 -3.048)
			(end 3.048 3.048)
			(stroke
				(width 0.1524)
				(type default)
			)
			(layer "B.Fab")
		)
		(fp_line
			(start -3.048 -3.048)
			(end 3.048 -3.048)
			(stroke
				(width 0.1524)
				(type default)
			)
			(layer "B.Fab")
		)
		(fp_line
			(start 3.048 3.048)
			(end -3.048 3.048)
			(stroke
				(width 0.1524)
				(type default)
			)
			(layer "B.Fab")
		)
		(fp_line
			(start -3.048 3.048)
			(end -3.048 -3.048)
			(stroke
				(width 0.1524)
				(type default)
			)
			(layer "B.Fab")
		)
		(fp_circle
			(center 2.413 -2.413)
			(end 2.413 -2.129003)
			(stroke
				(width 0.1524)
				(type default)
			)
			(fill no)
			(layer "B.Fab")
		)
		(fp_text user "40"
			(at 1.905 -4.09067 270)
			(unlocked yes)
			(layer "B.SilkS")
			(effects
				(font
					(size 0.7874 0.5842)
					(thickness 0.127)
				)
				(justify left mirror)
			)
		)
		(fp_text user "20"
			(at -2.31267 4.826 0)
			(unlocked yes)
			(layer "B.SilkS")
			(effects
				(font
					(size 0.7874 0.5842)
					(thickness 0.127)
				)
				(justify left mirror)
			)
		)
		(pad "1" smd custom
			(at 2.9464 -2.250008)
			(size 0.06985 0.06985)
			(layers "B.Cu" "B.Mask" "B.Paste")
			(net "10N2253")
			(options
				(clearance outline)
				(anchor circle)
			)
			(primitives
				(gr_poly
					(pts
						(xy -0.1397 -0.4064) (xy -0.1397 0.3302) (xy -0.0635 0.4064) (xy 0.1397 0.4064) (xy 0.1397 -0.4064)
					)
					(width 0)
					(fill yes)
				)
			)
		)
		(pad "2" smd rect
			(at 2.9464 -1.750009)
			(size 0.2794 0.8128)
			(layers "B.Cu" "B.Mask" "B.Paste")
			(net "VDD_5.0V")
		)
		(pad "3" smd rect
			(at 2.9464 -1.25001)
			(size 0.2794 0.8128)
			(layers "B.Cu" "B.Mask" "B.Paste")
			(net "10N2227")
		)
		(pad "4" smd rect
			(at 2.9464 -0.750011)
			(size 0.2794 0.8128)
			(layers "B.Cu" "B.Mask" "B.Paste")
			(net "10N2229")
		)
		(pad "5" smd rect
			(at 2.9464 -0.250012)
			(size 0.2794 0.8128)
			(layers "B.Cu" "B.Mask" "B.Paste")
			(net "GND")
		)
		(pad "6" smd rect
			(at 2.9464 0.250012)
			(size 0.2794 0.8128)
			(layers "B.Cu" "B.Mask" "B.Paste")
			(net "GH_PHASE1")
		)
		(pad "7" smd rect
			(at 2.9464 0.750011)
			(size 0.2794 0.8128)
			(layers "B.Cu" "B.Mask" "B.Paste")
			(net "10N2262")
		)
		(pad "8" smd rect
			(at 2.9464 1.25001)
			(size 0.2794 0.8128)
			(layers "B.Cu" "B.Mask" "B.Paste")
			(net "EXT_12.0V")
		)
		(pad "9" smd rect
			(at 2.9464 1.750009)
			(size 0.2794 0.8128)
			(layers "B.Cu" "B.Mask" "B.Paste")
			(net "EXT_12.0V")
		)
		(pad "10" smd custom
			(at 2.9464 2.250008)
			(size 0.06985 0.06985)
			(layers "B.Cu" "B.Mask" "B.Paste")
			(net "EXT_12.0V")
			(options
				(clearance outline)
				(anchor circle)
			)
			(primitives
				(gr_poly
					(pts
						(xy 0.1397 -0.4064) (xy 0.1397 0.3302) (xy 0.0635 0.4064) (xy -0.1397 0.4064) (xy -0.1397 -0.4064)
					)
					(width 0)
					(fill yes)
				)
			)
		)
		(pad "11" smd custom
			(at 2.250008 2.9464 270)
			(size 0.06985 0.06985)
			(layers "B.Cu" "B.Mask" "B.Paste")
			(net "EXT_12.0V")
			(options
				(clearance outline)
				(anchor circle)
			)
			(primitives
				(gr_poly
					(pts
						(xy -0.1397 -0.4064) (xy -0.1397 0.3302) (xy -0.0635 0.4064) (xy 0.1397 0.4064) (xy 0.1397 -0.4064)
					)
					(width 0)
					(fill yes)
				)
			)
		)
		(pad "12" smd rect
			(at 1.750009 2.9464 270)
			(size 0.2794 0.8128)
			(layers "B.Cu" "B.Mask" "B.Paste")
			(net "EXT_12.0V")
		)
		(pad "13" smd rect
			(at 1.25001 2.9464 270)
			(size 0.2794 0.8128)
			(layers "B.Cu" "B.Mask" "B.Paste")
			(net "EXT_12.0V")
		)
		(pad "14" smd rect
			(at 0.750011 2.9464 270)
			(size 0.2794 0.8128)
			(layers "B.Cu" "B.Mask" "B.Paste")
			(net "EXT_12.0V")
		)
		(pad "15" smd rect
			(at 0.250012 2.9464 270)
			(size 0.2794 0.8128)
			(layers "B.Cu" "B.Mask" "B.Paste")
			(net "L_1_CORE_PHASE")
		)
		(pad "16" smd rect
			(at -0.250012 2.9464 270)
			(size 0.2794 0.8128)
			(layers "B.Cu" "B.Mask" "B.Paste")
			(net "GND")
		)
		(pad "17" smd rect
			(at -0.750011 2.9464 270)
			(size 0.2794 0.8128)
			(layers "B.Cu" "B.Mask" "B.Paste")
			(net "GND")
		)
		(pad "18" smd rect
			(at -1.25001 2.9464 270)
			(size 0.2794 0.8128)
			(layers "B.Cu" "B.Mask" "B.Paste")
			(net "GND")
		)
		(pad "19" smd rect
			(at -1.750009 2.9464 270)
			(size 0.2794 0.8128)
			(layers "B.Cu" "B.Mask" "B.Paste")
			(net "GND")
		)
		(pad "20" smd custom
			(at -2.250008 2.9464 270)
			(size 0.06985 0.06985)
			(layers "B.Cu" "B.Mask" "B.Paste")
			(net "GND")
			(options
				(clearance outline)
				(anchor circle)
			)
			(primitives
				(gr_poly
					(pts
						(xy 0.1397 -0.4064) (xy 0.1397 0.3302) (xy 0.0635 0.4064) (xy -0.1397 0.4064) (xy -0.1397 -0.4064)
					)
					(width 0)
					(fill yes)
				)
			)
		)
		(pad "21" smd custom
			(at -2.9464 2.250008 180)
			(size 0.06985 0.06985)
			(layers "B.Cu" "B.Mask" "B.Paste")
			(net "GND")
			(options
				(clearance outline)
				(anchor circle)
			)
			(primitives
				(gr_poly
					(pts
						(xy -0.1397 -0.4064) (xy -0.1397 0.3302) (xy -0.0635 0.4064) (xy 0.1397 0.4064) (xy 0.1397 -0.4064)
					)
					(width 0)
					(fill yes)
				)
			)
		)
		(pad "22" smd rect
			(at -2.9464 1.750009 180)
			(size 0.2794 0.8128)
			(layers "B.Cu" "B.Mask" "B.Paste")
			(net "GND")
		)
		(pad "23" smd rect
			(at -2.9464 1.25001 180)
			(size 0.2794 0.8128)
			(layers "B.Cu" "B.Mask" "B.Paste")
			(net "GND")
		)
		(pad "24" smd rect
			(at -2.9464 0.750011 180)
			(size 0.2794 0.8128)
			(layers "B.Cu" "B.Mask" "B.Paste")
			(net "GND")
		)
		(pad "25" smd rect
			(at -2.9464 0.250012 180)
			(size 0.2794 0.8128)
			(layers "B.Cu" "B.Mask" "B.Paste")
			(net "GND")
		)
		(pad "26" smd rect
			(at -2.9464 -0.250012 180)
			(size 0.2794 0.8128)
			(layers "B.Cu" "B.Mask" "B.Paste")
			(net "GND")
		)
		(pad "27" smd rect
			(at -2.9464 -0.750011 180)
			(size 0.2794 0.8128)
			(layers "B.Cu" "B.Mask" "B.Paste")
			(net "GND")
		)
		(pad "28" smd rect
			(at -2.9464 -1.25001 180)
			(size 0.2794 0.8128)
			(layers "B.Cu" "B.Mask" "B.Paste")
			(net "GND")
		)
		(pad "29" smd rect
			(at -2.9464 -1.750009 180)
			(size 0.2794 0.8128)
			(layers "B.Cu" "B.Mask" "B.Paste")
			(net "L_1_CORE_PHASE")
		)
		(pad "30" smd custom
			(at -2.9464 -2.250008 180)
			(size 0.06985 0.06985)
			(layers "B.Cu" "B.Mask" "B.Paste")
			(net "L_1_CORE_PHASE")
			(options
				(clearance outline)
				(anchor circle)
			)
			(primitives
				(gr_poly
					(pts
						(xy 0.1397 -0.4064) (xy 0.1397 0.3302) (xy 0.0635 0.4064) (xy -0.1397 0.4064) (xy -0.1397 -0.4064)
					)
					(width 0)
					(fill yes)
				)
			)
		)
		(pad "31" smd custom
			(at -2.250008 -2.9464 90)
			(size 0.06985 0.06985)
			(layers "B.Cu" "B.Mask" "B.Paste")
			(net "L_1_CORE_PHASE")
			(options
				(clearance outline)
				(anchor circle)
			)
			(primitives
				(gr_poly
					(pts
						(xy -0.1397 -0.4064) (xy -0.1397 0.3302) (xy -0.0635 0.4064) (xy 0.1397 0.4064) (xy 0.1397 -0.4064)
					)
					(width 0)
					(fill yes)
				)
			)
		)
		(pad "32" smd rect
			(at -1.750009 -2.9464 90)
			(size 0.2794 0.8128)
			(layers "B.Cu" "B.Mask" "B.Paste")
			(net "L_1_CORE_PHASE")
		)
		(pad "33" smd rect
			(at -1.25001 -2.9464 90)
			(size 0.2794 0.8128)
			(layers "B.Cu" "B.Mask" "B.Paste")
			(net "L_1_CORE_PHASE")
		)
		(pad "34" smd rect
			(at -0.750011 -2.9464 90)
			(size 0.2794 0.8128)
			(layers "B.Cu" "B.Mask" "B.Paste")
			(net "L_1_CORE_PHASE")
		)
		(pad "35" smd rect
			(at -0.250012 -2.9464 90)
			(size 0.2794 0.8128)
			(layers "B.Cu" "B.Mask" "B.Paste")
			(net "L_1_CORE_PHASE")
		)
		(pad "36" smd rect
			(at 0.250012 -2.9464 90)
			(size 0.2794 0.8128)
			(layers "B.Cu" "B.Mask" "B.Paste")
			(net "GL_PHASE1")
		)
		(pad "37" smd rect
			(at 0.750011 -2.9464 90)
			(size 0.2794 0.8128)
			(layers "B.Cu" "B.Mask" "B.Paste")
			(net "GND")
		)
		(pad "38" smd rect
			(at 1.25001 -2.9464 90)
			(size 0.2794 0.8128)
			(layers "B.Cu" "B.Mask" "B.Paste")
			(net "CORE_FB_PH1_THERM_L")
		)
		(pad "39" smd rect
			(at 1.750009 -2.9464 90)
			(size 0.2794 0.8128)
			(layers "B.Cu" "B.Mask" "B.Paste")
			(net "10N2230")
		)
		(pad "40" smd custom
			(at 2.250008 -2.9464 90)
			(size 0.06985 0.06985)
			(layers "B.Cu" "B.Mask" "B.Paste")
			(net "NFP_CORE_PWM1")
			(options
				(clearance outline)
				(anchor circle)
			)
			(primitives
				(gr_poly
					(pts
						(xy 0.1397 -0.4064) (xy 0.1397 0.3302) (xy 0.0635 0.4064) (xy -0.1397 0.4064) (xy -0.1397 -0.4064)
					)
					(width 0)
					(fill yes)
				)
			)
		)
		(pad "41" smd rect
			(at 1.4478 -1.1938 270)
			(size 1.4986 2.0066)
			(layers "B.Cu" "B.Mask" "B.Paste")
			(net "GND")
		)
		(pad "42" smd rect
			(at 1.4478 1.1938 270)
			(size 1.4986 2.0066)
			(layers "B.Cu" "B.Mask" "B.Paste")
			(net "EXT_12.0V")
		)
		(pad "43" smd rect
			(at -1.0033 0 270)
			(size 2.3876 4.3942)
			(layers "B.Cu" "B.Mask" "B.Paste")
			(net "L_1_CORE_PHASE")
		)
		(zone
			(layer "B.Cu")
			(hatch none 0.5)
			(connect_pads
				(clearance 0)
			)
			(min_thickness 0.25)
			(keepout
				(tracks allowed)
				(vias not_allowed)
				(pads allowed)
				(copperpour not_allowed)
				(footprints allowed)
			)
			(placement
				(enabled no)
				(sheetname "")
			)
			(fill
				(thermal_gap 0.5)
				(thermal_bridge_width 0.5)
				(island_removal_mode 0)
			)
			(polygon
				(pts
					(arc
						(start 65.714397 36.82492)
						(mid 64.994003 36.82492)
						(end 65.714397 36.82492)
					)
				)
			)
		)
	)
	(footprint ""
		(layer "B.Cu")
		(at 36.7538 33.274 -90)
		(property "Reference" "R178"
			(at 0.28067 -4.2672 0)
			(unlocked yes)
			(layer "B.SilkS")
			(effects
				(font
					(size 0.7874 0.5842)
					(thickness 0.127)
				)
				(justify left mirror)
			)
		)
		(property "Value" "0"
			(at 0.148158 1.3462 180)
			(unlocked yes)
			(layer "B.Fab")
			(hide yes)
			(effects
				(font
					(size 1.27 0.9652)
					(thickness 0.000001)
				)
				(justify left mirror)
			)
		)
		(property "Device Type" "REST1111"
			(at 0.148158 1.3462 180)
			(unlocked yes)
			(layer "B.Fab")
			(hide yes)
			(effects
				(font
					(size 1.27 0.9652)
					(thickness 0.000001)
				)
				(justify left mirror)
			)
		)
		(duplicate_pad_numbers_are_jumpers no)
		(fp_poly
			(pts
				(xy -0.635 1.0668) (xy -0.635 -1.0668) (xy 0.635 -1.0668) (xy 0.635 1.0668)
			)
			(stroke
				(width 0)
				(type default)
			)
			(fill no)
			(layer "B.CrtYd")
		)
		(fp_line
			(start -0.254 0.508)
			(end 0.254 0.508)
			(stroke
				(width 0.0254)
				(type default)
			)
			(layer "B.Fab")
		)
		(fp_line
			(start 0.254 0.508)
			(end 0.254 -0.508)
			(stroke
				(width 0.0254)
				(type default)
			)
			(layer "B.Fab")
		)
		(fp_line
			(start -0.254 -0.508)
			(end -0.254 0.508)
			(stroke
				(width 0.0254)
				(type default)
			)
			(layer "B.Fab")
		)
		(fp_line
			(start 0.254 -0.508)
			(end -0.254 -0.508)
			(stroke
				(width 0.0254)
				(type default)
			)
			(layer "B.Fab")
		)
		(pad "1" smd rect
			(at 0 -0.4191 90)
			(size 0.508 0.5334)
			(layers "B.Cu" "B.Mask" "B.Paste")
			(net "NFP_CORE_VID7")
		)
		(pad "2" smd rect
			(at 0 0.4191 90)
			(size 0.508 0.5334)
			(layers "B.Cu" "B.Mask" "B.Paste")
			(net "_NFP_CORE_VID7")
		)
		(zone
			(layer "B.Cu")
			(hatch none 0.5)
			(connect_pads
				(clearance 0)
			)
			(min_thickness 0.25)
			(keepout
				(tracks not_allowed)
				(vias allowed)
				(pads allowed)
				(copperpour not_allowed)
				(footprints allowed)
			)
			(placement
				(enabled no)
				(sheetname "")
			)
			(fill
				(thermal_gap 0.5)
				(thermal_bridge_width 0.5)
				(island_removal_mode 0)
			)
			(polygon
				(pts
					(xy 36.7792 33.2486) (xy 36.7284 33.2486) (xy 36.7284 33.2994) (xy 36.7792 33.2994)
				)
			)
		)
	)
	(footprint ""
		(layer "B.Cu")
		(at 2.794 6.604)
		(property "Reference" "TP29"
			(at 0.254 -1.49733 0)
			(unlocked yes)
			(layer "B.SilkS")
			(effects
				(font
					(size 0.7874 0.5842)
					(thickness 0.127)
				)
				(justify left mirror)
			)
		)
		(property "Value" "*"
			(at 0.4826 -0.14732 0)
			(unlocked yes)
			(layer "B.Fab")
			(hide yes)
			(effects
				(font
					(size 1.27 0.9652)
					(thickness 0.000001)
				)
				(justify left mirror)
			)
		)
		(property "Device Type" "TP_SMALL"
			(at 0.4826 -0.14732 0)
			(unlocked yes)
			(layer "B.Fab")
			(hide yes)
			(effects
				(font
					(size 1.27 0.9652)
					(thickness 0.000001)
				)
				(justify left mirror)
			)
		)
		(duplicate_pad_numbers_are_jumpers no)
		(fp_line
			(start -0.8636 -0.8636)
			(end 0.8636 -0.8636)
			(stroke
				(width 0.1524)
				(type default)
			)
			(layer "B.SilkS")
		)
		(fp_line
			(start -0.8636 0.8636)
			(end -0.8636 -0.8636)
			(stroke
				(width 0.1524)
				(type default)
			)
			(layer "B.SilkS")
		)
		(fp_line
			(start 0.8636 -0.8636)
			(end 0.8636 0.8636)
			(stroke
				(width 0.1524)
				(type default)
			)
			(layer "B.SilkS")
		)
		(fp_line
			(start 0.8636 0.8636)
			(end -0.8636 0.8636)
			(stroke
				(width 0.1524)
				(type default)
			)
			(layer "B.SilkS")
		)
		(fp_poly
			(pts
				(xy 0.635 -0.635) (xy 0.635 0.635) (xy -0.635 0.635) (xy -0.635 -0.635)
			)
			(stroke
				(width 0)
				(type default)
			)
			(fill no)
			(layer "B.CrtYd")
		)
		(pad "1" smd rect
			(at 0 0 180)
			(size 1.27 1.27)
			(layers "B.Cu" "B.Mask" "B.Paste")
			(net "PGRM_JTAG_TDO")
		)
	)
	(footprint ""
		(layer "B.Cu")
		(at 22.733 31.75 -90)
		(property "Reference" "R59"
			(at -0.10033 0.889 0)
			(unlocked yes)
			(layer "B.SilkS")
			(effects
				(font
					(size 0.7874 0.5842)
					(thickness 0.127)
				)
				(justify left mirror)
			)
		)
		(property "Value" "4.75K"
			(at 0.148158 1.3462 180)
			(unlocked yes)
			(layer "B.Fab")
			(hide yes)
			(effects
				(font
					(size 1.27 0.9652)
					(thickness 0.000001)
				)
				(justify left mirror)
			)
		)
		(property "Device Type" "REST4024"
			(at 0.148158 1.3462 180)
			(unlocked yes)
			(layer "B.Fab")
			(hide yes)
			(effects
				(font
					(size 1.27 0.9652)
					(thickness 0.000001)
				)
				(justify left mirror)
			)
		)
		(duplicate_pad_numbers_are_jumpers no)
		(fp_poly
			(pts
				(xy -0.635 1.0668) (xy -0.635 -1.0668) (xy 0.635 -1.0668) (xy 0.635 1.0668)
			)
			(stroke
				(width 0)
				(type default)
			)
			(fill no)
			(layer "B.CrtYd")
		)
		(fp_line
			(start -0.254 0.508)
			(end 0.254 0.508)
			(stroke
				(width 0.0254)
				(type default)
			)
			(layer "B.Fab")
		)
		(fp_line
			(start 0.254 0.508)
			(end 0.254 -0.508)
			(stroke
				(width 0.0254)
				(type default)
			)
			(layer "B.Fab")
		)
		(fp_line
			(start -0.254 -0.508)
			(end -0.254 0.508)
			(stroke
				(width 0.0254)
				(type default)
			)
			(layer "B.Fab")
		)
		(fp_line
			(start 0.254 -0.508)
			(end -0.254 -0.508)
			(stroke
				(width 0.0254)
				(type default)
			)
			(layer "B.Fab")
		)
		(pad "1" smd rect
			(at 0 -0.4191 90)
			(size 0.508 0.5334)
			(layers "B.Cu" "B.Mask" "B.Paste")
			(net "9N2032")
		)
		(pad "2" smd rect
			(at 0 0.4191 90)
			(size 0.508 0.5334)
			(layers "B.Cu" "B.Mask" "B.Paste")
			(net "GND")
		)
		(zone
			(layer "B.Cu")
			(hatch none 0.5)
			(connect_pads
				(clearance 0)
			)
			(min_thickness 0.25)
			(keepout
				(tracks not_allowed)
				(vias allowed)
				(pads allowed)
				(copperpour not_allowed)
				(footprints allowed)
			)
			(placement
				(enabled no)
				(sheetname "")
			)
			(fill
				(thermal_gap 0.5)
				(thermal_bridge_width 0.5)
				(island_removal_mode 0)
			)
			(polygon
				(pts
					(xy 22.7584 31.7246) (xy 22.7076 31.7246) (xy 22.7076 31.7754) (xy 22.7584 31.7754)
				)
			)
		)
	)
	(footprint ""
		(layer "B.Cu")
		(at 73.05101 1.899006)
		(property "Reference" "V_A-DQ15"
			(at 0 0 0)
			(layer "B.SilkS")
			(hide yes)
			(effects
				(font
					(size 1.27 1.27)
				)
				(justify mirror)
			)
		)
		(property "Value" ""
			(at 0 0 0)
			(layer "B.Fab")
			(effects
				(font
					(size 1.27 1.27)
				)
				(justify mirror)
			)
		)
		(duplicate_pad_numbers_are_jumpers no)
		(pad "1" thru_hole circle
			(at 0 0 180)
			(size 0.4572 0.4572)
			(drill 0.20574)
			(layers "*.Cu" "*.Mask")
			(remove_unused_layers no)
			(net "DDR0_32A_DQ15")
			(clearance 0.1143)
			(thermal_gap 0.1143)
		)
	)
	(footprint ""
		(layer "B.Cu")
		(at 37.084 44.831)
		(property "Reference" "TP12"
			(at 1.016 -1.49733 0)
			(unlocked yes)
			(layer "B.SilkS")
			(effects
				(font
					(size 0.7874 0.5842)
					(thickness 0.127)
				)
				(justify left mirror)
			)
		)
		(property "Value" "*"
			(at 0.4826 -0.14732 0)
			(unlocked yes)
			(layer "B.Fab")
			(hide yes)
			(effects
				(font
					(size 1.27 0.9652)
					(thickness 0.000001)
				)
				(justify left mirror)
			)
		)
		(property "Device Type" "TP_SMALL"
			(at 0.4826 -0.14732 0)
			(unlocked yes)
			(layer "B.Fab")
			(hide yes)
			(effects
				(font
					(size 1.27 0.9652)
					(thickness 0.000001)
				)
				(justify left mirror)
			)
		)
		(duplicate_pad_numbers_are_jumpers no)
		(fp_line
			(start -0.8636 -0.8636)
			(end 0.8636 -0.8636)
			(stroke
				(width 0.1524)
				(type default)
			)
			(layer "B.SilkS")
		)
		(fp_line
			(start -0.8636 0.8636)
			(end -0.8636 -0.8636)
			(stroke
				(width 0.1524)
				(type default)
			)
			(layer "B.SilkS")
		)
		(fp_line
			(start 0.8636 -0.8636)
			(end 0.8636 0.8636)
			(stroke
				(width 0.1524)
				(type default)
			)
			(layer "B.SilkS")
		)
		(fp_line
			(start 0.8636 0.8636)
			(end -0.8636 0.8636)
			(stroke
				(width 0.1524)
				(type default)
			)
			(layer "B.SilkS")
		)
		(fp_poly
			(pts
				(xy 0.635 -0.635) (xy 0.635 0.635) (xy -0.635 0.635) (xy -0.635 -0.635)
			)
			(stroke
				(width 0)
				(type default)
			)
			(fill no)
			(layer "B.CrtYd")
		)
		(pad "1" smd rect
			(at 0 0 180)
			(size 1.27 1.27)
			(layers "B.Cu" "B.Mask" "B.Paste")
			(net "DEBUG_CPLD_PGRM_JTAG_TDO")
		)
	)
	(footprint ""
		(layer "B.Cu")
		(at 23.749 10.414 90)
		(property "Reference" "R44"
			(at 0 0 90)
			(layer "B.SilkS")
			(hide yes)
			(effects
				(font
					(size 1.27 1.27)
				)
				(justify mirror)
			)
		)
		(property "Value" "4.75K"
			(at 0.148158 1.3462 0)
			(unlocked yes)
			(layer "B.Fab")
			(hide yes)
			(effects
				(font
					(size 1.27 0.9652)
					(thickness 0.000001)
				)
				(justify left mirror)
			)
		)
		(property "Device Type" "REST4024"
			(at 0.148158 1.3462 0)
			(unlocked yes)
			(layer "B.Fab")
			(hide yes)
			(effects
				(font
					(size 1.27 0.9652)
					(thickness 0.000001)
				)
				(justify left mirror)
			)
		)
		(duplicate_pad_numbers_are_jumpers no)
		(fp_poly
			(pts
				(xy -0.635 1.0668) (xy -0.635 -1.0668) (xy 0.635 -1.0668) (xy 0.635 1.0668)
			)
			(stroke
				(width 0)
				(type default)
			)
			(fill no)
			(layer "B.CrtYd")
		)
		(fp_line
			(start 0.254 -0.508)
			(end -0.254 -0.508)
			(stroke
				(width 0.0254)
				(type default)
			)
			(layer "B.Fab")
		)
		(fp_line
			(start -0.254 -0.508)
			(end -0.254 0.508)
			(stroke
				(width 0.0254)
				(type default)
			)
			(layer "B.Fab")
		)
		(fp_line
			(start 0.254 0.508)
			(end 0.254 -0.508)
			(stroke
				(width 0.0254)
				(type default)
			)
			(layer "B.Fab")
		)
		(fp_line
			(start -0.254 0.508)
			(end 0.254 0.508)
			(stroke
				(width 0.0254)
				(type default)
			)
			(layer "B.Fab")
		)
		(pad "1" smd rect
			(at 0 -0.4191 270)
			(size 0.508 0.5334)
			(layers "B.Cu" "B.Mask" "B.Paste")
			(net "VDD_3.3V")
		)
		(pad "2" smd rect
			(at 0 0.4191 270)
			(size 0.508 0.5334)
			(layers "B.Cu" "B.Mask" "B.Paste")
			(net "PGRM_JTAG_TDI")
		)
		(zone
			(layer "B.Cu")
			(hatch none 0.5)
			(connect_pads
				(clearance 0)
			)
			(min_thickness 0.25)
			(keepout
				(tracks not_allowed)
				(vias allowed)
				(pads allowed)
				(copperpour not_allowed)
				(footprints allowed)
			)
			(placement
				(enabled no)
				(sheetname "")
			)
			(fill
				(thermal_gap 0.5)
				(thermal_bridge_width 0.5)
				(island_removal_mode 0)
			)
			(polygon
				(pts
					(xy 23.7236 10.4394) (xy 23.7744 10.4394) (xy 23.7744 10.3886) (xy 23.7236 10.3886)
				)
			)
		)
	)
	(footprint ""
		(layer "B.Cu")
		(at 20.701 16.891 180)
		(property "Reference" "R32"
			(at 1.04267 -1.143 270)
			(unlocked yes)
			(layer "B.SilkS")
			(effects
				(font
					(size 0.7874 0.5842)
					(thickness 0.127)
				)
				(justify left mirror)
			)
		)
		(property "Value" "4.75K"
			(at 0.148158 1.3462 90)
			(unlocked yes)
			(layer "B.Fab")
			(hide yes)
			(effects
				(font
					(size 1.27 0.9652)
					(thickness 0.000001)
				)
				(justify left mirror)
			)
		)
		(property "Device Type" "REST4024"
			(at 0.148158 1.3462 90)
			(unlocked yes)
			(layer "B.Fab")
			(hide yes)
			(effects
				(font
					(size 1.27 0.9652)
					(thickness 0.000001)
				)
				(justify left mirror)
			)
		)
		(duplicate_pad_numbers_are_jumpers no)
		(fp_poly
			(pts
				(xy -0.635 1.0668) (xy -0.635 -1.0668) (xy 0.635 -1.0668) (xy 0.635 1.0668)
			)
			(stroke
				(width 0)
				(type default)
			)
			(fill no)
			(layer "B.CrtYd")
		)
		(fp_line
			(start 0.254 0.508)
			(end 0.254 -0.508)
			(stroke
				(width 0.0254)
				(type default)
			)
			(layer "B.Fab")
		)
		(fp_line
			(start 0.254 -0.508)
			(end -0.254 -0.508)
			(stroke
				(width 0.0254)
				(type default)
			)
			(layer "B.Fab")
		)
		(fp_line
			(start -0.254 0.508)
			(end 0.254 0.508)
			(stroke
				(width 0.0254)
				(type default)
			)
			(layer "B.Fab")
		)
		(fp_line
			(start -0.254 -0.508)
			(end -0.254 0.508)
			(stroke
				(width 0.0254)
				(type default)
			)
			(layer "B.Fab")
		)
		(pad "1" smd rect
			(at 0 -0.4191)
			(size 0.508 0.5334)
			(layers "B.Cu" "B.Mask" "B.Paste")
			(net "NFP_ARM_SPI_FLASH_SEL")
		)
		(pad "2" smd rect
			(at 0 0.4191)
			(size 0.508 0.5334)
			(layers "B.Cu" "B.Mask" "B.Paste")
			(net "GND")
		)
		(zone
			(layer "B.Cu")
			(hatch none 0.5)
			(connect_pads
				(clearance 0)
			)
			(min_thickness 0.25)
			(keepout
				(tracks not_allowed)
				(vias allowed)
				(pads allowed)
				(copperpour not_allowed)
				(footprints allowed)
			)
			(placement
				(enabled no)
				(sheetname "")
			)
			(fill
				(thermal_gap 0.5)
				(thermal_bridge_width 0.5)
				(island_removal_mode 0)
			)
			(polygon
				(pts
					(xy 20.7264 16.9164) (xy 20.7264 16.8656) (xy 20.6756 16.8656) (xy 20.6756 16.9164)
				)
			)
		)
	)
	(footprint ""
		(layer "B.Cu")
		(at 38.989 48.641)
		(property "Reference" "TP3"
			(at 1.49733 3.429 270)
			(unlocked yes)
			(layer "B.SilkS")
			(effects
				(font
					(size 0.7874 0.5842)
					(thickness 0.127)
				)
				(justify left mirror)
			)
		)
		(property "Value" "*"
			(at 0.4826 -0.14732 0)
			(unlocked yes)
			(layer "B.Fab")
			(hide yes)
			(effects
				(font
					(size 1.27 0.9652)
					(thickness 0.000001)
				)
				(justify left mirror)
			)
		)
		(property "Device Type" "TP_SMALL"
			(at 0.4826 -0.14732 0)
			(unlocked yes)
			(layer "B.Fab")
			(hide yes)
			(effects
				(font
					(size 1.27 0.9652)
					(thickness 0.000001)
				)
				(justify left mirror)
			)
		)
		(duplicate_pad_numbers_are_jumpers no)
		(fp_line
			(start -0.8636 -0.8636)
			(end 0.8636 -0.8636)
			(stroke
				(width 0.1524)
				(type default)
			)
			(layer "B.SilkS")
		)
		(fp_line
			(start -0.8636 0.8636)
			(end -0.8636 -0.8636)
			(stroke
				(width 0.1524)
				(type default)
			)
			(layer "B.SilkS")
		)
		(fp_line
			(start 0.8636 -0.8636)
			(end 0.8636 0.8636)
			(stroke
				(width 0.1524)
				(type default)
			)
			(layer "B.SilkS")
		)
		(fp_line
			(start 0.8636 0.8636)
			(end -0.8636 0.8636)
			(stroke
				(width 0.1524)
				(type default)
			)
			(layer "B.SilkS")
		)
		(fp_poly
			(pts
				(xy 0.635 -0.635) (xy 0.635 0.635) (xy -0.635 0.635) (xy -0.635 -0.635)
			)
			(stroke
				(width 0)
				(type default)
			)
			(fill no)
			(layer "B.CrtYd")
		)
		(pad "1" smd rect
			(at 0 0 180)
			(size 1.27 1.27)
			(layers "B.Cu" "B.Mask" "B.Paste")
			(net "CNTRL_SPI_MISO")
		)
	)
	(footprint ""
		(layer "B.Cu")
		(at 56.736996 6.042025 90)
		(property "Reference" "C39"
			(at 1.443355 -0.602996 0)
			(unlocked yes)
			(layer "B.SilkS")
			(effects
				(font
					(size 0.7874 0.5842)
					(thickness 0.127)
				)
				(justify mirror)
			)
		)
		(property "Value" ""
			(at 0 0 90)
			(layer "B.Fab")
			(effects
				(font
					(size 1.27 1.27)
				)
				(justify mirror)
			)
		)
		(duplicate_pad_numbers_are_jumpers no)
		(fp_circle
			(center 0 0)
			(end 0 0.104648)
			(stroke
				(width 0.1016)
				(type default)
			)
			(fill no)
			(layer "B.SilkS")
		)
		(fp_poly
			(pts
				(xy 0.381 -0.889) (xy 0.381 0.889) (xy -0.381 0.889) (xy -0.381 -0.889)
			)
			(stroke
				(width 0)
				(type default)
			)
			(fill no)
			(layer "B.CrtYd")
		)
		(fp_line
			(start 0.508 -1.016)
			(end 0.254 -1.016)
			(stroke
				(width 0.0254)
				(type default)
			)
			(layer "B.Fab")
		)
		(fp_line
			(start 0.254 -1.016)
			(end -0.508 -1.016)
			(stroke
				(width 0.0254)
				(type default)
			)
			(layer "B.Fab")
		)
		(fp_line
			(start -0.508 -1.016)
			(end -0.508 1.016)
			(stroke
				(width 0.0254)
				(type default)
			)
			(layer "B.Fab")
		)
		(fp_line
			(start 0.508 1.016)
			(end 0.508 -1.016)
			(stroke
				(width 0.0254)
				(type default)
			)
			(layer "B.Fab")
		)
		(fp_line
			(start -0.508 1.016)
			(end 0.508 1.016)
			(stroke
				(width 0.0254)
				(type default)
			)
			(layer "B.Fab")
		)
		(pad "1" smd custom
			(at 0 -0.500126 270)
			(size 0.127 0.127)
			(layers "B.Cu" "B.Mask" "B.Paste")
			(net "VDDAH_PCIE0")
			(options
				(clearance outline)
				(anchor circle)
			)
			(primitives
				(gr_poly
					(pts
						(xy -0.1778 0.254) (xy 0.1778 0.254) (xy 0.254 0.1778) (xy 0.254 -0.1778) (xy 0.1778 -0.254) (xy -0.1778 -0.254)
						(xy -0.254 -0.1778) (xy -0.254 0.1778)
					)
					(width 0)
					(fill yes)
				)
			)
		)
		(pad "2" smd custom
			(at 0 0.500126 270)
			(size 0.127 0.127)
			(layers "B.Cu" "B.Mask" "B.Paste")
			(net "GND")
			(options
				(clearance outline)
				(anchor circle)
			)
			(primitives
				(gr_poly
					(pts
						(xy -0.1778 0.254) (xy 0.1778 0.254) (xy 0.254 0.1778) (xy 0.254 -0.1778) (xy 0.1778 -0.254) (xy -0.1778 -0.254)
						(xy -0.254 -0.1778) (xy -0.254 0.1778)
					)
					(width 0)
					(fill yes)
				)
			)
		)
	)
	(footprint ""
		(layer "B.Cu")
		(at 23.495 13.589)
		(property "Reference" "R31"
			(at 0.86233 1.016 270)
			(unlocked yes)
			(layer "B.SilkS")
			(effects
				(font
					(size 0.7874 0.5842)
					(thickness 0.127)
				)
				(justify left mirror)
			)
		)
		(property "Value" "4.75K"
			(at 0.148158 1.3462 270)
			(unlocked yes)
			(layer "B.Fab")
			(hide yes)
			(effects
				(font
					(size 1.27 0.9652)
					(thickness 0.000001)
				)
				(justify left mirror)
			)
		)
		(property "Device Type" "REST4024"
			(at 0.148158 1.3462 270)
			(unlocked yes)
			(layer "B.Fab")
			(hide yes)
			(effects
				(font
					(size 1.27 0.9652)
					(thickness 0.000001)
				)
				(justify left mirror)
			)
		)
		(duplicate_pad_numbers_are_jumpers no)
		(fp_poly
			(pts
				(xy -0.635 1.0668) (xy -0.635 -1.0668) (xy 0.635 -1.0668) (xy 0.635 1.0668)
			)
			(stroke
				(width 0)
				(type default)
			)
			(fill no)
			(layer "B.CrtYd")
		)
		(fp_line
			(start -0.254 -0.508)
			(end -0.254 0.508)
			(stroke
				(width 0.0254)
				(type default)
			)
			(layer "B.Fab")
		)
		(fp_line
			(start -0.254 0.508)
			(end 0.254 0.508)
			(stroke
				(width 0.0254)
				(type default)
			)
			(layer "B.Fab")
		)
		(fp_line
			(start 0.254 -0.508)
			(end -0.254 -0.508)
			(stroke
				(width 0.0254)
				(type default)
			)
			(layer "B.Fab")
		)
		(fp_line
			(start 0.254 0.508)
			(end 0.254 -0.508)
			(stroke
				(width 0.0254)
				(type default)
			)
			(layer "B.Fab")
		)
		(pad "1" smd rect
			(at 0 -0.4191 180)
			(size 0.508 0.5334)
			(layers "B.Cu" "B.Mask" "B.Paste")
			(net "VDD_3.3V")
		)
		(pad "2" smd rect
			(at 0 0.4191 180)
			(size 0.508 0.5334)
			(layers "B.Cu" "B.Mask" "B.Paste")
			(net "NFP_CFG_SPI_FLASH_WP_L")
		)
		(zone
			(layer "B.Cu")
			(hatch none 0.5)
			(connect_pads
				(clearance 0)
			)
			(min_thickness 0.25)
			(keepout
				(tracks not_allowed)
				(vias allowed)
				(pads allowed)
				(copperpour not_allowed)
				(footprints allowed)
			)
			(placement
				(enabled no)
				(sheetname "")
			)
			(fill
				(thermal_gap 0.5)
				(thermal_bridge_width 0.5)
				(island_removal_mode 0)
			)
			(polygon
				(pts
					(xy 23.4696 13.5636) (xy 23.4696 13.6144) (xy 23.5204 13.6144) (xy 23.5204 13.5636)
				)
			)
		)
	)
	(footprint ""
		(layer "B.Cu")
		(at 66.236977 17.542002 180)
		(property "Reference" "C190"
			(at -0.919353 0.143002 270)
			(unlocked yes)
			(layer "B.SilkS")
			(effects
				(font
					(size 0.7874 0.5842)
					(thickness 0.127)
				)
				(justify mirror)
			)
		)
		(property "Value" ""
			(at 0 0 0)
			(layer "B.Fab")
			(effects
				(font
					(size 1.27 1.27)
				)
				(justify mirror)
			)
		)
		(duplicate_pad_numbers_are_jumpers no)
		(fp_circle
			(center 0 0)
			(end -0.104648 0)
			(stroke
				(width 0.1016)
				(type default)
			)
			(fill no)
			(layer "B.SilkS")
		)
		(fp_poly
			(pts
				(xy 0.381 -0.889) (xy 0.381 0.889) (xy -0.381 0.889) (xy -0.381 -0.889)
			)
			(stroke
				(width 0)
				(type default)
			)
			(fill no)
			(layer "B.CrtYd")
		)
		(fp_line
			(start 0.508 1.016)
			(end 0.508 -1.016)
			(stroke
				(width 0.0254)
				(type default)
			)
			(layer "B.Fab")
		)
		(fp_line
			(start 0.508 -1.016)
			(end 0.254 -1.016)
			(stroke
				(width 0.0254)
				(type default)
			)
			(layer "B.Fab")
		)
		(fp_line
			(start 0.254 -1.016)
			(end -0.508 -1.016)
			(stroke
				(width 0.0254)
				(type default)
			)
			(layer "B.Fab")
		)
		(fp_line
			(start -0.508 1.016)
			(end 0.508 1.016)
			(stroke
				(width 0.0254)
				(type default)
			)
			(layer "B.Fab")
		)
		(fp_line
			(start -0.508 -1.016)
			(end -0.508 1.016)
			(stroke
				(width 0.0254)
				(type default)
			)
			(layer "B.Fab")
		)
		(pad "1" smd custom
			(at 0 -0.500126)
			(size 0.127 0.127)
			(layers "B.Cu" "B.Mask" "B.Paste")
			(net "DDR_VDDQ")
			(options
				(clearance outline)
				(anchor circle)
			)
			(primitives
				(gr_poly
					(pts
						(xy -0.1778 0.254) (xy 0.1778 0.254) (xy 0.254 0.1778) (xy 0.254 -0.1778) (xy 0.1778 -0.254) (xy -0.1778 -0.254)
						(xy -0.254 -0.1778) (xy -0.254 0.1778)
					)
					(width 0)
					(fill yes)
				)
			)
		)
		(pad "2" smd custom
			(at 0 0.500126)
			(size 0.127 0.127)
			(layers "B.Cu" "B.Mask" "B.Paste")
			(net "GND")
			(options
				(clearance outline)
				(anchor circle)
			)
			(primitives
				(gr_poly
					(pts
						(xy -0.1778 0.254) (xy 0.1778 0.254) (xy 0.254 0.1778) (xy 0.254 -0.1778) (xy 0.1778 -0.254) (xy -0.1778 -0.254)
						(xy -0.254 -0.1778) (xy -0.254 0.1778)
					)
					(width 0)
					(fill yes)
				)
			)
		)
	)
	(footprint ""
		(layer "B.Cu")
		(at 75.451005 25.013006)
		(property "Reference" "V_A-CB0"
			(at 0 0 0)
			(layer "B.SilkS")
			(hide yes)
			(effects
				(font
					(size 1.27 1.27)
				)
				(justify mirror)
			)
		)
		(property "Value" ""
			(at 0 0 0)
			(layer "B.Fab")
			(effects
				(font
					(size 1.27 1.27)
				)
				(justify mirror)
			)
		)
		(duplicate_pad_numbers_are_jumpers no)
		(pad "1" thru_hole circle
			(at 0 0 180)
			(size 0.4572 0.4572)
			(drill 0.20574)
			(layers "*.Cu" "*.Mask")
			(remove_unused_layers no)
			(net "DDR0_32A_CB0")
			(clearance 0.1143)
			(thermal_gap 0.1143)
		)
	)
	(footprint ""
		(layer "B.Cu")
		(at 81.050994 25.013006)
		(property "Reference" "V3_A-BA0"
			(at 0 0 0)
			(layer "B.SilkS")
			(hide yes)
			(effects
				(font
					(size 1.27 1.27)
				)
				(justify mirror)
			)
		)
		(property "Value" ""
			(at 0 0 0)
			(layer "B.Fab")
			(effects
				(font
					(size 1.27 1.27)
				)
				(justify mirror)
			)
		)
		(duplicate_pad_numbers_are_jumpers no)
		(pad "1" thru_hole circle
			(at 0 0 180)
			(size 0.4572 0.4572)
			(drill 0.20574)
			(layers "*.Cu" "*.Mask")
			(remove_unused_layers no)
			(net "DDR0_32A_BA0")
			(clearance 0.1143)
			(thermal_gap 0.1143)
		)
	)
	(footprint ""
		(layer "B.Cu")
		(at 26.289 8.509 90)
		(property "Reference" "R404"
			(at 0.73533 2.286 0)
			(unlocked yes)
			(layer "B.SilkS")
			(effects
				(font
					(size 0.7874 0.5842)
					(thickness 0.127)
				)
				(justify left mirror)
			)
		)
		(property "Value" "4.75K"
			(at 0.148158 1.3462 0)
			(unlocked yes)
			(layer "B.Fab")
			(hide yes)
			(effects
				(font
					(size 1.27 0.9652)
					(thickness 0.000001)
				)
				(justify left mirror)
			)
		)
		(property "Device Type" "REST4024"
			(at 0.148158 1.3462 0)
			(unlocked yes)
			(layer "B.Fab")
			(hide yes)
			(effects
				(font
					(size 1.27 0.9652)
					(thickness 0.000001)
				)
				(justify left mirror)
			)
		)
		(duplicate_pad_numbers_are_jumpers no)
		(fp_poly
			(pts
				(xy -0.635 1.0668) (xy -0.635 -1.0668) (xy 0.635 -1.0668) (xy 0.635 1.0668)
			)
			(stroke
				(width 0)
				(type default)
			)
			(fill no)
			(layer "B.CrtYd")
		)
		(fp_line
			(start 0.254 -0.508)
			(end -0.254 -0.508)
			(stroke
				(width 0.0254)
				(type default)
			)
			(layer "B.Fab")
		)
		(fp_line
			(start -0.254 -0.508)
			(end -0.254 0.508)
			(stroke
				(width 0.0254)
				(type default)
			)
			(layer "B.Fab")
		)
		(fp_line
			(start 0.254 0.508)
			(end 0.254 -0.508)
			(stroke
				(width 0.0254)
				(type default)
			)
			(layer "B.Fab")
		)
		(fp_line
			(start -0.254 0.508)
			(end 0.254 0.508)
			(stroke
				(width 0.0254)
				(type default)
			)
			(layer "B.Fab")
		)
		(pad "1" smd rect
			(at 0 -0.4191 270)
			(size 0.508 0.5334)
			(layers "B.Cu" "B.Mask" "B.Paste")
			(net "VDD_3.3V")
		)
		(pad "2" smd rect
			(at 0 0.4191 270)
			(size 0.508 0.5334)
			(layers "B.Cu" "B.Mask" "B.Paste")
			(net "NFP_JTAG_ARM_TDO")
		)
		(zone
			(layer "B.Cu")
			(hatch none 0.5)
			(connect_pads
				(clearance 0)
			)
			(min_thickness 0.25)
			(keepout
				(tracks not_allowed)
				(vias allowed)
				(pads allowed)
				(copperpour not_allowed)
				(footprints allowed)
			)
			(placement
				(enabled no)
				(sheetname "")
			)
			(fill
				(thermal_gap 0.5)
				(thermal_bridge_width 0.5)
				(island_removal_mode 0)
			)
			(polygon
				(pts
					(xy 26.2636 8.5344) (xy 26.3144 8.5344) (xy 26.3144 8.4836) (xy 26.2636 8.4836)
				)
			)
		)
	)
	(footprint ""
		(layer "B.Cu")
		(at 54.737 33.782)
		(property "Reference" "C14"
			(at 0.98933 0.254 270)
			(unlocked yes)
			(layer "B.SilkS")
			(effects
				(font
					(size 0.7874 0.5842)
					(thickness 0.127)
				)
				(justify left mirror)
			)
		)
		(property "Value" "22UF"
			(at 0.148158 1.7526 270)
			(unlocked yes)
			(layer "B.Fab")
			(hide yes)
			(effects
				(font
					(size 1.27 0.9652)
					(thickness 0.000001)
				)
				(justify left mirror)
			)
		)
		(property "Device Type" "CAPC0063"
			(at 0.148158 1.7526 270)
			(unlocked yes)
			(layer "B.Fab")
			(hide yes)
			(effects
				(font
					(size 1.27 0.9652)
					(thickness 0.000001)
				)
				(justify left mirror)
			)
		)
		(duplicate_pad_numbers_are_jumpers no)
		(fp_circle
			(center 0 0)
			(end 0.127 0)
			(stroke
				(width 0.2032)
				(type default)
			)
			(fill no)
			(layer "B.SilkS")
		)
		(fp_poly
			(pts
				(xy -0.7874 -1.6637) (xy 0.7874 -1.6637) (xy 0.7874 1.6637) (xy -0.7874 1.6637)
			)
			(stroke
				(width 0)
				(type default)
			)
			(fill no)
			(layer "B.CrtYd")
		)
		(fp_line
			(start -0.4064 -0.7874)
			(end -0.4064 0.8128)
			(stroke
				(width 0.0254)
				(type default)
			)
			(layer "B.Fab")
		)
		(fp_line
			(start -0.4064 0.8128)
			(end 0.4064 0.8128)
			(stroke
				(width 0.0254)
				(type default)
			)
			(layer "B.Fab")
		)
		(fp_line
			(start 0.4064 -0.7874)
			(end -0.4064 -0.7874)
			(stroke
				(width 0.0254)
				(type default)
			)
			(layer "B.Fab")
		)
		(fp_line
			(start 0.4064 0.8128)
			(end 0.4064 -0.7874)
			(stroke
				(width 0.0254)
				(type default)
			)
			(layer "B.Fab")
		)
		(pad "1" smd rect
			(at 0 -0.8001 180)
			(size 0.8636 0.9652)
			(layers "B.Cu" "B.Mask" "B.Paste")
			(net "VDD_CORE")
		)
		(pad "2" smd rect
			(at 0 0.8001 180)
			(size 0.8636 0.9652)
			(layers "B.Cu" "B.Mask" "B.Paste")
			(net "GND")
		)
		(zone
			(layer "B.Cu")
			(hatch none 0.5)
			(connect_pads
				(clearance 0)
			)
			(min_thickness 0.25)
			(keepout
				(tracks not_allowed)
				(vias allowed)
				(pads allowed)
				(copperpour not_allowed)
				(footprints allowed)
			)
			(placement
				(enabled no)
				(sheetname "")
			)
			(fill
				(thermal_gap 0.5)
				(thermal_bridge_width 0.5)
				(island_removal_mode 0)
			)
			(polygon
				(pts
					(xy 54.8005 33.528) (xy 54.6735 33.528) (xy 54.6735 34.036) (xy 54.8005 34.036)
				)
			)
		)
	)
	(footprint ""
		(layer "B.Cu")
		(at 49.237011 12.542012)
		(property "Reference" "C178"
			(at 0 0 0)
			(layer "B.SilkS")
			(hide yes)
			(effects
				(font
					(size 1.27 1.27)
				)
				(justify mirror)
			)
		)
		(property "Value" ""
			(at 0 0 0)
			(layer "B.Fab")
			(effects
				(font
					(size 1.27 1.27)
				)
				(justify mirror)
			)
		)
		(duplicate_pad_numbers_are_jumpers no)
		(fp_circle
			(center 0 0)
			(end 0.104648 0)
			(stroke
				(width 0.1016)
				(type default)
			)
			(fill no)
			(layer "B.SilkS")
		)
		(fp_poly
			(pts
				(xy 0.381 -0.889) (xy 0.381 0.889) (xy -0.381 0.889) (xy -0.381 -0.889)
			)
			(stroke
				(width 0)
				(type default)
			)
			(fill no)
			(layer "B.CrtYd")
		)
		(fp_line
			(start -0.508 -1.016)
			(end -0.508 1.016)
			(stroke
				(width 0.0254)
				(type default)
			)
			(layer "B.Fab")
		)
		(fp_line
			(start -0.508 1.016)
			(end 0.508 1.016)
			(stroke
				(width 0.0254)
				(type default)
			)
			(layer "B.Fab")
		)
		(fp_line
			(start 0.254 -1.016)
			(end -0.508 -1.016)
			(stroke
				(width 0.0254)
				(type default)
			)
			(layer "B.Fab")
		)
		(fp_line
			(start 0.508 -1.016)
			(end 0.254 -1.016)
			(stroke
				(width 0.0254)
				(type default)
			)
			(layer "B.Fab")
		)
		(fp_line
			(start 0.508 1.016)
			(end 0.508 -1.016)
			(stroke
				(width 0.0254)
				(type default)
			)
			(layer "B.Fab")
		)
		(pad "1" smd custom
			(at 0 -0.500126 180)
			(size 0.127 0.127)
			(layers "B.Cu" "B.Mask" "B.Paste")
			(net "VDD_CORE")
			(options
				(clearance outline)
				(anchor circle)
			)
			(primitives
				(gr_poly
					(pts
						(xy -0.1778 0.254) (xy 0.1778 0.254) (xy 0.254 0.1778) (xy 0.254 -0.1778) (xy 0.1778 -0.254) (xy -0.1778 -0.254)
						(xy -0.254 -0.1778) (xy -0.254 0.1778)
					)
					(width 0)
					(fill yes)
				)
			)
		)
		(pad "2" smd custom
			(at 0 0.500126 180)
			(size 0.127 0.127)
			(layers "B.Cu" "B.Mask" "B.Paste")
			(net "GND")
			(options
				(clearance outline)
				(anchor circle)
			)
			(primitives
				(gr_poly
					(pts
						(xy -0.1778 0.254) (xy 0.1778 0.254) (xy 0.254 0.1778) (xy 0.254 -0.1778) (xy 0.1778 -0.254) (xy -0.1778 -0.254)
						(xy -0.254 -0.1778) (xy -0.254 0.1778)
					)
					(width 0)
					(fill yes)
				)
			)
		)
	)
	(footprint ""
		(layer "B.Cu")
		(at 39.237031 26.542238 180)
		(property "Reference" "R407"
			(at 0.274701 -2.286762 270)
			(unlocked yes)
			(layer "B.SilkS")
			(effects
				(font
					(size 0.7874 0.5842)
					(thickness 0.127)
				)
				(justify mirror)
			)
		)
		(property "Value" ""
			(at 0 0 0)
			(layer "B.Fab")
			(effects
				(font
					(size 1.27 1.27)
				)
				(justify mirror)
			)
		)
		(duplicate_pad_numbers_are_jumpers no)
		(fp_circle
			(center 0 0)
			(end -0.104648 0)
			(stroke
				(width 0.1016)
				(type default)
			)
			(fill no)
			(layer "B.SilkS")
		)
		(fp_poly
			(pts
				(xy 0.381 -0.889) (xy 0.381 0.889) (xy -0.381 0.889) (xy -0.381 -0.889)
			)
			(stroke
				(width 0)
				(type default)
			)
			(fill no)
			(layer "B.CrtYd")
		)
		(fp_line
			(start 0.508 1.016)
			(end 0.508 -1.016)
			(stroke
				(width 0.0254)
				(type default)
			)
			(layer "B.Fab")
		)
		(fp_line
			(start 0.508 -1.016)
			(end 0.254 -1.016)
			(stroke
				(width 0.0254)
				(type default)
			)
			(layer "B.Fab")
		)
		(fp_line
			(start 0.254 -1.016)
			(end -0.508 -1.016)
			(stroke
				(width 0.0254)
				(type default)
			)
			(layer "B.Fab")
		)
		(fp_line
			(start -0.508 1.016)
			(end 0.508 1.016)
			(stroke
				(width 0.0254)
				(type default)
			)
			(layer "B.Fab")
		)
		(fp_line
			(start -0.508 -1.016)
			(end -0.508 1.016)
			(stroke
				(width 0.0254)
				(type default)
			)
			(layer "B.Fab")
		)
		(pad "1" smd custom
			(at 0 -0.500126)
			(size 0.127 0.127)
			(layers "B.Cu" "B.Mask" "B.Paste")
			(net "NFP_JTAG_ARM_TRST_L")
			(options
				(clearance outline)
				(anchor circle)
			)
			(primitives
				(gr_poly
					(pts
						(xy -0.1778 0.254) (xy 0.1778 0.254) (xy 0.254 0.1778) (xy 0.254 -0.1778) (xy 0.1778 -0.254) (xy -0.1778 -0.254)
						(xy -0.254 -0.1778) (xy -0.254 0.1778)
					)
					(width 0)
					(fill yes)
				)
			)
		)
		(pad "2" smd custom
			(at 0 0.500126)
			(size 0.127 0.127)
			(layers "B.Cu" "B.Mask" "B.Paste")
			(net "GND")
			(options
				(clearance outline)
				(anchor circle)
			)
			(primitives
				(gr_poly
					(pts
						(xy -0.1778 0.254) (xy 0.1778 0.254) (xy 0.254 0.1778) (xy 0.254 -0.1778) (xy 0.1778 -0.254) (xy -0.1778 -0.254)
						(xy -0.254 -0.1778) (xy -0.254 0.1778)
					)
					(width 0)
					(fill yes)
				)
			)
		)
	)
	(footprint ""
		(layer "B.Cu")
		(at 51.94808 35.41776 90)
		(property "Reference" "R118"
			(at -1.55067 1.6891 0)
			(unlocked yes)
			(layer "B.SilkS")
			(effects
				(font
					(size 0.7874 0.5842)
					(thickness 0.127)
				)
				(justify left mirror)
			)
		)
		(property "Value" "2.2"
			(at 0.148158 1.7526 0)
			(unlocked yes)
			(layer "B.Fab")
			(hide yes)
			(effects
				(font
					(size 1.27 0.9652)
					(thickness 0.000001)
				)
				(justify left mirror)
			)
		)
		(property "Device Type" "REST0145"
			(at 0.148158 1.7526 0)
			(unlocked yes)
			(layer "B.Fab")
			(hide yes)
			(effects
				(font
					(size 1.27 0.9652)
					(thickness 0.000001)
				)
				(justify left mirror)
			)
		)
		(duplicate_pad_numbers_are_jumpers no)
		(fp_circle
			(center 0 0)
			(end 0 0.127)
			(stroke
				(width 0.2032)
				(type default)
			)
			(fill no)
			(layer "B.SilkS")
		)
		(fp_poly
			(pts
				(xy -0.7874 -1.6637) (xy 0.7874 -1.6637) (xy 0.7874 1.6637) (xy -0.7874 1.6637)
			)
			(stroke
				(width 0)
				(type default)
			)
			(fill no)
			(layer "B.CrtYd")
		)
		(fp_line
			(start 0.4064 -0.8128)
			(end -0.4064 -0.8128)
			(stroke
				(width 0.0254)
				(type default)
			)
			(layer "B.Fab")
		)
		(fp_line
			(start -0.4064 -0.8128)
			(end -0.4064 0.8128)
			(stroke
				(width 0.0254)
				(type default)
			)
			(layer "B.Fab")
		)
		(fp_line
			(start 0.4064 0.8128)
			(end 0.4064 -0.8128)
			(stroke
				(width 0.0254)
				(type default)
			)
			(layer "B.Fab")
		)
		(fp_line
			(start -0.4064 0.8128)
			(end 0.4064 0.8128)
			(stroke
				(width 0.0254)
				(type default)
			)
			(layer "B.Fab")
		)
		(pad "1" smd rect
			(at 0 -0.8001 270)
			(size 0.762 0.9652)
			(layers "B.Cu" "B.Mask" "B.Paste")
			(net "10N2233")
		)
		(pad "2" smd rect
			(at 0 0.8001 270)
			(size 0.762 0.9652)
			(layers "B.Cu" "B.Mask" "B.Paste")
			(net "10N2259")
		)
		(zone
			(layer "B.Cu")
			(hatch none 0.5)
			(connect_pads
				(clearance 0)
			)
			(min_thickness 0.25)
			(keepout
				(tracks not_allowed)
				(vias allowed)
				(pads allowed)
				(copperpour not_allowed)
				(footprints allowed)
			)
			(placement
				(enabled no)
				(sheetname "")
			)
			(fill
				(thermal_gap 0.5)
				(thermal_bridge_width 0.5)
				(island_removal_mode 0)
			)
			(polygon
				(pts
					(xy 51.69408 35.35426) (xy 51.69408 35.48126) (xy 52.20208 35.48126) (xy 52.20208 35.35426)
				)
			)
		)
	)
	(footprint ""
		(layer "B.Cu")
		(at 66.929 23.622 90)
		(property "Reference" "R272"
			(at 0.98933 2.032 0)
			(unlocked yes)
			(layer "B.SilkS")
			(effects
				(font
					(size 0.7874 0.5842)
					(thickness 0.127)
				)
				(justify mirror)
			)
		)
		(property "Value" ""
			(at 0 0 90)
			(layer "B.Fab")
			(effects
				(font
					(size 1.27 1.27)
				)
				(justify mirror)
			)
		)
		(duplicate_pad_numbers_are_jumpers no)
		(fp_circle
			(center 0 0)
			(end 0 0.104648)
			(stroke
				(width 0.1016)
				(type default)
			)
			(fill no)
			(layer "B.SilkS")
		)
		(fp_poly
			(pts
				(xy 0.381 -0.889) (xy 0.381 0.889) (xy -0.381 0.889) (xy -0.381 -0.889)
			)
			(stroke
				(width 0)
				(type default)
			)
			(fill no)
			(layer "B.CrtYd")
		)
		(fp_line
			(start 0.508 -1.016)
			(end 0.254 -1.016)
			(stroke
				(width 0.0254)
				(type default)
			)
			(layer "B.Fab")
		)
		(fp_line
			(start 0.254 -1.016)
			(end -0.508 -1.016)
			(stroke
				(width 0.0254)
				(type default)
			)
			(layer "B.Fab")
		)
		(fp_line
			(start -0.508 -1.016)
			(end -0.508 1.016)
			(stroke
				(width 0.0254)
				(type default)
			)
			(layer "B.Fab")
		)
		(fp_line
			(start 0.508 1.016)
			(end 0.508 -1.016)
			(stroke
				(width 0.0254)
				(type default)
			)
			(layer "B.Fab")
		)
		(fp_line
			(start -0.508 1.016)
			(end 0.508 1.016)
			(stroke
				(width 0.0254)
				(type default)
			)
			(layer "B.Fab")
		)
		(pad "1" smd custom
			(at 0 -0.500126 270)
			(size 0.127 0.127)
			(layers "B.Cu" "B.Mask" "B.Paste")
			(net "6N3961")
			(options
				(clearance outline)
				(anchor circle)
			)
			(primitives
				(gr_poly
					(pts
						(xy -0.1778 0.254) (xy 0.1778 0.254) (xy 0.254 0.1778) (xy 0.254 -0.1778) (xy 0.1778 -0.254) (xy -0.1778 -0.254)
						(xy -0.254 -0.1778) (xy -0.254 0.1778)
					)
					(width 0)
					(fill yes)
				)
			)
		)
		(pad "2" smd custom
			(at 0 0.500126 270)
			(size 0.127 0.127)
			(layers "B.Cu" "B.Mask" "B.Paste")
			(net "DDR0_32A_DRAMRST_L")
			(options
				(clearance outline)
				(anchor circle)
			)
			(primitives
				(gr_poly
					(pts
						(xy -0.1778 0.254) (xy 0.1778 0.254) (xy 0.254 0.1778) (xy 0.254 -0.1778) (xy 0.1778 -0.254) (xy -0.1778 -0.254)
						(xy -0.254 -0.1778) (xy -0.254 0.1778)
					)
					(width 0)
					(fill yes)
				)
			)
		)
	)
	(footprint ""
		(layer "B.Cu")
		(at 61.849 47.625)
		(property "Reference" "TP35"
			(at 0.889 1.80467 0)
			(unlocked yes)
			(layer "B.SilkS")
			(effects
				(font
					(size 0.7874 0.5842)
					(thickness 0.127)
				)
				(justify left mirror)
			)
		)
		(property "Value" "*"
			(at 0.4826 -0.14732 0)
			(unlocked yes)
			(layer "B.Fab")
			(hide yes)
			(effects
				(font
					(size 1.27 0.9652)
					(thickness 0.000001)
				)
				(justify left mirror)
			)
		)
		(property "Device Type" "TP_SMALL"
			(at 0.4826 -0.14732 0)
			(unlocked yes)
			(layer "B.Fab")
			(hide yes)
			(effects
				(font
					(size 1.27 0.9652)
					(thickness 0.000001)
				)
				(justify left mirror)
			)
		)
		(duplicate_pad_numbers_are_jumpers no)
		(fp_line
			(start -0.8636 -0.8636)
			(end 0.8636 -0.8636)
			(stroke
				(width 0.1524)
				(type default)
			)
			(layer "B.SilkS")
		)
		(fp_line
			(start -0.8636 0.8636)
			(end -0.8636 -0.8636)
			(stroke
				(width 0.1524)
				(type default)
			)
			(layer "B.SilkS")
		)
		(fp_line
			(start 0.8636 -0.8636)
			(end 0.8636 0.8636)
			(stroke
				(width 0.1524)
				(type default)
			)
			(layer "B.SilkS")
		)
		(fp_line
			(start 0.8636 0.8636)
			(end -0.8636 0.8636)
			(stroke
				(width 0.1524)
				(type default)
			)
			(layer "B.SilkS")
		)
		(fp_poly
			(pts
				(xy 0.635 -0.635) (xy 0.635 0.635) (xy -0.635 0.635) (xy -0.635 -0.635)
			)
			(stroke
				(width 0)
				(type default)
			)
			(fill no)
			(layer "B.CrtYd")
		)
		(pad "1" smd rect
			(at 0 0 180)
			(size 1.27 1.27)
			(layers "B.Cu" "B.Mask" "B.Paste")
			(net "CORE_FB_PH1_THERM_L")
		)
	)
	(footprint ""
		(layer "B.Cu")
		(at 26.924 22.2758 180)
		(property "Reference" "R47"
			(at 0.15367 -2.8702 270)
			(unlocked yes)
			(layer "B.SilkS")
			(effects
				(font
					(size 0.7874 0.5842)
					(thickness 0.127)
				)
				(justify left mirror)
			)
		)
		(property "Value" "4.75K"
			(at 0.148158 1.3462 90)
			(unlocked yes)
			(layer "B.Fab")
			(hide yes)
			(effects
				(font
					(size 1.27 0.9652)
					(thickness 0.000001)
				)
				(justify left mirror)
			)
		)
		(property "Device Type" "REST4024"
			(at 0.148158 1.3462 90)
			(unlocked yes)
			(layer "B.Fab")
			(hide yes)
			(effects
				(font
					(size 1.27 0.9652)
					(thickness 0.000001)
				)
				(justify left mirror)
			)
		)
		(duplicate_pad_numbers_are_jumpers no)
		(fp_poly
			(pts
				(xy -0.635 1.0668) (xy -0.635 -1.0668) (xy 0.635 -1.0668) (xy 0.635 1.0668)
			)
			(stroke
				(width 0)
				(type default)
			)
			(fill no)
			(layer "B.CrtYd")
		)
		(fp_line
			(start 0.254 0.508)
			(end 0.254 -0.508)
			(stroke
				(width 0.0254)
				(type default)
			)
			(layer "B.Fab")
		)
		(fp_line
			(start 0.254 -0.508)
			(end -0.254 -0.508)
			(stroke
				(width 0.0254)
				(type default)
			)
			(layer "B.Fab")
		)
		(fp_line
			(start -0.254 0.508)
			(end 0.254 0.508)
			(stroke
				(width 0.0254)
				(type default)
			)
			(layer "B.Fab")
		)
		(fp_line
			(start -0.254 -0.508)
			(end -0.254 0.508)
			(stroke
				(width 0.0254)
				(type default)
			)
			(layer "B.Fab")
		)
		(pad "1" smd rect
			(at 0 -0.4191)
			(size 0.508 0.5334)
			(layers "B.Cu" "B.Mask" "B.Paste")
			(net "_NFP_CLK_NRESET_L")
		)
		(pad "2" smd rect
			(at 0 0.4191)
			(size 0.508 0.5334)
			(layers "B.Cu" "B.Mask" "B.Paste")
			(net "GND")
		)
		(zone
			(layer "B.Cu")
			(hatch none 0.5)
			(connect_pads
				(clearance 0)
			)
			(min_thickness 0.25)
			(keepout
				(tracks not_allowed)
				(vias allowed)
				(pads allowed)
				(copperpour not_allowed)
				(footprints allowed)
			)
			(placement
				(enabled no)
				(sheetname "")
			)
			(fill
				(thermal_gap 0.5)
				(thermal_bridge_width 0.5)
				(island_removal_mode 0)
			)
			(polygon
				(pts
					(xy 26.9494 22.3012) (xy 26.9494 22.2504) (xy 26.8986 22.2504) (xy 26.8986 22.3012)
				)
			)
		)
	)
	(footprint ""
		(layer "B.Cu")
		(at 29.083 40.513)
		(property "Reference" "TP39"
			(at 3.937 -0.35433 0)
			(unlocked yes)
			(layer "B.SilkS")
			(effects
				(font
					(size 0.7874 0.5842)
					(thickness 0.127)
				)
				(justify left mirror)
			)
		)
		(property "Value" "*"
			(at 0.4826 -0.14732 0)
			(unlocked yes)
			(layer "B.Fab")
			(hide yes)
			(effects
				(font
					(size 1.27 0.9652)
					(thickness 0.000001)
				)
				(justify left mirror)
			)
		)
		(property "Device Type" "TP_SMALL"
			(at 0.4826 -0.14732 0)
			(unlocked yes)
			(layer "B.Fab")
			(hide yes)
			(effects
				(font
					(size 1.27 0.9652)
					(thickness 0.000001)
				)
				(justify left mirror)
			)
		)
		(duplicate_pad_numbers_are_jumpers no)
		(fp_line
			(start -0.8636 -0.8636)
			(end 0.8636 -0.8636)
			(stroke
				(width 0.1524)
				(type default)
			)
			(layer "B.SilkS")
		)
		(fp_line
			(start -0.8636 0.8636)
			(end -0.8636 -0.8636)
			(stroke
				(width 0.1524)
				(type default)
			)
			(layer "B.SilkS")
		)
		(fp_line
			(start 0.8636 -0.8636)
			(end 0.8636 0.8636)
			(stroke
				(width 0.1524)
				(type default)
			)
			(layer "B.SilkS")
		)
		(fp_line
			(start 0.8636 0.8636)
			(end -0.8636 0.8636)
			(stroke
				(width 0.1524)
				(type default)
			)
			(layer "B.SilkS")
		)
		(fp_poly
			(pts
				(xy 0.635 -0.635) (xy 0.635 0.635) (xy -0.635 0.635) (xy -0.635 -0.635)
			)
			(stroke
				(width 0)
				(type default)
			)
			(fill no)
			(layer "B.CrtYd")
		)
		(pad "1" smd rect
			(at 0 0 180)
			(size 1.27 1.27)
			(layers "B.Cu" "B.Mask" "B.Paste")
			(net "GND")
		)
	)
	(footprint ""
		(layer "B.Cu")
		(at 84.250987 2.699004)
		(property "Reference" "V1_A-A13"
			(at 0 0 0)
			(layer "B.SilkS")
			(hide yes)
			(effects
				(font
					(size 1.27 1.27)
				)
				(justify mirror)
			)
		)
		(property "Value" ""
			(at 0 0 0)
			(layer "B.Fab")
			(effects
				(font
					(size 1.27 1.27)
				)
				(justify mirror)
			)
		)
		(duplicate_pad_numbers_are_jumpers no)
		(pad "1" thru_hole circle
			(at 0 0 180)
			(size 0.4572 0.4572)
			(drill 0.20574)
			(layers "*.Cu" "*.Mask")
			(remove_unused_layers no)
			(net "DDR0_32A_A13")
			(clearance 0.1143)
			(thermal_gap 0.1143)
		)
	)
	(footprint ""
		(layer "B.Cu")
		(at 83.450989 25.013006)
		(property "Reference" "V3_A-A07"
			(at 0 0 0)
			(layer "B.SilkS")
			(hide yes)
			(effects
				(font
					(size 1.27 1.27)
				)
				(justify mirror)
			)
		)
		(property "Value" ""
			(at 0 0 0)
			(layer "B.Fab")
			(effects
				(font
					(size 1.27 1.27)
				)
				(justify mirror)
			)
		)
		(duplicate_pad_numbers_are_jumpers no)
		(pad "1" thru_hole circle
			(at 0 0 180)
			(size 0.4572 0.4572)
			(drill 0.20574)
			(layers "*.Cu" "*.Mask")
			(remove_unused_layers no)
			(net "DDR0_32A_A7")
			(clearance 0.1143)
			(thermal_gap 0.1143)
		)
	)
	(footprint ""
		(layer "B.Cu")
		(at 4.572 17.4498)
		(property "Reference" "R376"
			(at 0.98933 3.8862 270)
			(unlocked yes)
			(layer "B.SilkS")
			(effects
				(font
					(size 0.7874 0.5842)
					(thickness 0.127)
				)
				(justify left mirror)
			)
		)
		(property "Value" "4.75K"
			(at 0.148158 1.3462 270)
			(unlocked yes)
			(layer "B.Fab")
			(hide yes)
			(effects
				(font
					(size 1.27 0.9652)
					(thickness 0.000001)
				)
				(justify left mirror)
			)
		)
		(property "Device Type" "REST4024"
			(at 0.148158 1.3462 270)
			(unlocked yes)
			(layer "B.Fab")
			(hide yes)
			(effects
				(font
					(size 1.27 0.9652)
					(thickness 0.000001)
				)
				(justify left mirror)
			)
		)
		(duplicate_pad_numbers_are_jumpers no)
		(fp_poly
			(pts
				(xy -0.635 1.0668) (xy -0.635 -1.0668) (xy 0.635 -1.0668) (xy 0.635 1.0668)
			)
			(stroke
				(width 0)
				(type default)
			)
			(fill no)
			(layer "B.CrtYd")
		)
		(fp_line
			(start -0.254 -0.508)
			(end -0.254 0.508)
			(stroke
				(width 0.0254)
				(type default)
			)
			(layer "B.Fab")
		)
		(fp_line
			(start -0.254 0.508)
			(end 0.254 0.508)
			(stroke
				(width 0.0254)
				(type default)
			)
			(layer "B.Fab")
		)
		(fp_line
			(start 0.254 -0.508)
			(end -0.254 -0.508)
			(stroke
				(width 0.0254)
				(type default)
			)
			(layer "B.Fab")
		)
		(fp_line
			(start 0.254 0.508)
			(end 0.254 -0.508)
			(stroke
				(width 0.0254)
				(type default)
			)
			(layer "B.Fab")
		)
		(pad "1" smd rect
			(at 0 -0.4191 180)
			(size 0.508 0.5334)
			(layers "B.Cu" "B.Mask" "B.Paste")
			(net "13N4351")
		)
		(pad "2" smd rect
			(at 0 0.4191 180)
			(size 0.508 0.5334)
			(layers "B.Cu" "B.Mask" "B.Paste")
			(net "GND")
		)
		(zone
			(layer "B.Cu")
			(hatch none 0.5)
			(connect_pads
				(clearance 0)
			)
			(min_thickness 0.25)
			(keepout
				(tracks not_allowed)
				(vias allowed)
				(pads allowed)
				(copperpour not_allowed)
				(footprints allowed)
			)
			(placement
				(enabled no)
				(sheetname "")
			)
			(fill
				(thermal_gap 0.5)
				(thermal_bridge_width 0.5)
				(island_removal_mode 0)
			)
			(polygon
				(pts
					(xy 4.5466 17.4244) (xy 4.5466 17.4752) (xy 4.5974 17.4752) (xy 4.5974 17.4244)
				)
			)
		)
	)
	(footprint ""
		(layer "B.Cu")
		(at 43.5229 38.735 180)
		(property "Reference" "C46"
			(at 0.87757 -0.254 270)
			(unlocked yes)
			(layer "B.SilkS")
			(effects
				(font
					(size 0.7874 0.5842)
					(thickness 0.127)
				)
				(justify left mirror)
			)
		)
		(property "Value" "1000PF"
			(at 0.091846 0.2921 90)
			(unlocked yes)
			(layer "B.Fab")
			(hide yes)
			(effects
				(font
					(size 0.7874 0.5842)
					(thickness 0.2032)
				)
				(justify left mirror)
			)
		)
		(property "Device Type" "CAPC0083"
			(at 0.091846 0.2921 90)
			(unlocked yes)
			(layer "B.Fab")
			(hide yes)
			(effects
				(font
					(size 0.7874 0.5842)
					(thickness 0.2032)
				)
				(justify left mirror)
			)
		)
		(duplicate_pad_numbers_are_jumpers no)
		(fp_poly
			(pts
				(xy -0.635 1.0668) (xy -0.635 -1.0668) (xy 0.635 -1.0668) (xy 0.635 1.0668)
			)
			(stroke
				(width 0)
				(type default)
			)
			(fill no)
			(layer "B.CrtYd")
		)
		(fp_line
			(start 0.254 0.508)
			(end 0.254 -0.508)
			(stroke
				(width 0.0254)
				(type default)
			)
			(layer "B.Fab")
		)
		(fp_line
			(start 0.254 -0.508)
			(end -0.254 -0.508)
			(stroke
				(width 0.0254)
				(type default)
			)
			(layer "B.Fab")
		)
		(fp_line
			(start -0.254 0.508)
			(end 0.254 0.508)
			(stroke
				(width 0.0254)
				(type default)
			)
			(layer "B.Fab")
		)
		(fp_line
			(start -0.254 -0.508)
			(end -0.254 0.508)
			(stroke
				(width 0.0254)
				(type default)
			)
			(layer "B.Fab")
		)
		(pad "1" smd rect
			(at 0 -0.4191)
			(size 0.508 0.5334)
			(layers "B.Cu" "B.Mask" "B.Paste")
			(net "10N2223")
		)
		(pad "2" smd rect
			(at 0 0.4191)
			(size 0.508 0.5334)
			(layers "B.Cu" "B.Mask" "B.Paste")
			(net "GND")
		)
		(zone
			(layer "B.Cu")
			(hatch none 0.5)
			(connect_pads
				(clearance 0)
			)
			(min_thickness 0.25)
			(keepout
				(tracks not_allowed)
				(vias allowed)
				(pads allowed)
				(copperpour not_allowed)
				(footprints allowed)
			)
			(placement
				(enabled no)
				(sheetname "")
			)
			(fill
				(thermal_gap 0.5)
				(thermal_bridge_width 0.5)
				(island_removal_mode 0)
			)
			(polygon
				(pts
					(xy 43.5483 38.7604) (xy 43.5483 38.7096) (xy 43.4975 38.7096) (xy 43.4975 38.7604)
				)
			)
		)
	)
	(footprint ""
		(layer "B.Cu")
		(at 82.65099 6.698996)
		(property "Reference" "V1_A-A01"
			(at 0 0 0)
			(layer "B.SilkS")
			(hide yes)
			(effects
				(font
					(size 1.27 1.27)
				)
				(justify mirror)
			)
		)
		(property "Value" ""
			(at 0 0 0)
			(layer "B.Fab")
			(effects
				(font
					(size 1.27 1.27)
				)
				(justify mirror)
			)
		)
		(duplicate_pad_numbers_are_jumpers no)
		(pad "1" thru_hole circle
			(at 0 0 180)
			(size 0.4572 0.4572)
			(drill 0.20574)
			(layers "*.Cu" "*.Mask")
			(remove_unused_layers no)
			(net "DDR0_32A_A1")
			(clearance 0.1143)
			(thermal_gap 0.1143)
		)
	)
	(footprint ""
		(layer "B.Cu")
		(at 81.050994 13.456006)
		(property "Reference" "V2_A-BA0"
			(at 0 0 0)
			(layer "B.SilkS")
			(hide yes)
			(effects
				(font
					(size 1.27 1.27)
				)
				(justify mirror)
			)
		)
		(property "Value" ""
			(at 0 0 0)
			(layer "B.Fab")
			(effects
				(font
					(size 1.27 1.27)
				)
				(justify mirror)
			)
		)
		(duplicate_pad_numbers_are_jumpers no)
		(pad "1" thru_hole circle
			(at 0 0 180)
			(size 0.4572 0.4572)
			(drill 0.20574)
			(layers "*.Cu" "*.Mask")
			(remove_unused_layers no)
			(net "DDR0_32A_BA0")
			(clearance 0.1143)
			(thermal_gap 0.1143)
		)
	)
	(footprint ""
		(layer "B.Cu")
		(at 47.0789 35.7124 180)
		(property "Reference" "C204"
			(at 0 0 0)
			(layer "B.SilkS")
			(hide yes)
			(effects
				(font
					(size 1.27 1.27)
				)
				(justify mirror)
			)
		)
		(property "Value" "1UF"
			(at 0.091846 0.2921 90)
			(unlocked yes)
			(layer "B.Fab")
			(hide yes)
			(effects
				(font
					(size 0.7874 0.5842)
					(thickness 0.2032)
				)
				(justify left mirror)
			)
		)
		(property "Device Type" "CAPC0028"
			(at 0.091846 0.2921 90)
			(unlocked yes)
			(layer "B.Fab")
			(hide yes)
			(effects
				(font
					(size 0.7874 0.5842)
					(thickness 0.2032)
				)
				(justify left mirror)
			)
		)
		(duplicate_pad_numbers_are_jumpers no)
		(fp_poly
			(pts
				(xy -0.635 1.0668) (xy -0.635 -1.0668) (xy 0.635 -1.0668) (xy 0.635 1.0668)
			)
			(stroke
				(width 0)
				(type default)
			)
			(fill no)
			(layer "B.CrtYd")
		)
		(fp_line
			(start 0.254 0.508)
			(end 0.254 -0.508)
			(stroke
				(width 0.0254)
				(type default)
			)
			(layer "B.Fab")
		)
		(fp_line
			(start 0.254 -0.508)
			(end -0.254 -0.508)
			(stroke
				(width 0.0254)
				(type default)
			)
			(layer "B.Fab")
		)
		(fp_line
			(start -0.254 0.508)
			(end 0.254 0.508)
			(stroke
				(width 0.0254)
				(type default)
			)
			(layer "B.Fab")
		)
		(fp_line
			(start -0.254 -0.508)
			(end -0.254 0.508)
			(stroke
				(width 0.0254)
				(type default)
			)
			(layer "B.Fab")
		)
		(pad "1" smd rect
			(at 0 -0.4191)
			(size 0.508 0.5334)
			(layers "B.Cu" "B.Mask" "B.Paste")
			(net "VDD_5.0V")
		)
		(pad "2" smd rect
			(at 0 0.4191)
			(size 0.508 0.5334)
			(layers "B.Cu" "B.Mask" "B.Paste")
			(net "GND")
		)
		(zone
			(layer "B.Cu")
			(hatch none 0.5)
			(connect_pads
				(clearance 0)
			)
			(min_thickness 0.25)
			(keepout
				(tracks not_allowed)
				(vias allowed)
				(pads allowed)
				(copperpour not_allowed)
				(footprints allowed)
			)
			(placement
				(enabled no)
				(sheetname "")
			)
			(fill
				(thermal_gap 0.5)
				(thermal_bridge_width 0.5)
				(island_removal_mode 0)
			)
			(polygon
				(pts
					(xy 47.1043 35.7378) (xy 47.1043 35.687) (xy 47.0535 35.687) (xy 47.0535 35.7378)
				)
			)
		)
	)
	(footprint ""
		(layer "B.Cu")
		(at 26.543 32.639)
		(property "Reference" "R179"
			(at -0.78867 3.048 270)
			(unlocked yes)
			(layer "B.SilkS")
			(effects
				(font
					(size 0.7874 0.5842)
					(thickness 0.127)
				)
				(justify left mirror)
			)
		)
		(property "Value" "0"
			(at 0.148158 1.3462 270)
			(unlocked yes)
			(layer "B.Fab")
			(hide yes)
			(effects
				(font
					(size 1.27 0.9652)
					(thickness 0.000001)
				)
				(justify left mirror)
			)
		)
		(property "Device Type" "REST1111"
			(at 0.148158 1.3462 270)
			(unlocked yes)
			(layer "B.Fab")
			(hide yes)
			(effects
				(font
					(size 1.27 0.9652)
					(thickness 0.000001)
				)
				(justify left mirror)
			)
		)
		(duplicate_pad_numbers_are_jumpers no)
		(fp_poly
			(pts
				(xy -0.635 1.0668) (xy -0.635 -1.0668) (xy 0.635 -1.0668) (xy 0.635 1.0668)
			)
			(stroke
				(width 0)
				(type default)
			)
			(fill no)
			(layer "B.CrtYd")
		)
		(fp_line
			(start -0.254 -0.508)
			(end -0.254 0.508)
			(stroke
				(width 0.0254)
				(type default)
			)
			(layer "B.Fab")
		)
		(fp_line
			(start -0.254 0.508)
			(end 0.254 0.508)
			(stroke
				(width 0.0254)
				(type default)
			)
			(layer "B.Fab")
		)
		(fp_line
			(start 0.254 -0.508)
			(end -0.254 -0.508)
			(stroke
				(width 0.0254)
				(type default)
			)
			(layer "B.Fab")
		)
		(fp_line
			(start 0.254 0.508)
			(end 0.254 -0.508)
			(stroke
				(width 0.0254)
				(type default)
			)
			(layer "B.Fab")
		)
		(pad "1" smd rect
			(at 0 -0.4191 180)
			(size 0.508 0.5334)
			(layers "B.Cu" "B.Mask" "B.Paste")
			(net "NFP_CORE_VID0")
		)
		(pad "2" smd rect
			(at 0 0.4191 180)
			(size 0.508 0.5334)
			(layers "B.Cu" "B.Mask" "B.Paste")
			(net "_NFP_CORE_VID0")
		)
		(zone
			(layer "B.Cu")
			(hatch none 0.5)
			(connect_pads
				(clearance 0)
			)
			(min_thickness 0.25)
			(keepout
				(tracks not_allowed)
				(vias allowed)
				(pads allowed)
				(copperpour not_allowed)
				(footprints allowed)
			)
			(placement
				(enabled no)
				(sheetname "")
			)
			(fill
				(thermal_gap 0.5)
				(thermal_bridge_width 0.5)
				(island_removal_mode 0)
			)
			(polygon
				(pts
					(xy 26.5176 32.6136) (xy 26.5176 32.6644) (xy 26.5684 32.6644) (xy 26.5684 32.6136)
				)
			)
		)
	)
	(footprint ""
		(layer "B.Cu")
		(at 48.237013 29.541978)
		(property "Reference" "C200"
			(at -0.003683 -2.998978 270)
			(unlocked yes)
			(layer "B.SilkS")
			(effects
				(font
					(size 0.7874 0.5842)
					(thickness 0.127)
				)
				(justify mirror)
			)
		)
		(property "Value" ""
			(at 0 0 0)
			(layer "B.Fab")
			(effects
				(font
					(size 1.27 1.27)
				)
				(justify mirror)
			)
		)
		(duplicate_pad_numbers_are_jumpers no)
		(fp_circle
			(center 0 0)
			(end 0.104648 0)
			(stroke
				(width 0.1016)
				(type default)
			)
			(fill no)
			(layer "B.SilkS")
		)
		(fp_poly
			(pts
				(xy 0.381 -0.889) (xy 0.381 0.889) (xy -0.381 0.889) (xy -0.381 -0.889)
			)
			(stroke
				(width 0)
				(type default)
			)
			(fill no)
			(layer "B.CrtYd")
		)
		(fp_line
			(start -0.508 -1.016)
			(end -0.508 1.016)
			(stroke
				(width 0.0254)
				(type default)
			)
			(layer "B.Fab")
		)
		(fp_line
			(start -0.508 1.016)
			(end 0.508 1.016)
			(stroke
				(width 0.0254)
				(type default)
			)
			(layer "B.Fab")
		)
		(fp_line
			(start 0.254 -1.016)
			(end -0.508 -1.016)
			(stroke
				(width 0.0254)
				(type default)
			)
			(layer "B.Fab")
		)
		(fp_line
			(start 0.508 -1.016)
			(end 0.254 -1.016)
			(stroke
				(width 0.0254)
				(type default)
			)
			(layer "B.Fab")
		)
		(fp_line
			(start 0.508 1.016)
			(end 0.508 -1.016)
			(stroke
				(width 0.0254)
				(type default)
			)
			(layer "B.Fab")
		)
		(pad "1" smd custom
			(at 0 -0.500126 180)
			(size 0.127 0.127)
			(layers "B.Cu" "B.Mask" "B.Paste")
			(net "VDD_CORE")
			(options
				(clearance outline)
				(anchor circle)
			)
			(primitives
				(gr_poly
					(pts
						(xy -0.1778 0.254) (xy 0.1778 0.254) (xy 0.254 0.1778) (xy 0.254 -0.1778) (xy 0.1778 -0.254) (xy -0.1778 -0.254)
						(xy -0.254 -0.1778) (xy -0.254 0.1778)
					)
					(width 0)
					(fill yes)
				)
			)
		)
		(pad "2" smd custom
			(at 0 0.500126 180)
			(size 0.127 0.127)
			(layers "B.Cu" "B.Mask" "B.Paste")
			(net "GND")
			(options
				(clearance outline)
				(anchor circle)
			)
			(primitives
				(gr_poly
					(pts
						(xy -0.1778 0.254) (xy 0.1778 0.254) (xy 0.254 0.1778) (xy 0.254 -0.1778) (xy 0.1778 -0.254) (xy -0.1778 -0.254)
						(xy -0.254 -0.1778) (xy -0.254 0.1778)
					)
					(width 0)
					(fill yes)
				)
			)
		)
	)
	(footprint ""
		(layer "B.Cu")
		(at 39.237031 14.542008)
		(property "Reference" "R45"
			(at 0.005969 -1.434338 0)
			(unlocked yes)
			(layer "B.SilkS")
			(effects
				(font
					(size 0.7874 0.5842)
					(thickness 0.127)
				)
				(justify mirror)
			)
		)
		(property "Value" ""
			(at 0 0 0)
			(layer "B.Fab")
			(effects
				(font
					(size 1.27 1.27)
				)
				(justify mirror)
			)
		)
		(duplicate_pad_numbers_are_jumpers no)
		(fp_circle
			(center 0 0)
			(end 0.104648 0)
			(stroke
				(width 0.1016)
				(type default)
			)
			(fill no)
			(layer "B.SilkS")
		)
		(fp_poly
			(pts
				(xy 0.381 -0.889) (xy 0.381 0.889) (xy -0.381 0.889) (xy -0.381 -0.889)
			)
			(stroke
				(width 0)
				(type default)
			)
			(fill no)
			(layer "B.CrtYd")
		)
		(fp_line
			(start -0.508 -1.016)
			(end -0.508 1.016)
			(stroke
				(width 0.0254)
				(type default)
			)
			(layer "B.Fab")
		)
		(fp_line
			(start -0.508 1.016)
			(end 0.508 1.016)
			(stroke
				(width 0.0254)
				(type default)
			)
			(layer "B.Fab")
		)
		(fp_line
			(start 0.254 -1.016)
			(end -0.508 -1.016)
			(stroke
				(width 0.0254)
				(type default)
			)
			(layer "B.Fab")
		)
		(fp_line
			(start 0.508 -1.016)
			(end 0.254 -1.016)
			(stroke
				(width 0.0254)
				(type default)
			)
			(layer "B.Fab")
		)
		(fp_line
			(start 0.508 1.016)
			(end 0.508 -1.016)
			(stroke
				(width 0.0254)
				(type default)
			)
			(layer "B.Fab")
		)
		(pad "1" smd custom
			(at 0 -0.500126 180)
			(size 0.127 0.127)
			(layers "B.Cu" "B.Mask" "B.Paste")
			(net "PGRM_JTAG_TCK")
			(options
				(clearance outline)
				(anchor circle)
			)
			(primitives
				(gr_poly
					(pts
						(xy -0.1778 0.254) (xy 0.1778 0.254) (xy 0.254 0.1778) (xy 0.254 -0.1778) (xy 0.1778 -0.254) (xy -0.1778 -0.254)
						(xy -0.254 -0.1778) (xy -0.254 0.1778)
					)
					(width 0)
					(fill yes)
				)
			)
		)
		(pad "2" smd custom
			(at 0 0.500126 180)
			(size 0.127 0.127)
			(layers "B.Cu" "B.Mask" "B.Paste")
			(net "GND")
			(options
				(clearance outline)
				(anchor circle)
			)
			(primitives
				(gr_poly
					(pts
						(xy -0.1778 0.254) (xy 0.1778 0.254) (xy 0.254 0.1778) (xy 0.254 -0.1778) (xy 0.1778 -0.254) (xy -0.1778 -0.254)
						(xy -0.254 -0.1778) (xy -0.254 0.1778)
					)
					(width 0)
					(fill yes)
				)
			)
		)
	)
	(footprint ""
		(layer "B.Cu")
		(at 69.85 35.56 90)
		(property "Reference" "C32"
			(at -1.29667 1.016 0)
			(unlocked yes)
			(layer "B.SilkS")
			(effects
				(font
					(size 0.7874 0.5842)
					(thickness 0.127)
				)
				(justify left mirror)
			)
		)
		(property "Value" "0.22UF"
			(at 0.148158 1.7526 0)
			(unlocked yes)
			(layer "B.Fab")
			(hide yes)
			(effects
				(font
					(size 1.27 0.9652)
					(thickness 0.000001)
				)
				(justify left mirror)
			)
		)
		(property "Device Type" "CAPC0022"
			(at 0.148158 1.7526 0)
			(unlocked yes)
			(layer "B.Fab")
			(hide yes)
			(effects
				(font
					(size 1.27 0.9652)
					(thickness 0.000001)
				)
				(justify left mirror)
			)
		)
		(duplicate_pad_numbers_are_jumpers no)
		(fp_circle
			(center 0 0)
			(end 0 0.127)
			(stroke
				(width 0.2032)
				(type default)
			)
			(fill no)
			(layer "B.SilkS")
		)
		(fp_poly
			(pts
				(xy -0.7874 -1.6637) (xy 0.7874 -1.6637) (xy 0.7874 1.6637) (xy -0.7874 1.6637)
			)
			(stroke
				(width 0)
				(type default)
			)
			(fill no)
			(layer "B.CrtYd")
		)
		(fp_line
			(start 0.4064 -0.7874)
			(end -0.4064 -0.7874)
			(stroke
				(width 0.0254)
				(type default)
			)
			(layer "B.Fab")
		)
		(fp_line
			(start -0.4064 -0.7874)
			(end -0.4064 0.8128)
			(stroke
				(width 0.0254)
				(type default)
			)
			(layer "B.Fab")
		)
		(fp_line
			(start 0.4064 0.8128)
			(end 0.4064 -0.7874)
			(stroke
				(width 0.0254)
				(type default)
			)
			(layer "B.Fab")
		)
		(fp_line
			(start -0.4064 0.8128)
			(end 0.4064 0.8128)
			(stroke
				(width 0.0254)
				(type default)
			)
			(layer "B.Fab")
		)
		(pad "1" smd rect
			(at 0 -0.8001 270)
			(size 0.8636 0.9652)
			(layers "B.Cu" "B.Mask" "B.Paste")
			(net "10N2229")
		)
		(pad "2" smd rect
			(at 0 0.8001 270)
			(size 0.8636 0.9652)
			(layers "B.Cu" "B.Mask" "B.Paste")
			(net "10N2228")
		)
		(zone
			(layer "B.Cu")
			(hatch none 0.5)
			(connect_pads
				(clearance 0)
			)
			(min_thickness 0.25)
			(keepout
				(tracks not_allowed)
				(vias allowed)
				(pads allowed)
				(copperpour not_allowed)
				(footprints allowed)
			)
			(placement
				(enabled no)
				(sheetname "")
			)
			(fill
				(thermal_gap 0.5)
				(thermal_bridge_width 0.5)
				(island_removal_mode 0)
			)
			(polygon
				(pts
					(xy 69.596 35.4965) (xy 69.596 35.6235) (xy 70.104 35.6235) (xy 70.104 35.4965)
				)
			)
		)
	)
	(footprint ""
		(layer "B.Cu")
		(at 19.05 45.847 180)
		(property "Reference" "J5"
			(at 9.525 4.6355 0)
			(unlocked yes)
			(layer "B.SilkS")
			(effects
				(font
					(size 1.27 0.9652)
					(thickness 0.1524)
				)
				(justify left mirror)
			)
		)
		(property "Value" "*"
			(at 4.2926 -0.14732 180)
			(unlocked yes)
			(layer "B.Fab")
			(hide yes)
			(effects
				(font
					(size 1.27 0.9652)
					(thickness 0.000001)
				)
				(justify left mirror)
			)
		)
		(property "Device Type" "CONM0077"
			(at 4.2926 -0.14732 180)
			(unlocked yes)
			(layer "B.Fab")
			(hide yes)
			(effects
				(font
					(size 1.27 0.9652)
					(thickness 0.000001)
				)
				(justify left mirror)
			)
		)
		(duplicate_pad_numbers_are_jumpers no)
		(fp_line
			(start 13.081 2.921)
			(end 9.652 2.921)
			(stroke
				(width 0.2032)
				(type default)
			)
			(layer "B.SilkS")
		)
		(fp_line
			(start 13.081 -3.429)
			(end 13.081 2.921)
			(stroke
				(width 0.2032)
				(type default)
			)
			(layer "B.SilkS")
		)
		(fp_line
			(start 11.43 1.778)
			(end 12.065 2.921)
			(stroke
				(width 0.2032)
				(type default)
			)
			(layer "B.SilkS")
		)
		(fp_line
			(start 11.303 -2.921)
			(end 11.303 -3.429)
			(stroke
				(width 0.2032)
				(type default)
			)
			(layer "B.SilkS")
		)
		(fp_line
			(start 11.303 -3.429)
			(end 13.081 -3.429)
			(stroke
				(width 0.2032)
				(type default)
			)
			(layer "B.SilkS")
		)
		(fp_line
			(start 10.795 2.921)
			(end 11.43 1.778)
			(stroke
				(width 0.2032)
				(type default)
			)
			(layer "B.SilkS")
		)
		(fp_line
			(start 9.652 -2.921)
			(end 11.303 -2.921)
			(stroke
				(width 0.2032)
				(type default)
			)
			(layer "B.SilkS")
		)
		(fp_line
			(start -9.652 -2.921)
			(end -11.303 -2.921)
			(stroke
				(width 0.2032)
				(type default)
			)
			(layer "B.SilkS")
		)
		(fp_line
			(start -11.303 -2.921)
			(end -11.303 -3.429)
			(stroke
				(width 0.2032)
				(type default)
			)
			(layer "B.SilkS")
		)
		(fp_line
			(start -11.303 -3.429)
			(end -13.081 -3.429)
			(stroke
				(width 0.2032)
				(type default)
			)
			(layer "B.SilkS")
		)
		(fp_line
			(start -13.081 2.921)
			(end -9.652 2.921)
			(stroke
				(width 0.2032)
				(type default)
			)
			(layer "B.SilkS")
		)
		(fp_line
			(start -13.081 -3.429)
			(end -13.081 2.921)
			(stroke
				(width 0.2032)
				(type default)
			)
			(layer "B.SilkS")
		)
		(fp_circle
			(center 9.906 3.556)
			(end 9.62152 3.556)
			(stroke
				(width 0.2032)
				(type default)
			)
			(fill no)
			(layer "B.SilkS")
		)
		(fp_poly
			(pts
				(xy 13.335 -3.683) (xy 13.335 3.175) (xy 9.906 3.175) (xy 9.906 4.064) (xy -9.906 4.064) (xy -9.906 3.175)
				(xy -13.335 3.175) (xy -13.335 -3.683) (xy -9.906 -3.683) (xy -9.906 -4.064) (xy 9.906 -4.064) (xy 9.906 -3.683)
			)
			(stroke
				(width 0)
				(type default)
			)
			(fill no)
			(layer "B.CrtYd")
		)
		(fp_line
			(start 12.7 2.54)
			(end -12.7 2.54)
			(stroke
				(width 0.2032)
				(type default)
			)
			(layer "B.Fab")
		)
		(fp_line
			(start 12.7 -3.048)
			(end 12.7 2.54)
			(stroke
				(width 0.2032)
				(type default)
			)
			(layer "B.Fab")
		)
		(fp_line
			(start 11.7602 -2.54)
			(end 11.7602 -3.048)
			(stroke
				(width 0.2032)
				(type default)
			)
			(layer "B.Fab")
		)
		(fp_line
			(start 11.7602 -3.048)
			(end 12.7 -3.048)
			(stroke
				(width 0.2032)
				(type default)
			)
			(layer "B.Fab")
		)
		(fp_line
			(start 8.89 1.397)
			(end 9.525 2.54)
			(stroke
				(width 0.2032)
				(type default)
			)
			(layer "B.Fab")
		)
		(fp_line
			(start 8.255 2.54)
			(end 8.89 1.397)
			(stroke
				(width 0.2032)
				(type default)
			)
			(layer "B.Fab")
		)
		(fp_line
			(start 1.27 2.54)
			(end 1.27 1.778)
			(stroke
				(width 0.2032)
				(type default)
			)
			(layer "B.Fab")
		)
		(fp_line
			(start 1.27 1.778)
			(end -1.27 1.778)
			(stroke
				(width 0.2032)
				(type default)
			)
			(layer "B.Fab")
		)
		(fp_line
			(start 1.27 -2.54)
			(end 11.7602 -2.54)
			(stroke
				(width 0.2032)
				(type default)
			)
			(layer "B.Fab")
		)
		(fp_line
			(start 1.27 -3.048)
			(end 1.27 -2.54)
			(stroke
				(width 0.2032)
				(type default)
			)
			(layer "B.Fab")
		)
		(fp_line
			(start -1.27 1.778)
			(end -1.27 2.54)
			(stroke
				(width 0.2032)
				(type default)
			)
			(layer "B.Fab")
		)
		(fp_line
			(start -1.27 -2.54)
			(end -1.27 -3.048)
			(stroke
				(width 0.2032)
				(type default)
			)
			(layer "B.Fab")
		)
		(fp_line
			(start -1.27 -3.048)
			(end 1.27 -3.048)
			(stroke
				(width 0.2032)
				(type default)
			)
			(layer "B.Fab")
		)
		(fp_line
			(start -11.7602 -2.54)
			(end -1.27 -2.54)
			(stroke
				(width 0.2032)
				(type default)
			)
			(layer "B.Fab")
		)
		(fp_line
			(start -11.7602 -3.048)
			(end -11.7602 -2.54)
			(stroke
				(width 0.2032)
				(type default)
			)
			(layer "B.Fab")
		)
		(fp_line
			(start -12.7 2.54)
			(end -12.7 -3.048)
			(stroke
				(width 0.2032)
				(type default)
			)
			(layer "B.Fab")
		)
		(fp_line
			(start -12.7 -3.048)
			(end -11.7602 -3.048)
			(stroke
				(width 0.2032)
				(type default)
			)
			(layer "B.Fab")
		)
		(fp_text user "2"
			(at 9.652 -3.70967 0)
			(unlocked yes)
			(layer "B.SilkS")
			(effects
				(font
					(size 0.7874 0.5842)
					(thickness 0.127)
				)
				(justify left mirror)
			)
		)
		(fp_text user "29"
			(at -10.922 3.65633 0)
			(unlocked yes)
			(layer "B.SilkS")
			(effects
				(font
					(size 0.7874 0.5842)
					(thickness 0.127)
				)
				(justify left mirror)
			)
		)
		(fp_text user "30"
			(at -10.922 -3.58267 0)
			(unlocked yes)
			(layer "B.SilkS")
			(effects
				(font
					(size 0.7874 0.5842)
					(thickness 0.127)
				)
				(justify left mirror)
			)
		)
		(pad "1" smd rect
			(at 8.89 1.9685)
			(size 0.7366 2.921)
			(layers "B.Cu" "B.Mask" "B.Paste")
			(net "CPLD_GPIO_0")
		)
		(pad "2" smd rect
			(at 8.89 -1.9685)
			(size 0.7366 2.921)
			(layers "B.Cu" "B.Mask" "B.Paste")
			(net "CPLD_GPIO_1")
		)
		(pad "3" smd rect
			(at 7.62 1.9685)
			(size 0.7366 2.921)
			(layers "B.Cu" "B.Mask" "B.Paste")
			(net "EXT_3.3V")
		)
		(pad "4" smd rect
			(at 7.62 -1.9685)
			(size 0.7366 2.921)
			(layers "B.Cu" "B.Mask" "B.Paste")
			(net "GND")
		)
		(pad "5" smd rect
			(at 6.35 1.9685)
			(size 0.7366 2.921)
			(layers "B.Cu" "B.Mask" "B.Paste")
			(net "NFP_JTAG_ARM_TCK")
		)
		(pad "6" smd rect
			(at 6.35 -1.9685)
			(size 0.7366 2.921)
			(layers "B.Cu" "B.Mask" "B.Paste")
			(net "PWR_GOOD_LED_L")
		)
		(pad "7" smd rect
			(at 5.08 1.9685)
			(size 0.7366 2.921)
			(layers "B.Cu" "B.Mask" "B.Paste")
			(net "NFP_JTAG_ARM_TDI")
		)
		(pad "8" smd rect
			(at 5.08 -1.9685)
			(size 0.7366 2.921)
			(layers "B.Cu" "B.Mask" "B.Paste")
			(net "PSU_I2C_SCL")
		)
		(pad "9" smd rect
			(at 3.81 1.9685)
			(size 0.7366 2.921)
			(layers "B.Cu" "B.Mask" "B.Paste")
			(net "NFP_JTAG_ARM_TDO")
		)
		(pad "10" smd rect
			(at 3.81 -1.9685)
			(size 0.7366 2.921)
			(layers "B.Cu" "B.Mask" "B.Paste")
			(net "PSU_I2C_SDA")
		)
		(pad "11" smd rect
			(at 2.54 1.9685)
			(size 0.7366 2.921)
			(layers "B.Cu" "B.Mask" "B.Paste")
			(net "NFP_JTAG_ARM_TMS")
		)
		(pad "12" smd rect
			(at 2.54 -1.9685)
			(size 0.7366 2.921)
			(layers "B.Cu" "B.Mask" "B.Paste")
			(net "GND")
		)
		(pad "13" smd rect
			(at 1.27 1.9685)
			(size 0.7366 2.921)
			(layers "B.Cu" "B.Mask" "B.Paste")
			(net "NFP_JTAG_ARM_TRST_L")
		)
		(pad "14" smd rect
			(at 1.27 -1.9685)
			(size 0.7366 2.921)
			(layers "B.Cu" "B.Mask" "B.Paste")
			(net "NFP_FAIL_SAFE_BOOT_L")
		)
		(pad "15" smd rect
			(at 0 1.9685)
			(size 0.7366 2.921)
			(layers "B.Cu" "B.Mask" "B.Paste")
			(net "DEBUG_CPLD_PGRM_JTAG_TCK")
		)
		(pad "16" smd rect
			(at 0 -1.9685)
			(size 0.7366 2.921)
			(layers "B.Cu" "B.Mask" "B.Paste")
			(net "HOST_RESET_REQ_L")
		)
		(pad "17" smd rect
			(at -1.27 1.9685)
			(size 0.7366 2.921)
			(layers "B.Cu" "B.Mask" "B.Paste")
			(net "DEBUG_CPLD_PGRM_JTAG_TDI")
		)
		(pad "18" smd rect
			(at -1.27 -1.9685)
			(size 0.7366 2.921)
			(layers "B.Cu" "B.Mask" "B.Paste")
			(net "CNTRL_SPI_SCK")
		)
		(pad "19" smd rect
			(at -2.54 1.9685)
			(size 0.7366 2.921)
			(layers "B.Cu" "B.Mask" "B.Paste")
			(net "DEBUG_CPLD_PGRM_JTAG_TDO")
		)
		(pad "20" smd rect
			(at -2.54 -1.9685)
			(size 0.7366 2.921)
			(layers "B.Cu" "B.Mask" "B.Paste")
			(net "CNTRL_SPI_MOSI")
		)
		(pad "21" smd rect
			(at -3.81 1.9685)
			(size 0.7366 2.921)
			(layers "B.Cu" "B.Mask" "B.Paste")
			(net "DEBUG_CPLD_PGRM_JTAG_TMS")
		)
		(pad "22" smd rect
			(at -3.81 -1.9685)
			(size 0.7366 2.921)
			(layers "B.Cu" "B.Mask" "B.Paste")
			(net "CNTRL_SPI_MISO")
		)
		(pad "23" smd rect
			(at -5.08 1.9685)
			(size 0.7366 2.921)
			(layers "B.Cu" "B.Mask" "B.Paste")
			(net "NFP_CFG_SPI_FLASH_HOLD_L")
		)
		(pad "24" smd rect
			(at -5.08 -1.9685)
			(size 0.7366 2.921)
			(layers "B.Cu" "B.Mask" "B.Paste")
			(net "CNTRL_SPI_CS")
		)
		(pad "25" smd rect
			(at -6.35 1.9685)
			(size 0.7366 2.921)
			(layers "B.Cu" "B.Mask" "B.Paste")
			(net "NFP_UART_SR_RX")
		)
		(pad "26" smd rect
			(at -6.35 -1.9685)
			(size 0.7366 2.921)
			(layers "B.Cu" "B.Mask" "B.Paste")
			(net "NFP_UART_SR_TX")
		)
		(pad "27" smd rect
			(at -7.62 1.9685)
			(size 0.7366 2.921)
			(layers "B.Cu" "B.Mask" "B.Paste")
			(net "GND")
		)
		(pad "28" smd rect
			(at -7.62 -1.9685)
			(size 0.7366 2.921)
			(layers "B.Cu" "B.Mask" "B.Paste")
			(net "EXT_3.3V")
		)
		(pad "29" smd rect
			(at -8.89 1.9685)
			(size 0.7366 2.921)
			(layers "B.Cu" "B.Mask" "B.Paste")
			(net "CPLD_GPIO_2")
		)
		(pad "30" smd rect
			(at -8.89 -1.9685)
			(size 0.7366 2.921)
			(layers "B.Cu" "B.Mask" "B.Paste")
			(net "CPLD_GPIO_3")
		)
	)
	(footprint ""
		(layer "B.Cu")
		(at 21.971 16.891)
		(property "Reference" "R20"
			(at 0.127 -1.37033 0)
			(unlocked yes)
			(layer "B.SilkS")
			(effects
				(font
					(size 0.7874 0.5842)
					(thickness 0.127)
				)
				(justify left mirror)
			)
		)
		(property "Value" "4.75K"
			(at 0.148158 1.3462 270)
			(unlocked yes)
			(layer "B.Fab")
			(hide yes)
			(effects
				(font
					(size 1.27 0.9652)
					(thickness 0.000001)
				)
				(justify left mirror)
			)
		)
		(property "Device Type" "REST4024"
			(at 0.148158 1.3462 270)
			(unlocked yes)
			(layer "B.Fab")
			(hide yes)
			(effects
				(font
					(size 1.27 0.9652)
					(thickness 0.000001)
				)
				(justify left mirror)
			)
		)
		(duplicate_pad_numbers_are_jumpers no)
		(fp_poly
			(pts
				(xy -0.635 1.0668) (xy -0.635 -1.0668) (xy 0.635 -1.0668) (xy 0.635 1.0668)
			)
			(stroke
				(width 0)
				(type default)
			)
			(fill no)
			(layer "B.CrtYd")
		)
		(fp_line
			(start -0.254 -0.508)
			(end -0.254 0.508)
			(stroke
				(width 0.0254)
				(type default)
			)
			(layer "B.Fab")
		)
		(fp_line
			(start -0.254 0.508)
			(end 0.254 0.508)
			(stroke
				(width 0.0254)
				(type default)
			)
			(layer "B.Fab")
		)
		(fp_line
			(start 0.254 -0.508)
			(end -0.254 -0.508)
			(stroke
				(width 0.0254)
				(type default)
			)
			(layer "B.Fab")
		)
		(fp_line
			(start 0.254 0.508)
			(end 0.254 -0.508)
			(stroke
				(width 0.0254)
				(type default)
			)
			(layer "B.Fab")
		)
		(pad "1" smd rect
			(at 0 -0.4191 180)
			(size 0.508 0.5334)
			(layers "B.Cu" "B.Mask" "B.Paste")
			(net "VDD_3.3V")
		)
		(pad "2" smd rect
			(at 0 0.4191 180)
			(size 0.508 0.5334)
			(layers "B.Cu" "B.Mask" "B.Paste")
			(net "NFP_ARM_SPI_FLASH_MISO")
		)
		(zone
			(layer "B.Cu")
			(hatch none 0.5)
			(connect_pads
				(clearance 0)
			)
			(min_thickness 0.25)
			(keepout
				(tracks not_allowed)
				(vias allowed)
				(pads allowed)
				(copperpour not_allowed)
				(footprints allowed)
			)
			(placement
				(enabled no)
				(sheetname "")
			)
			(fill
				(thermal_gap 0.5)
				(thermal_bridge_width 0.5)
				(island_removal_mode 0)
			)
			(polygon
				(pts
					(xy 21.9456 16.8656) (xy 21.9456 16.9164) (xy 21.9964 16.9164) (xy 21.9964 16.8656)
				)
			)
		)
	)
	(footprint ""
		(layer "B.Cu")
		(at 73.851008 14.256004)
		(property "Reference" "V_A-DM3"
			(at 0 0 0)
			(layer "B.SilkS")
			(hide yes)
			(effects
				(font
					(size 1.27 1.27)
				)
				(justify mirror)
			)
		)
		(property "Value" ""
			(at 0 0 0)
			(layer "B.Fab")
			(effects
				(font
					(size 1.27 1.27)
				)
				(justify mirror)
			)
		)
		(duplicate_pad_numbers_are_jumpers no)
		(pad "1" thru_hole circle
			(at 0 0 180)
			(size 0.4572 0.4572)
			(drill 0.20574)
			(layers "*.Cu" "*.Mask")
			(remove_unused_layers no)
			(net "DDR0_32A_DM3")
			(clearance 0.1143)
			(thermal_gap 0.1143)
		)
	)
	(footprint ""
		(layer "B.Cu")
		(at 40.237029 24.541988 180)
		(property "Reference" "R19"
			(at 0 0 0)
			(layer "B.SilkS")
			(hide yes)
			(effects
				(font
					(size 1.27 1.27)
				)
				(justify mirror)
			)
		)
		(property "Value" ""
			(at 0 0 0)
			(layer "B.Fab")
			(effects
				(font
					(size 1.27 1.27)
				)
				(justify mirror)
			)
		)
		(duplicate_pad_numbers_are_jumpers no)
		(fp_circle
			(center 0 0)
			(end -0.104648 0)
			(stroke
				(width 0.1016)
				(type default)
			)
			(fill no)
			(layer "B.SilkS")
		)
		(fp_poly
			(pts
				(xy 0.381 -0.889) (xy 0.381 0.889) (xy -0.381 0.889) (xy -0.381 -0.889)
			)
			(stroke
				(width 0)
				(type default)
			)
			(fill no)
			(layer "B.CrtYd")
		)
		(fp_line
			(start 0.508 1.016)
			(end 0.508 -1.016)
			(stroke
				(width 0.0254)
				(type default)
			)
			(layer "B.Fab")
		)
		(fp_line
			(start 0.508 -1.016)
			(end 0.254 -1.016)
			(stroke
				(width 0.0254)
				(type default)
			)
			(layer "B.Fab")
		)
		(fp_line
			(start 0.254 -1.016)
			(end -0.508 -1.016)
			(stroke
				(width 0.0254)
				(type default)
			)
			(layer "B.Fab")
		)
		(fp_line
			(start -0.508 1.016)
			(end 0.508 1.016)
			(stroke
				(width 0.0254)
				(type default)
			)
			(layer "B.Fab")
		)
		(fp_line
			(start -0.508 -1.016)
			(end -0.508 1.016)
			(stroke
				(width 0.0254)
				(type default)
			)
			(layer "B.Fab")
		)
		(pad "1" smd custom
			(at 0 -0.500126)
			(size 0.127 0.127)
			(layers "B.Cu" "B.Mask" "B.Paste")
			(net "VDD_3.3V")
			(options
				(clearance outline)
				(anchor circle)
			)
			(primitives
				(gr_poly
					(pts
						(xy -0.1778 0.254) (xy 0.1778 0.254) (xy 0.254 0.1778) (xy 0.254 -0.1778) (xy 0.1778 -0.254) (xy -0.1778 -0.254)
						(xy -0.254 -0.1778) (xy -0.254 0.1778)
					)
					(width 0)
					(fill yes)
				)
			)
		)
		(pad "2" smd custom
			(at 0 0.500126)
			(size 0.127 0.127)
			(layers "B.Cu" "B.Mask" "B.Paste")
			(net "NFP_CLK_NRESET_OUT_L")
			(options
				(clearance outline)
				(anchor circle)
			)
			(primitives
				(gr_poly
					(pts
						(xy -0.1778 0.254) (xy 0.1778 0.254) (xy 0.254 0.1778) (xy 0.254 -0.1778) (xy 0.1778 -0.254) (xy -0.1778 -0.254)
						(xy -0.254 -0.1778) (xy -0.254 0.1778)
					)
					(width 0)
					(fill yes)
				)
			)
		)
	)
	(footprint ""
		(layer "B.Cu")
		(at 81.850992 14.256004)
		(property "Reference" "V2_A-A00"
			(at 0 0 0)
			(layer "B.SilkS")
			(hide yes)
			(effects
				(font
					(size 1.27 1.27)
				)
				(justify mirror)
			)
		)
		(property "Value" ""
			(at 0 0 0)
			(layer "B.Fab")
			(effects
				(font
					(size 1.27 1.27)
				)
				(justify mirror)
			)
		)
		(duplicate_pad_numbers_are_jumpers no)
		(pad "1" thru_hole circle
			(at 0 0 180)
			(size 0.4572 0.4572)
			(drill 0.20574)
			(layers "*.Cu" "*.Mask")
			(remove_unused_layers no)
			(net "DDR0_32A_A0")
			(clearance 0.1143)
			(thermal_gap 0.1143)
		)
	)
	(footprint ""
		(layer "B.Cu")
		(at 77.051002 2.699004)
		(property "Reference" "V_A-DQ04"
			(at 0 0 0)
			(layer "B.SilkS")
			(hide yes)
			(effects
				(font
					(size 1.27 1.27)
				)
				(justify mirror)
			)
		)
		(property "Value" ""
			(at 0 0 0)
			(layer "B.Fab")
			(effects
				(font
					(size 1.27 1.27)
				)
				(justify mirror)
			)
		)
		(duplicate_pad_numbers_are_jumpers no)
		(pad "1" thru_hole circle
			(at 0 0 180)
			(size 0.4572 0.4572)
			(drill 0.20574)
			(layers "*.Cu" "*.Mask")
			(remove_unused_layers no)
			(net "DDR0_32A_DQ4")
			(clearance 0.1143)
			(thermal_gap 0.1143)
		)
	)
	(footprint ""
		(layer "B.Cu")
		(at 62.221999 0.762 180)
		(property "Reference" "C153"
			(at 0.145212 0.8763 270)
			(unlocked yes)
			(layer "B.SilkS")
			(effects
				(font
					(size 0.7874 0.5842)
					(thickness 0.127)
				)
				(justify left mirror)
			)
		)
		(property "Value" "0.22UF"
			(at 0.091846 0.2921 90)
			(unlocked yes)
			(layer "B.Fab")
			(hide yes)
			(effects
				(font
					(size 0.7874 0.5842)
					(thickness 0.2032)
				)
				(justify left mirror)
			)
		)
		(property "Device Type" "CAPC0062"
			(at 0.091846 0.2921 90)
			(unlocked yes)
			(layer "B.Fab")
			(hide yes)
			(effects
				(font
					(size 0.7874 0.5842)
					(thickness 0.2032)
				)
				(justify left mirror)
			)
		)
		(duplicate_pad_numbers_are_jumpers no)
		(fp_poly
			(pts
				(xy -0.635 1.0668) (xy -0.635 -1.0668) (xy 0.635 -1.0668) (xy 0.635 1.0668)
			)
			(stroke
				(width 0)
				(type default)
			)
			(fill no)
			(layer "B.CrtYd")
		)
		(fp_line
			(start 0.254 0.508)
			(end 0.254 -0.508)
			(stroke
				(width 0.0254)
				(type default)
			)
			(layer "B.Fab")
		)
		(fp_line
			(start 0.254 -0.508)
			(end -0.254 -0.508)
			(stroke
				(width 0.0254)
				(type default)
			)
			(layer "B.Fab")
		)
		(fp_line
			(start -0.254 0.508)
			(end 0.254 0.508)
			(stroke
				(width 0.0254)
				(type default)
			)
			(layer "B.Fab")
		)
		(fp_line
			(start -0.254 -0.508)
			(end -0.254 0.508)
			(stroke
				(width 0.0254)
				(type default)
			)
			(layer "B.Fab")
		)
		(pad "1" smd rect
			(at 0 -0.4191)
			(size 0.508 0.5334)
			(layers "B.Cu" "B.Mask" "B.Paste")
			(net "_NFP_PCIE0_PER0_P")
		)
		(pad "2" smd rect
			(at 0 0.4191)
			(size 0.508 0.5334)
			(layers "B.Cu" "B.Mask" "B.Paste")
			(net "NFP_PCIE0_PER0_P")
		)
		(zone
			(layer "B.Cu")
			(hatch none 0.5)
			(connect_pads
				(clearance 0)
			)
			(min_thickness 0.25)
			(keepout
				(tracks not_allowed)
				(vias allowed)
				(pads allowed)
				(copperpour not_allowed)
				(footprints allowed)
			)
			(placement
				(enabled no)
				(sheetname "")
			)
			(fill
				(thermal_gap 0.5)
				(thermal_bridge_width 0.5)
				(island_removal_mode 0)
			)
			(polygon
				(pts
					(xy 62.247399 0.7874) (xy 62.247399 0.7366) (xy 62.196599 0.7366) (xy 62.196599 0.7874)
				)
			)
		)
	)
	(footprint ""
		(layer "B.Cu")
		(at 37.592 19.304 -90)
		(property "Reference" "R202"
			(at 0 0 90)
			(layer "B.SilkS")
			(hide yes)
			(effects
				(font
					(size 1.27 1.27)
				)
				(justify mirror)
			)
		)
		(property "Value" "39.0"
			(at 0.148158 1.3462 180)
			(unlocked yes)
			(layer "B.Fab")
			(hide yes)
			(effects
				(font
					(size 1.27 0.9652)
					(thickness 0.000001)
				)
				(justify left mirror)
			)
		)
		(property "Device Type" "REST0108"
			(at 0.148158 1.3462 180)
			(unlocked yes)
			(layer "B.Fab")
			(hide yes)
			(effects
				(font
					(size 1.27 0.9652)
					(thickness 0.000001)
				)
				(justify left mirror)
			)
		)
		(duplicate_pad_numbers_are_jumpers no)
		(fp_poly
			(pts
				(xy -0.635 1.0668) (xy -0.635 -1.0668) (xy 0.635 -1.0668) (xy 0.635 1.0668)
			)
			(stroke
				(width 0)
				(type default)
			)
			(fill no)
			(layer "B.CrtYd")
		)
		(fp_line
			(start -0.254 0.508)
			(end 0.254 0.508)
			(stroke
				(width 0.0254)
				(type default)
			)
			(layer "B.Fab")
		)
		(fp_line
			(start 0.254 0.508)
			(end 0.254 -0.508)
			(stroke
				(width 0.0254)
				(type default)
			)
			(layer "B.Fab")
		)
		(fp_line
			(start -0.254 -0.508)
			(end -0.254 0.508)
			(stroke
				(width 0.0254)
				(type default)
			)
			(layer "B.Fab")
		)
		(fp_line
			(start 0.254 -0.508)
			(end -0.254 -0.508)
			(stroke
				(width 0.0254)
				(type default)
			)
			(layer "B.Fab")
		)
		(pad "1" smd rect
			(at 0 -0.4191 90)
			(size 0.508 0.5334)
			(layers "B.Cu" "B.Mask" "B.Paste")
			(net "_NFP_CFG_SPI_FLASH_MOSI")
		)
		(pad "2" smd rect
			(at 0 0.4191 90)
			(size 0.508 0.5334)
			(layers "B.Cu" "B.Mask" "B.Paste")
			(net "NFP_CFG_SPI_FLASH_MOSI")
		)
		(zone
			(layer "B.Cu")
			(hatch none 0.5)
			(connect_pads
				(clearance 0)
			)
			(min_thickness 0.25)
			(keepout
				(tracks not_allowed)
				(vias allowed)
				(pads allowed)
				(copperpour not_allowed)
				(footprints allowed)
			)
			(placement
				(enabled no)
				(sheetname "")
			)
			(fill
				(thermal_gap 0.5)
				(thermal_bridge_width 0.5)
				(island_removal_mode 0)
			)
			(polygon
				(pts
					(xy 37.6174 19.2786) (xy 37.5666 19.2786) (xy 37.5666 19.3294) (xy 37.6174 19.3294)
				)
			)
		)
	)
	(footprint ""
		(layer "B.Cu")
		(at 45.737018 1.042035 180)
		(property "Reference" "L15"
			(at -0.998982 1.142365 0)
			(unlocked yes)
			(layer "B.SilkS")
			(effects
				(font
					(size 0.7874 0.5842)
					(thickness 0.127)
				)
				(justify left mirror)
			)
		)
		(property "Value" ""
			(at 0 0 0)
			(layer "B.Fab")
			(effects
				(font
					(size 1.27 1.27)
				)
				(justify mirror)
			)
		)
		(duplicate_pad_numbers_are_jumpers no)
		(fp_rect
			(start -1.7907 0.889)
			(end 1.7907 -0.889)
			(stroke
				(width 0)
				(type default)
			)
			(fill no)
			(layer "B.CrtYd")
		)
		(fp_line
			(start 1.778 0.762)
			(end 1.778 -0.762)
			(stroke
				(width 0.0254)
				(type default)
			)
			(layer "B.Fab")
		)
		(fp_line
			(start 1.778 -0.762)
			(end -1.778 -0.762)
			(stroke
				(width 0.0254)
				(type default)
			)
			(layer "B.Fab")
		)
		(fp_line
			(start -1.778 0.762)
			(end 1.778 0.762)
			(stroke
				(width 0.0254)
				(type default)
			)
			(layer "B.Fab")
		)
		(fp_line
			(start -1.778 -0.762)
			(end -1.778 0.762)
			(stroke
				(width 0.0254)
				(type default)
			)
			(layer "B.Fab")
		)
		(pad "1" smd rect
			(at 0.7493 0 270)
			(size 0.7874 0.8128)
			(layers "B.Cu" "B.Mask" "B.Paste")
			(net "VDD_1.8V")
		)
		(pad "2" smd rect
			(at -0.7493 0 270)
			(size 0.7874 0.8128)
			(layers "B.Cu" "B.Mask" "B.Paste")
			(net "VDDAH_SERDES")
		)
		(zone
			(layer "B.Cu")
			(hatch none 0.5)
			(connect_pads
				(clearance 0)
			)
			(min_thickness 0.25)
			(keepout
				(tracks not_allowed)
				(vias allowed)
				(pads allowed)
				(copperpour not_allowed)
				(footprints allowed)
			)
			(placement
				(enabled no)
				(sheetname "")
			)
			(fill
				(thermal_gap 0.5)
				(thermal_bridge_width 0.5)
				(island_removal_mode 0)
			)
			(polygon
				(pts
					(xy 45.457618 1.448435) (xy 45.457618 0.635635) (xy 46.016418 0.635635) (xy 46.016418 1.448435)
				)
			)
		)
	)
	(footprint ""
		(layer "B.Cu")
		(at 58.236993 26.541984)
		(property "Reference" "C8"
			(at 0.029337 -2.030984 270)
			(unlocked yes)
			(layer "B.SilkS")
			(effects
				(font
					(size 0.7874 0.5842)
					(thickness 0.127)
				)
				(justify mirror)
			)
		)
		(property "Value" ""
			(at 0 0 0)
			(layer "B.Fab")
			(effects
				(font
					(size 1.27 1.27)
				)
				(justify mirror)
			)
		)
		(duplicate_pad_numbers_are_jumpers no)
		(fp_circle
			(center 0 0)
			(end 0.104648 0)
			(stroke
				(width 0.1016)
				(type default)
			)
			(fill no)
			(layer "B.SilkS")
		)
		(fp_poly
			(pts
				(xy 0.381 -0.889) (xy 0.381 0.889) (xy -0.381 0.889) (xy -0.381 -0.889)
			)
			(stroke
				(width 0)
				(type default)
			)
			(fill no)
			(layer "B.CrtYd")
		)
		(fp_line
			(start -0.508 -1.016)
			(end -0.508 1.016)
			(stroke
				(width 0.0254)
				(type default)
			)
			(layer "B.Fab")
		)
		(fp_line
			(start -0.508 1.016)
			(end 0.508 1.016)
			(stroke
				(width 0.0254)
				(type default)
			)
			(layer "B.Fab")
		)
		(fp_line
			(start 0.254 -1.016)
			(end -0.508 -1.016)
			(stroke
				(width 0.0254)
				(type default)
			)
			(layer "B.Fab")
		)
		(fp_line
			(start 0.508 -1.016)
			(end 0.254 -1.016)
			(stroke
				(width 0.0254)
				(type default)
			)
			(layer "B.Fab")
		)
		(fp_line
			(start 0.508 1.016)
			(end 0.508 -1.016)
			(stroke
				(width 0.0254)
				(type default)
			)
			(layer "B.Fab")
		)
		(pad "1" smd custom
			(at 0 -0.500126 180)
			(size 0.127 0.127)
			(layers "B.Cu" "B.Mask" "B.Paste")
			(net "VDD_CORE")
			(options
				(clearance outline)
				(anchor circle)
			)
			(primitives
				(gr_poly
					(pts
						(xy -0.1778 0.254) (xy 0.1778 0.254) (xy 0.254 0.1778) (xy 0.254 -0.1778) (xy 0.1778 -0.254) (xy -0.1778 -0.254)
						(xy -0.254 -0.1778) (xy -0.254 0.1778)
					)
					(width 0)
					(fill yes)
				)
			)
		)
		(pad "2" smd custom
			(at 0 0.500126 180)
			(size 0.127 0.127)
			(layers "B.Cu" "B.Mask" "B.Paste")
			(net "GND")
			(options
				(clearance outline)
				(anchor circle)
			)
			(primitives
				(gr_poly
					(pts
						(xy -0.1778 0.254) (xy 0.1778 0.254) (xy 0.254 0.1778) (xy 0.254 -0.1778) (xy 0.1778 -0.254) (xy -0.1778 -0.254)
						(xy -0.254 -0.1778) (xy -0.254 0.1778)
					)
					(width 0)
					(fill yes)
				)
			)
		)
	)
	(footprint ""
		(layer "B.Cu")
		(at 83.450989 1.899006)
		(property "Reference" "V1_A-A07"
			(at 0 0 0)
			(layer "B.SilkS")
			(hide yes)
			(effects
				(font
					(size 1.27 1.27)
				)
				(justify mirror)
			)
		)
		(property "Value" ""
			(at 0 0 0)
			(layer "B.Fab")
			(effects
				(font
					(size 1.27 1.27)
				)
				(justify mirror)
			)
		)
		(duplicate_pad_numbers_are_jumpers no)
		(pad "1" thru_hole circle
			(at 0 0 180)
			(size 0.4572 0.4572)
			(drill 0.20574)
			(layers "*.Cu" "*.Mask")
			(remove_unused_layers no)
			(net "DDR0_32A_A7")
			(clearance 0.1143)
			(thermal_gap 0.1143)
		)
	)
	(footprint ""
		(layer "B.Cu")
		(at 61.214 0.762 180)
		(property "Reference" "C156"
			(at 0.145212 0.8763 270)
			(unlocked yes)
			(layer "B.SilkS")
			(effects
				(font
					(size 0.7874 0.5842)
					(thickness 0.127)
				)
				(justify left mirror)
			)
		)
		(property "Value" "0.22UF"
			(at 0.091846 0.2921 90)
			(unlocked yes)
			(layer "B.Fab")
			(hide yes)
			(effects
				(font
					(size 0.7874 0.5842)
					(thickness 0.2032)
				)
				(justify left mirror)
			)
		)
		(property "Device Type" "CAPC0062"
			(at 0.091846 0.2921 90)
			(unlocked yes)
			(layer "B.Fab")
			(hide yes)
			(effects
				(font
					(size 0.7874 0.5842)
					(thickness 0.2032)
				)
				(justify left mirror)
			)
		)
		(duplicate_pad_numbers_are_jumpers no)
		(fp_poly
			(pts
				(xy -0.635 1.0668) (xy -0.635 -1.0668) (xy 0.635 -1.0668) (xy 0.635 1.0668)
			)
			(stroke
				(width 0)
				(type default)
			)
			(fill no)
			(layer "B.CrtYd")
		)
		(fp_line
			(start 0.254 0.508)
			(end 0.254 -0.508)
			(stroke
				(width 0.0254)
				(type default)
			)
			(layer "B.Fab")
		)
		(fp_line
			(start 0.254 -0.508)
			(end -0.254 -0.508)
			(stroke
				(width 0.0254)
				(type default)
			)
			(layer "B.Fab")
		)
		(fp_line
			(start -0.254 0.508)
			(end 0.254 0.508)
			(stroke
				(width 0.0254)
				(type default)
			)
			(layer "B.Fab")
		)
		(fp_line
			(start -0.254 -0.508)
			(end -0.254 0.508)
			(stroke
				(width 0.0254)
				(type default)
			)
			(layer "B.Fab")
		)
		(pad "1" smd rect
			(at 0 -0.4191)
			(size 0.508 0.5334)
			(layers "B.Cu" "B.Mask" "B.Paste")
			(net "_NFP_PCIE0_PER1_N")
		)
		(pad "2" smd rect
			(at 0 0.4191)
			(size 0.508 0.5334)
			(layers "B.Cu" "B.Mask" "B.Paste")
			(net "NFP_PCIE0_PER1_N")
		)
		(zone
			(layer "B.Cu")
			(hatch none 0.5)
			(connect_pads
				(clearance 0)
			)
			(min_thickness 0.25)
			(keepout
				(tracks not_allowed)
				(vias allowed)
				(pads allowed)
				(copperpour not_allowed)
				(footprints allowed)
			)
			(placement
				(enabled no)
				(sheetname "")
			)
			(fill
				(thermal_gap 0.5)
				(thermal_bridge_width 0.5)
				(island_removal_mode 0)
			)
			(polygon
				(pts
					(xy 61.2394 0.7874) (xy 61.2394 0.7366) (xy 61.1886 0.7366) (xy 61.1886 0.7874)
				)
			)
		)
	)
	(footprint ""
		(layer "B.Cu")
		(at 84.250987 7.498994)
		(property "Reference" "V1_A-A08"
			(at 0 0 0)
			(layer "B.SilkS")
			(hide yes)
			(effects
				(font
					(size 1.27 1.27)
				)
				(justify mirror)
			)
		)
		(property "Value" ""
			(at 0 0 0)
			(layer "B.Fab")
			(effects
				(font
					(size 1.27 1.27)
				)
				(justify mirror)
			)
		)
		(duplicate_pad_numbers_are_jumpers no)
		(pad "1" thru_hole circle
			(at 0 0 180)
			(size 0.4572 0.4572)
			(drill 0.20574)
			(layers "*.Cu" "*.Mask")
			(remove_unused_layers no)
			(net "DDR0_32A_A8")
			(clearance 0.1143)
			(thermal_gap 0.1143)
		)
	)
	(footprint ""
		(layer "B.Cu")
		(at 35.433 32.639)
		(property "Reference" "R81"
			(at 0.48133 3.429 270)
			(unlocked yes)
			(layer "B.SilkS")
			(effects
				(font
					(size 0.7874 0.5842)
					(thickness 0.127)
				)
				(justify left mirror)
			)
		)
		(property "Value" "4.75K"
			(at 0.148158 1.3462 270)
			(unlocked yes)
			(layer "B.Fab")
			(hide yes)
			(effects
				(font
					(size 1.27 0.9652)
					(thickness 0.000001)
				)
				(justify left mirror)
			)
		)
		(property "Device Type" "REST4024"
			(at 0.148158 1.3462 270)
			(unlocked yes)
			(layer "B.Fab")
			(hide yes)
			(effects
				(font
					(size 1.27 0.9652)
					(thickness 0.000001)
				)
				(justify left mirror)
			)
		)
		(duplicate_pad_numbers_are_jumpers no)
		(fp_poly
			(pts
				(xy -0.635 1.0668) (xy -0.635 -1.0668) (xy 0.635 -1.0668) (xy 0.635 1.0668)
			)
			(stroke
				(width 0)
				(type default)
			)
			(fill no)
			(layer "B.CrtYd")
		)
		(fp_line
			(start -0.254 -0.508)
			(end -0.254 0.508)
			(stroke
				(width 0.0254)
				(type default)
			)
			(layer "B.Fab")
		)
		(fp_line
			(start -0.254 0.508)
			(end 0.254 0.508)
			(stroke
				(width 0.0254)
				(type default)
			)
			(layer "B.Fab")
		)
		(fp_line
			(start 0.254 -0.508)
			(end -0.254 -0.508)
			(stroke
				(width 0.0254)
				(type default)
			)
			(layer "B.Fab")
		)
		(fp_line
			(start 0.254 0.508)
			(end 0.254 -0.508)
			(stroke
				(width 0.0254)
				(type default)
			)
			(layer "B.Fab")
		)
		(pad "1" smd rect
			(at 0 -0.4191 180)
			(size 0.508 0.5334)
			(layers "B.Cu" "B.Mask" "B.Paste")
			(net "GND")
		)
		(pad "2" smd rect
			(at 0 0.4191 180)
			(size 0.508 0.5334)
			(layers "B.Cu" "B.Mask" "B.Paste")
			(net "_NFP_CORE_VID7")
		)
		(zone
			(layer "B.Cu")
			(hatch none 0.5)
			(connect_pads
				(clearance 0)
			)
			(min_thickness 0.25)
			(keepout
				(tracks not_allowed)
				(vias allowed)
				(pads allowed)
				(copperpour not_allowed)
				(footprints allowed)
			)
			(placement
				(enabled no)
				(sheetname "")
			)
			(fill
				(thermal_gap 0.5)
				(thermal_bridge_width 0.5)
				(island_removal_mode 0)
			)
			(polygon
				(pts
					(xy 35.4076 32.6136) (xy 35.4076 32.6644) (xy 35.4584 32.6644) (xy 35.4584 32.6136)
				)
			)
		)
	)
	(footprint ""
		(layer "B.Cu")
		(at 38.989 44.831)
		(property "Reference" "TP11"
			(at 2.159 -2.38633 0)
			(unlocked yes)
			(layer "B.SilkS")
			(effects
				(font
					(size 0.7874 0.5842)
					(thickness 0.127)
				)
				(justify left mirror)
			)
		)
		(property "Value" "*"
			(at 0.4826 -0.14732 0)
			(unlocked yes)
			(layer "B.Fab")
			(hide yes)
			(effects
				(font
					(size 1.27 0.9652)
					(thickness 0.000001)
				)
				(justify left mirror)
			)
		)
		(property "Device Type" "TP_SMALL"
			(at 0.4826 -0.14732 0)
			(unlocked yes)
			(layer "B.Fab")
			(hide yes)
			(effects
				(font
					(size 1.27 0.9652)
					(thickness 0.000001)
				)
				(justify left mirror)
			)
		)
		(duplicate_pad_numbers_are_jumpers no)
		(fp_line
			(start -0.8636 -0.8636)
			(end 0.8636 -0.8636)
			(stroke
				(width 0.1524)
				(type default)
			)
			(layer "B.SilkS")
		)
		(fp_line
			(start -0.8636 0.8636)
			(end -0.8636 -0.8636)
			(stroke
				(width 0.1524)
				(type default)
			)
			(layer "B.SilkS")
		)
		(fp_line
			(start 0.8636 -0.8636)
			(end 0.8636 0.8636)
			(stroke
				(width 0.1524)
				(type default)
			)
			(layer "B.SilkS")
		)
		(fp_line
			(start 0.8636 0.8636)
			(end -0.8636 0.8636)
			(stroke
				(width 0.1524)
				(type default)
			)
			(layer "B.SilkS")
		)
		(fp_poly
			(pts
				(xy 0.635 -0.635) (xy 0.635 0.635) (xy -0.635 0.635) (xy -0.635 -0.635)
			)
			(stroke
				(width 0)
				(type default)
			)
			(fill no)
			(layer "B.CrtYd")
		)
		(pad "1" smd rect
			(at 0 0 180)
			(size 1.27 1.27)
			(layers "B.Cu" "B.Mask" "B.Paste")
			(net "DEBUG_CPLD_PGRM_JTAG_TMS")
		)
	)
	(footprint ""
		(layer "B.Cu")
		(at 55.437024 0.762 180)
		(property "Reference" "C146"
			(at 0.145212 0.8763 270)
			(unlocked yes)
			(layer "B.SilkS")
			(effects
				(font
					(size 0.7874 0.5842)
					(thickness 0.127)
				)
				(justify left mirror)
			)
		)
		(property "Value" "0.22UF"
			(at 0.091846 0.2921 90)
			(unlocked yes)
			(layer "B.Fab")
			(hide yes)
			(effects
				(font
					(size 0.7874 0.5842)
					(thickness 0.2032)
				)
				(justify left mirror)
			)
		)
		(property "Device Type" "CAPC0062"
			(at 0.091846 0.2921 90)
			(unlocked yes)
			(layer "B.Fab")
			(hide yes)
			(effects
				(font
					(size 0.7874 0.5842)
					(thickness 0.2032)
				)
				(justify left mirror)
			)
		)
		(duplicate_pad_numbers_are_jumpers no)
		(fp_poly
			(pts
				(xy -0.635 1.0668) (xy -0.635 -1.0668) (xy 0.635 -1.0668) (xy 0.635 1.0668)
			)
			(stroke
				(width 0)
				(type default)
			)
			(fill no)
			(layer "B.CrtYd")
		)
		(fp_line
			(start 0.254 0.508)
			(end 0.254 -0.508)
			(stroke
				(width 0.0254)
				(type default)
			)
			(layer "B.Fab")
		)
		(fp_line
			(start 0.254 -0.508)
			(end -0.254 -0.508)
			(stroke
				(width 0.0254)
				(type default)
			)
			(layer "B.Fab")
		)
		(fp_line
			(start -0.254 0.508)
			(end 0.254 0.508)
			(stroke
				(width 0.0254)
				(type default)
			)
			(layer "B.Fab")
		)
		(fp_line
			(start -0.254 -0.508)
			(end -0.254 0.508)
			(stroke
				(width 0.0254)
				(type default)
			)
			(layer "B.Fab")
		)
		(pad "1" smd rect
			(at 0 -0.4191)
			(size 0.508 0.5334)
			(layers "B.Cu" "B.Mask" "B.Paste")
			(net "_NFP_PCIE0_PER4_N")
		)
		(pad "2" smd rect
			(at 0 0.4191)
			(size 0.508 0.5334)
			(layers "B.Cu" "B.Mask" "B.Paste")
			(net "NFP_PCIE0_PER4_N")
		)
		(zone
			(layer "B.Cu")
			(hatch none 0.5)
			(connect_pads
				(clearance 0)
			)
			(min_thickness 0.25)
			(keepout
				(tracks not_allowed)
				(vias allowed)
				(pads allowed)
				(copperpour not_allowed)
				(footprints allowed)
			)
			(placement
				(enabled no)
				(sheetname "")
			)
			(fill
				(thermal_gap 0.5)
				(thermal_bridge_width 0.5)
				(island_removal_mode 0)
			)
			(polygon
				(pts
					(xy 55.462424 0.7874) (xy 55.462424 0.7366) (xy 55.411624 0.7366) (xy 55.411624 0.7874)
				)
			)
		)
	)
	(footprint ""
		(layer "B.Cu")
		(at 76.251003 3.499002)
		(property "Reference" "V_A-DQS0-P"
			(at 0 0 0)
			(layer "B.SilkS")
			(hide yes)
			(effects
				(font
					(size 1.27 1.27)
				)
				(justify mirror)
			)
		)
		(property "Value" ""
			(at 0 0 0)
			(layer "B.Fab")
			(effects
				(font
					(size 1.27 1.27)
				)
				(justify mirror)
			)
		)
		(duplicate_pad_numbers_are_jumpers no)
		(pad "1" thru_hole circle
			(at 0 0 180)
			(size 0.4572 0.4572)
			(drill 0.20574)
			(layers "*.Cu" "*.Mask")
			(remove_unused_layers no)
			(net "DDR0_32A_DQS0_P")
			(clearance 0.1143)
			(thermal_gap 0.1143)
		)
	)
	(footprint ""
		(layer "B.Cu")
		(at 33.274 46.736)
		(property "Reference" "TP6"
			(at -0.66167 3.175 270)
			(unlocked yes)
			(layer "B.SilkS")
			(effects
				(font
					(size 0.7874 0.5842)
					(thickness 0.127)
				)
				(justify left mirror)
			)
		)
		(property "Value" "*"
			(at 0.4826 -0.14732 0)
			(unlocked yes)
			(layer "B.Fab")
			(hide yes)
			(effects
				(font
					(size 1.27 0.9652)
					(thickness 0.000001)
				)
				(justify left mirror)
			)
		)
		(property "Device Type" "TP_SMALL"
			(at 0.4826 -0.14732 0)
			(unlocked yes)
			(layer "B.Fab")
			(hide yes)
			(effects
				(font
					(size 1.27 0.9652)
					(thickness 0.000001)
				)
				(justify left mirror)
			)
		)
		(duplicate_pad_numbers_are_jumpers no)
		(fp_line
			(start -0.8636 -0.8636)
			(end 0.8636 -0.8636)
			(stroke
				(width 0.1524)
				(type default)
			)
			(layer "B.SilkS")
		)
		(fp_line
			(start -0.8636 0.8636)
			(end -0.8636 -0.8636)
			(stroke
				(width 0.1524)
				(type default)
			)
			(layer "B.SilkS")
		)
		(fp_line
			(start 0.8636 -0.8636)
			(end 0.8636 0.8636)
			(stroke
				(width 0.1524)
				(type default)
			)
			(layer "B.SilkS")
		)
		(fp_line
			(start 0.8636 0.8636)
			(end -0.8636 0.8636)
			(stroke
				(width 0.1524)
				(type default)
			)
			(layer "B.SilkS")
		)
		(fp_poly
			(pts
				(xy 0.635 -0.635) (xy 0.635 0.635) (xy -0.635 0.635) (xy -0.635 -0.635)
			)
			(stroke
				(width 0)
				(type default)
			)
			(fill no)
			(layer "B.CrtYd")
		)
		(pad "1" smd rect
			(at 0 0 180)
			(size 1.27 1.27)
			(layers "B.Cu" "B.Mask" "B.Paste")
			(net "NFP_JTAG_ARM_TCK")
		)
	)
	(footprint ""
		(layer "B.Cu")
		(at 27.813 22.352)
		(property "Reference" "R57"
			(at -0.02667 -0.635 270)
			(unlocked yes)
			(layer "B.SilkS")
			(effects
				(font
					(size 0.7874 0.5842)
					(thickness 0.127)
				)
				(justify left mirror)
			)
		)
		(property "Value" "4.75K"
			(at 0.148158 1.3462 270)
			(unlocked yes)
			(layer "B.Fab")
			(hide yes)
			(effects
				(font
					(size 1.27 0.9652)
					(thickness 0.000001)
				)
				(justify left mirror)
			)
		)
		(property "Device Type" "REST4024"
			(at 0.148158 1.3462 270)
			(unlocked yes)
			(layer "B.Fab")
			(hide yes)
			(effects
				(font
					(size 1.27 0.9652)
					(thickness 0.000001)
				)
				(justify left mirror)
			)
		)
		(duplicate_pad_numbers_are_jumpers no)
		(fp_poly
			(pts
				(xy -0.635 1.0668) (xy -0.635 -1.0668) (xy 0.635 -1.0668) (xy 0.635 1.0668)
			)
			(stroke
				(width 0)
				(type default)
			)
			(fill no)
			(layer "B.CrtYd")
		)
		(fp_line
			(start -0.254 -0.508)
			(end -0.254 0.508)
			(stroke
				(width 0.0254)
				(type default)
			)
			(layer "B.Fab")
		)
		(fp_line
			(start -0.254 0.508)
			(end 0.254 0.508)
			(stroke
				(width 0.0254)
				(type default)
			)
			(layer "B.Fab")
		)
		(fp_line
			(start 0.254 -0.508)
			(end -0.254 -0.508)
			(stroke
				(width 0.0254)
				(type default)
			)
			(layer "B.Fab")
		)
		(fp_line
			(start 0.254 0.508)
			(end 0.254 -0.508)
			(stroke
				(width 0.0254)
				(type default)
			)
			(layer "B.Fab")
		)
		(pad "1" smd rect
			(at 0 -0.4191 180)
			(size 0.508 0.5334)
			(layers "B.Cu" "B.Mask" "B.Paste")
			(net "NFP_SRESET_L")
		)
		(pad "2" smd rect
			(at 0 0.4191 180)
			(size 0.508 0.5334)
			(layers "B.Cu" "B.Mask" "B.Paste")
			(net "GND")
		)
		(zone
			(layer "B.Cu")
			(hatch none 0.5)
			(connect_pads
				(clearance 0)
			)
			(min_thickness 0.25)
			(keepout
				(tracks not_allowed)
				(vias allowed)
				(pads allowed)
				(copperpour not_allowed)
				(footprints allowed)
			)
			(placement
				(enabled no)
				(sheetname "")
			)
			(fill
				(thermal_gap 0.5)
				(thermal_bridge_width 0.5)
				(island_removal_mode 0)
			)
			(polygon
				(pts
					(xy 27.7876 22.3266) (xy 27.7876 22.3774) (xy 27.8384 22.3774) (xy 27.8384 22.3266)
				)
			)
		)
	)
	(footprint ""
		(layer "B.Cu")
		(at 43.737022 23.041991 90)
		(property "Reference" "C26"
			(at -0.479679 2.363978 0)
			(unlocked yes)
			(layer "B.SilkS")
			(effects
				(font
					(size 0.7874 0.5842)
					(thickness 0.127)
				)
				(justify mirror)
			)
		)
		(property "Value" ""
			(at 0 0 90)
			(layer "B.Fab")
			(effects
				(font
					(size 1.27 1.27)
				)
				(justify mirror)
			)
		)
		(duplicate_pad_numbers_are_jumpers no)
		(fp_circle
			(center 0 0)
			(end 0 0.104648)
			(stroke
				(width 0.1016)
				(type default)
			)
			(fill no)
			(layer "B.SilkS")
		)
		(fp_poly
			(pts
				(xy 0.381 -0.889) (xy 0.381 0.889) (xy -0.381 0.889) (xy -0.381 -0.889)
			)
			(stroke
				(width 0)
				(type default)
			)
			(fill no)
			(layer "B.CrtYd")
		)
		(fp_line
			(start 0.508 -1.016)
			(end 0.254 -1.016)
			(stroke
				(width 0.0254)
				(type default)
			)
			(layer "B.Fab")
		)
		(fp_line
			(start 0.254 -1.016)
			(end -0.508 -1.016)
			(stroke
				(width 0.0254)
				(type default)
			)
			(layer "B.Fab")
		)
		(fp_line
			(start -0.508 -1.016)
			(end -0.508 1.016)
			(stroke
				(width 0.0254)
				(type default)
			)
			(layer "B.Fab")
		)
		(fp_line
			(start 0.508 1.016)
			(end 0.508 -1.016)
			(stroke
				(width 0.0254)
				(type default)
			)
			(layer "B.Fab")
		)
		(fp_line
			(start -0.508 1.016)
			(end 0.508 1.016)
			(stroke
				(width 0.0254)
				(type default)
			)
			(layer "B.Fab")
		)
		(pad "1" smd custom
			(at 0 -0.500126 270)
			(size 0.127 0.127)
			(layers "B.Cu" "B.Mask" "B.Paste")
			(net "VDDA_PLL")
			(options
				(clearance outline)
				(anchor circle)
			)
			(primitives
				(gr_poly
					(pts
						(xy -0.1778 0.254) (xy 0.1778 0.254) (xy 0.254 0.1778) (xy 0.254 -0.1778) (xy 0.1778 -0.254) (xy -0.1778 -0.254)
						(xy -0.254 -0.1778) (xy -0.254 0.1778)
					)
					(width 0)
					(fill yes)
				)
			)
		)
		(pad "2" smd custom
			(at 0 0.500126 270)
			(size 0.127 0.127)
			(layers "B.Cu" "B.Mask" "B.Paste")
			(net "GND")
			(options
				(clearance outline)
				(anchor circle)
			)
			(primitives
				(gr_poly
					(pts
						(xy -0.1778 0.254) (xy 0.1778 0.254) (xy 0.254 0.1778) (xy 0.254 -0.1778) (xy 0.1778 -0.254) (xy -0.1778 -0.254)
						(xy -0.254 -0.1778) (xy -0.254 0.1778)
					)
					(width 0)
					(fill yes)
				)
			)
		)
	)
	(footprint ""
		(layer "B.Cu")
		(at 76.251003 26.613002)
		(property "Reference" "V_A-DQS4-P"
			(at 0 0 0)
			(layer "B.SilkS")
			(hide yes)
			(effects
				(font
					(size 1.27 1.27)
				)
				(justify mirror)
			)
		)
		(property "Value" ""
			(at 0 0 0)
			(layer "B.Fab")
			(effects
				(font
					(size 1.27 1.27)
				)
				(justify mirror)
			)
		)
		(duplicate_pad_numbers_are_jumpers no)
		(pad "1" thru_hole circle
			(at 0 0 180)
			(size 0.4572 0.4572)
			(drill 0.20574)
			(layers "*.Cu" "*.Mask")
			(remove_unused_layers no)
			(net "DDR0_32A_DQS4_P")
			(clearance 0.1143)
			(thermal_gap 0.1143)
		)
	)
	(footprint ""
		(layer "B.Cu")
		(at 43.5229 36.957 180)
		(property "Reference" "R76"
			(at -0.01143 0.889 270)
			(unlocked yes)
			(layer "B.SilkS")
			(effects
				(font
					(size 0.7874 0.5842)
					(thickness 0.127)
				)
				(justify left mirror)
			)
		)
		(property "Value" "4.75K"
			(at 0.148158 1.3462 90)
			(unlocked yes)
			(layer "B.Fab")
			(hide yes)
			(effects
				(font
					(size 1.27 0.9652)
					(thickness 0.000001)
				)
				(justify left mirror)
			)
		)
		(property "Device Type" "REST4024"
			(at 0.148158 1.3462 90)
			(unlocked yes)
			(layer "B.Fab")
			(hide yes)
			(effects
				(font
					(size 1.27 0.9652)
					(thickness 0.000001)
				)
				(justify left mirror)
			)
		)
		(duplicate_pad_numbers_are_jumpers no)
		(fp_poly
			(pts
				(xy -0.635 1.0668) (xy -0.635 -1.0668) (xy 0.635 -1.0668) (xy 0.635 1.0668)
			)
			(stroke
				(width 0)
				(type default)
			)
			(fill no)
			(layer "B.CrtYd")
		)
		(fp_line
			(start 0.254 0.508)
			(end 0.254 -0.508)
			(stroke
				(width 0.0254)
				(type default)
			)
			(layer "B.Fab")
		)
		(fp_line
			(start 0.254 -0.508)
			(end -0.254 -0.508)
			(stroke
				(width 0.0254)
				(type default)
			)
			(layer "B.Fab")
		)
		(fp_line
			(start -0.254 0.508)
			(end 0.254 0.508)
			(stroke
				(width 0.0254)
				(type default)
			)
			(layer "B.Fab")
		)
		(fp_line
			(start -0.254 -0.508)
			(end -0.254 0.508)
			(stroke
				(width 0.0254)
				(type default)
			)
			(layer "B.Fab")
		)
		(pad "1" smd rect
			(at 0 -0.4191)
			(size 0.508 0.5334)
			(layers "B.Cu" "B.Mask" "B.Paste")
			(net "CORE_FB_PH2_THERM_L")
		)
		(pad "2" smd rect
			(at 0 0.4191)
			(size 0.508 0.5334)
			(layers "B.Cu" "B.Mask" "B.Paste")
			(net "VDD_3.3V")
		)
		(zone
			(layer "B.Cu")
			(hatch none 0.5)
			(connect_pads
				(clearance 0)
			)
			(min_thickness 0.25)
			(keepout
				(tracks not_allowed)
				(vias allowed)
				(pads allowed)
				(copperpour not_allowed)
				(footprints allowed)
			)
			(placement
				(enabled no)
				(sheetname "")
			)
			(fill
				(thermal_gap 0.5)
				(thermal_bridge_width 0.5)
				(island_removal_mode 0)
			)
			(polygon
				(pts
					(xy 43.5483 36.9824) (xy 43.5483 36.9316) (xy 43.4975 36.9316) (xy 43.4975 36.9824)
				)
			)
		)
	)
	(footprint ""
		(layer "B.Cu")
		(at 52.237005 33.54197)
		(property "Reference" "C173"
			(at 0 0 0)
			(layer "B.SilkS")
			(hide yes)
			(effects
				(font
					(size 1.27 1.27)
				)
				(justify mirror)
			)
		)
		(property "Value" ""
			(at 0 0 0)
			(layer "B.Fab")
			(effects
				(font
					(size 1.27 1.27)
				)
				(justify mirror)
			)
		)
		(duplicate_pad_numbers_are_jumpers no)
		(fp_circle
			(center 0 0)
			(end 0.104648 0)
			(stroke
				(width 0.1016)
				(type default)
			)
			(fill no)
			(layer "B.SilkS")
		)
		(fp_poly
			(pts
				(xy 0.381 -0.889) (xy 0.381 0.889) (xy -0.381 0.889) (xy -0.381 -0.889)
			)
			(stroke
				(width 0)
				(type default)
			)
			(fill no)
			(layer "B.CrtYd")
		)
		(fp_line
			(start -0.508 -1.016)
			(end -0.508 1.016)
			(stroke
				(width 0.0254)
				(type default)
			)
			(layer "B.Fab")
		)
		(fp_line
			(start -0.508 1.016)
			(end 0.508 1.016)
			(stroke
				(width 0.0254)
				(type default)
			)
			(layer "B.Fab")
		)
		(fp_line
			(start 0.254 -1.016)
			(end -0.508 -1.016)
			(stroke
				(width 0.0254)
				(type default)
			)
			(layer "B.Fab")
		)
		(fp_line
			(start 0.508 -1.016)
			(end 0.254 -1.016)
			(stroke
				(width 0.0254)
				(type default)
			)
			(layer "B.Fab")
		)
		(fp_line
			(start 0.508 1.016)
			(end 0.508 -1.016)
			(stroke
				(width 0.0254)
				(type default)
			)
			(layer "B.Fab")
		)
		(pad "1" smd custom
			(at 0 -0.500126 180)
			(size 0.127 0.127)
			(layers "B.Cu" "B.Mask" "B.Paste")
			(net "VDD_CORE")
			(options
				(clearance outline)
				(anchor circle)
			)
			(primitives
				(gr_poly
					(pts
						(xy -0.1778 0.254) (xy 0.1778 0.254) (xy 0.254 0.1778) (xy 0.254 -0.1778) (xy 0.1778 -0.254) (xy -0.1778 -0.254)
						(xy -0.254 -0.1778) (xy -0.254 0.1778)
					)
					(width 0)
					(fill yes)
				)
			)
		)
		(pad "2" smd custom
			(at 0 0.500126 180)
			(size 0.127 0.127)
			(layers "B.Cu" "B.Mask" "B.Paste")
			(net "GND")
			(options
				(clearance outline)
				(anchor circle)
			)
			(primitives
				(gr_poly
					(pts
						(xy -0.1778 0.254) (xy 0.1778 0.254) (xy 0.254 0.1778) (xy 0.254 -0.1778) (xy 0.1778 -0.254) (xy -0.1778 -0.254)
						(xy -0.254 -0.1778) (xy -0.254 0.1778)
					)
					(width 0)
					(fill yes)
				)
			)
		)
	)
	(footprint ""
		(layer "B.Cu")
		(at 59.236991 11.542014)
		(property "Reference" "C166"
			(at -0.970661 -0.112014 270)
			(unlocked yes)
			(layer "B.SilkS")
			(effects
				(font
					(size 0.7874 0.5842)
					(thickness 0.127)
				)
				(justify mirror)
			)
		)
		(property "Value" ""
			(at 0 0 0)
			(layer "B.Fab")
			(effects
				(font
					(size 1.27 1.27)
				)
				(justify mirror)
			)
		)
		(duplicate_pad_numbers_are_jumpers no)
		(fp_circle
			(center 0 0)
			(end 0.104648 0)
			(stroke
				(width 0.1016)
				(type default)
			)
			(fill no)
			(layer "B.SilkS")
		)
		(fp_poly
			(pts
				(xy 0.381 -0.889) (xy 0.381 0.889) (xy -0.381 0.889) (xy -0.381 -0.889)
			)
			(stroke
				(width 0)
				(type default)
			)
			(fill no)
			(layer "B.CrtYd")
		)
		(fp_line
			(start -0.508 -1.016)
			(end -0.508 1.016)
			(stroke
				(width 0.0254)
				(type default)
			)
			(layer "B.Fab")
		)
		(fp_line
			(start -0.508 1.016)
			(end 0.508 1.016)
			(stroke
				(width 0.0254)
				(type default)
			)
			(layer "B.Fab")
		)
		(fp_line
			(start 0.254 -1.016)
			(end -0.508 -1.016)
			(stroke
				(width 0.0254)
				(type default)
			)
			(layer "B.Fab")
		)
		(fp_line
			(start 0.508 -1.016)
			(end 0.254 -1.016)
			(stroke
				(width 0.0254)
				(type default)
			)
			(layer "B.Fab")
		)
		(fp_line
			(start 0.508 1.016)
			(end 0.508 -1.016)
			(stroke
				(width 0.0254)
				(type default)
			)
			(layer "B.Fab")
		)
		(pad "1" smd custom
			(at 0 -0.500126 180)
			(size 0.127 0.127)
			(layers "B.Cu" "B.Mask" "B.Paste")
			(net "VDD_CORE")
			(options
				(clearance outline)
				(anchor circle)
			)
			(primitives
				(gr_poly
					(pts
						(xy -0.1778 0.254) (xy 0.1778 0.254) (xy 0.254 0.1778) (xy 0.254 -0.1778) (xy 0.1778 -0.254) (xy -0.1778 -0.254)
						(xy -0.254 -0.1778) (xy -0.254 0.1778)
					)
					(width 0)
					(fill yes)
				)
			)
		)
		(pad "2" smd custom
			(at 0 0.500126 180)
			(size 0.127 0.127)
			(layers "B.Cu" "B.Mask" "B.Paste")
			(net "GND")
			(options
				(clearance outline)
				(anchor circle)
			)
			(primitives
				(gr_poly
					(pts
						(xy -0.1778 0.254) (xy 0.1778 0.254) (xy 0.254 0.1778) (xy 0.254 -0.1778) (xy 0.1778 -0.254) (xy -0.1778 -0.254)
						(xy -0.254 -0.1778) (xy -0.254 0.1778)
					)
					(width 0)
					(fill yes)
				)
			)
		)
	)
	(footprint ""
		(layer "B.Cu")
		(at 64.897 35.687)
		(property "Reference" "R126"
			(at 0 0 0)
			(layer "B.SilkS")
			(hide yes)
			(effects
				(font
					(size 1.27 1.27)
				)
				(justify mirror)
			)
		)
		(property "Value" "10K"
			(at 0.148158 1.3462 270)
			(unlocked yes)
			(layer "B.Fab")
			(hide yes)
			(effects
				(font
					(size 1.27 0.9652)
					(thickness 0.000001)
				)
				(justify left mirror)
			)
		)
		(property "Device Type" "REST0005"
			(at 0.148158 1.3462 270)
			(unlocked yes)
			(layer "B.Fab")
			(hide yes)
			(effects
				(font
					(size 1.27 0.9652)
					(thickness 0.000001)
				)
				(justify left mirror)
			)
		)
		(duplicate_pad_numbers_are_jumpers no)
		(fp_poly
			(pts
				(xy -0.635 1.0668) (xy -0.635 -1.0668) (xy 0.635 -1.0668) (xy 0.635 1.0668)
			)
			(stroke
				(width 0)
				(type default)
			)
			(fill no)
			(layer "B.CrtYd")
		)
		(fp_line
			(start -0.254 -0.508)
			(end -0.254 0.508)
			(stroke
				(width 0.0254)
				(type default)
			)
			(layer "B.Fab")
		)
		(fp_line
			(start -0.254 0.508)
			(end 0.254 0.508)
			(stroke
				(width 0.0254)
				(type default)
			)
			(layer "B.Fab")
		)
		(fp_line
			(start 0.254 -0.508)
			(end -0.254 -0.508)
			(stroke
				(width 0.0254)
				(type default)
			)
			(layer "B.Fab")
		)
		(fp_line
			(start 0.254 0.508)
			(end 0.254 -0.508)
			(stroke
				(width 0.0254)
				(type default)
			)
			(layer "B.Fab")
		)
		(pad "1" smd rect
			(at 0 -0.4191 180)
			(size 0.508 0.5334)
			(layers "B.Cu" "B.Mask" "B.Paste")
			(net "VDD_5.0V")
		)
		(pad "2" smd rect
			(at 0 0.4191 180)
			(size 0.508 0.5334)
			(layers "B.Cu" "B.Mask" "B.Paste")
			(net "10N2253")
		)
		(zone
			(layer "B.Cu")
			(hatch none 0.5)
			(connect_pads
				(clearance 0)
			)
			(min_thickness 0.25)
			(keepout
				(tracks not_allowed)
				(vias allowed)
				(pads allowed)
				(copperpour not_allowed)
				(footprints allowed)
			)
			(placement
				(enabled no)
				(sheetname "")
			)
			(fill
				(thermal_gap 0.5)
				(thermal_bridge_width 0.5)
				(island_removal_mode 0)
			)
			(polygon
				(pts
					(xy 64.8716 35.6616) (xy 64.8716 35.7124) (xy 64.9224 35.7124) (xy 64.9224 35.6616)
				)
			)
		)
	)
	(footprint ""
		(layer "B.Cu")
		(at 72.251011 2.699004)
		(property "Reference" "V_A-DQ12"
			(at 0 0 0)
			(layer "B.SilkS")
			(hide yes)
			(effects
				(font
					(size 1.27 1.27)
				)
				(justify mirror)
			)
		)
		(property "Value" ""
			(at 0 0 0)
			(layer "B.Fab")
			(effects
				(font
					(size 1.27 1.27)
				)
				(justify mirror)
			)
		)
		(duplicate_pad_numbers_are_jumpers no)
		(pad "1" thru_hole circle
			(at 0 0 180)
			(size 0.4572 0.4572)
			(drill 0.20574)
			(layers "*.Cu" "*.Mask")
			(remove_unused_layers no)
			(net "DDR0_32A_DQ12")
			(clearance 0.1143)
			(thermal_gap 0.1143)
		)
	)
	(footprint ""
		(layer "B.Cu")
		(at 63.213996 0.762 180)
		(property "Reference" "C154"
			(at 0.145212 0.8763 270)
			(unlocked yes)
			(layer "B.SilkS")
			(effects
				(font
					(size 0.7874 0.5842)
					(thickness 0.127)
				)
				(justify left mirror)
			)
		)
		(property "Value" "0.22UF"
			(at 0.091846 0.2921 90)
			(unlocked yes)
			(layer "B.Fab")
			(hide yes)
			(effects
				(font
					(size 0.7874 0.5842)
					(thickness 0.2032)
				)
				(justify left mirror)
			)
		)
		(property "Device Type" "CAPC0062"
			(at 0.091846 0.2921 90)
			(unlocked yes)
			(layer "B.Fab")
			(hide yes)
			(effects
				(font
					(size 0.7874 0.5842)
					(thickness 0.2032)
				)
				(justify left mirror)
			)
		)
		(duplicate_pad_numbers_are_jumpers no)
		(fp_poly
			(pts
				(xy -0.635 1.0668) (xy -0.635 -1.0668) (xy 0.635 -1.0668) (xy 0.635 1.0668)
			)
			(stroke
				(width 0)
				(type default)
			)
			(fill no)
			(layer "B.CrtYd")
		)
		(fp_line
			(start 0.254 0.508)
			(end 0.254 -0.508)
			(stroke
				(width 0.0254)
				(type default)
			)
			(layer "B.Fab")
		)
		(fp_line
			(start 0.254 -0.508)
			(end -0.254 -0.508)
			(stroke
				(width 0.0254)
				(type default)
			)
			(layer "B.Fab")
		)
		(fp_line
			(start -0.254 0.508)
			(end 0.254 0.508)
			(stroke
				(width 0.0254)
				(type default)
			)
			(layer "B.Fab")
		)
		(fp_line
			(start -0.254 -0.508)
			(end -0.254 0.508)
			(stroke
				(width 0.0254)
				(type default)
			)
			(layer "B.Fab")
		)
		(pad "1" smd rect
			(at 0 -0.4191)
			(size 0.508 0.5334)
			(layers "B.Cu" "B.Mask" "B.Paste")
			(net "_NFP_PCIE0_PER0_N")
		)
		(pad "2" smd rect
			(at 0 0.4191)
			(size 0.508 0.5334)
			(layers "B.Cu" "B.Mask" "B.Paste")
			(net "NFP_PCIE0_PER0_N")
		)
		(zone
			(layer "B.Cu")
			(hatch none 0.5)
			(connect_pads
				(clearance 0)
			)
			(min_thickness 0.25)
			(keepout
				(tracks not_allowed)
				(vias allowed)
				(pads allowed)
				(copperpour not_allowed)
				(footprints allowed)
			)
			(placement
				(enabled no)
				(sheetname "")
			)
			(fill
				(thermal_gap 0.5)
				(thermal_bridge_width 0.5)
				(island_removal_mode 0)
			)
			(polygon
				(pts
					(xy 63.239396 0.7874) (xy 63.239396 0.7366) (xy 63.188596 0.7366) (xy 63.188596 0.7874)
				)
			)
		)
	)
	(footprint ""
		(layer "B.Cu")
		(at 41.237027 24.541988)
		(property "Reference" "R365"
			(at 0 0 0)
			(layer "B.SilkS")
			(hide yes)
			(effects
				(font
					(size 1.27 1.27)
				)
				(justify mirror)
			)
		)
		(property "Value" ""
			(at 0 0 0)
			(layer "B.Fab")
			(effects
				(font
					(size 1.27 1.27)
				)
				(justify mirror)
			)
		)
		(duplicate_pad_numbers_are_jumpers no)
		(fp_circle
			(center 0 0)
			(end 0.104648 0)
			(stroke
				(width 0.1016)
				(type default)
			)
			(fill no)
			(layer "B.SilkS")
		)
		(fp_poly
			(pts
				(xy 0.381 -0.889) (xy 0.381 0.889) (xy -0.381 0.889) (xy -0.381 -0.889)
			)
			(stroke
				(width 0)
				(type default)
			)
			(fill no)
			(layer "B.CrtYd")
		)
		(fp_line
			(start -0.508 -1.016)
			(end -0.508 1.016)
			(stroke
				(width 0.0254)
				(type default)
			)
			(layer "B.Fab")
		)
		(fp_line
			(start -0.508 1.016)
			(end 0.508 1.016)
			(stroke
				(width 0.0254)
				(type default)
			)
			(layer "B.Fab")
		)
		(fp_line
			(start 0.254 -1.016)
			(end -0.508 -1.016)
			(stroke
				(width 0.0254)
				(type default)
			)
			(layer "B.Fab")
		)
		(fp_line
			(start 0.508 -1.016)
			(end 0.254 -1.016)
			(stroke
				(width 0.0254)
				(type default)
			)
			(layer "B.Fab")
		)
		(fp_line
			(start 0.508 1.016)
			(end 0.508 -1.016)
			(stroke
				(width 0.0254)
				(type default)
			)
			(layer "B.Fab")
		)
		(pad "1" smd custom
			(at 0 -0.500126 180)
			(size 0.127 0.127)
			(layers "B.Cu" "B.Mask" "B.Paste")
			(net "_NFP_PCIE0_RESET_OUT_L")
			(options
				(clearance outline)
				(anchor circle)
			)
			(primitives
				(gr_poly
					(pts
						(xy -0.1778 0.254) (xy 0.1778 0.254) (xy 0.254 0.1778) (xy 0.254 -0.1778) (xy 0.1778 -0.254) (xy -0.1778 -0.254)
						(xy -0.254 -0.1778) (xy -0.254 0.1778)
					)
					(width 0)
					(fill yes)
				)
			)
		)
		(pad "2" smd custom
			(at 0 0.500126 180)
			(size 0.127 0.127)
			(layers "B.Cu" "B.Mask" "B.Paste")
			(net "VDD_3.3V")
			(options
				(clearance outline)
				(anchor circle)
			)
			(primitives
				(gr_poly
					(pts
						(xy -0.1778 0.254) (xy 0.1778 0.254) (xy 0.254 0.1778) (xy 0.254 -0.1778) (xy 0.1778 -0.254) (xy -0.1778 -0.254)
						(xy -0.254 -0.1778) (xy -0.254 0.1778)
					)
					(width 0)
					(fill yes)
				)
			)
		)
	)
	(footprint ""
		(layer "B.Cu")
		(at 40.237029 14.542008)
		(property "Reference" "R46"
			(at 1.011301 0.570992 270)
			(unlocked yes)
			(layer "B.SilkS")
			(effects
				(font
					(size 0.7874 0.5842)
					(thickness 0.127)
				)
				(justify mirror)
			)
		)
		(property "Value" ""
			(at 0 0 0)
			(layer "B.Fab")
			(effects
				(font
					(size 1.27 1.27)
				)
				(justify mirror)
			)
		)
		(duplicate_pad_numbers_are_jumpers no)
		(fp_circle
			(center 0 0)
			(end 0.104648 0)
			(stroke
				(width 0.1016)
				(type default)
			)
			(fill no)
			(layer "B.SilkS")
		)
		(fp_poly
			(pts
				(xy 0.381 -0.889) (xy 0.381 0.889) (xy -0.381 0.889) (xy -0.381 -0.889)
			)
			(stroke
				(width 0)
				(type default)
			)
			(fill no)
			(layer "B.CrtYd")
		)
		(fp_line
			(start -0.508 -1.016)
			(end -0.508 1.016)
			(stroke
				(width 0.0254)
				(type default)
			)
			(layer "B.Fab")
		)
		(fp_line
			(start -0.508 1.016)
			(end 0.508 1.016)
			(stroke
				(width 0.0254)
				(type default)
			)
			(layer "B.Fab")
		)
		(fp_line
			(start 0.254 -1.016)
			(end -0.508 -1.016)
			(stroke
				(width 0.0254)
				(type default)
			)
			(layer "B.Fab")
		)
		(fp_line
			(start 0.508 -1.016)
			(end 0.254 -1.016)
			(stroke
				(width 0.0254)
				(type default)
			)
			(layer "B.Fab")
		)
		(fp_line
			(start 0.508 1.016)
			(end 0.508 -1.016)
			(stroke
				(width 0.0254)
				(type default)
			)
			(layer "B.Fab")
		)
		(pad "1" smd custom
			(at 0 -0.500126 180)
			(size 0.127 0.127)
			(layers "B.Cu" "B.Mask" "B.Paste")
			(net "PGRM_JTAG_TRST_L")
			(options
				(clearance outline)
				(anchor circle)
			)
			(primitives
				(gr_poly
					(pts
						(xy -0.1778 0.254) (xy 0.1778 0.254) (xy 0.254 0.1778) (xy 0.254 -0.1778) (xy 0.1778 -0.254) (xy -0.1778 -0.254)
						(xy -0.254 -0.1778) (xy -0.254 0.1778)
					)
					(width 0)
					(fill yes)
				)
			)
		)
		(pad "2" smd custom
			(at 0 0.500126 180)
			(size 0.127 0.127)
			(layers "B.Cu" "B.Mask" "B.Paste")
			(net "GND")
			(options
				(clearance outline)
				(anchor circle)
			)
			(primitives
				(gr_poly
					(pts
						(xy -0.1778 0.254) (xy 0.1778 0.254) (xy 0.254 0.1778) (xy 0.254 -0.1778) (xy 0.1778 -0.254) (xy -0.1778 -0.254)
						(xy -0.254 -0.1778) (xy -0.254 0.1778)
					)
					(width 0)
					(fill yes)
				)
			)
		)
	)
	(footprint ""
		(layer "B.Cu")
		(at 72.251011 14.256004)
		(property "Reference" "V_A-DQ24"
			(at 0 0 0)
			(layer "B.SilkS")
			(hide yes)
			(effects
				(font
					(size 1.27 1.27)
				)
				(justify mirror)
			)
		)
		(property "Value" ""
			(at 0 0 0)
			(layer "B.Fab")
			(effects
				(font
					(size 1.27 1.27)
				)
				(justify mirror)
			)
		)
		(duplicate_pad_numbers_are_jumpers no)
		(pad "1" thru_hole circle
			(at 0 0 180)
			(size 0.4572 0.4572)
			(drill 0.20574)
			(layers "*.Cu" "*.Mask")
			(remove_unused_layers no)
			(net "DDR0_32A_DQ24")
			(clearance 0.1143)
			(thermal_gap 0.1143)
		)
	)
	(footprint ""
		(layer "B.Cu")
		(at 22.352 2.794)
		(property "Reference" "R380"
			(at -1.04267 0.889 270)
			(unlocked yes)
			(layer "B.SilkS")
			(effects
				(font
					(size 0.7874 0.5842)
					(thickness 0.127)
				)
				(justify left mirror)
			)
		)
		(property "Value" "4.75K"
			(at 0.148158 1.3462 270)
			(unlocked yes)
			(layer "B.Fab")
			(hide yes)
			(effects
				(font
					(size 1.27 0.9652)
					(thickness 0.000001)
				)
				(justify left mirror)
			)
		)
		(property "Device Type" "REST4024"
			(at 0.148158 1.3462 270)
			(unlocked yes)
			(layer "B.Fab")
			(hide yes)
			(effects
				(font
					(size 1.27 0.9652)
					(thickness 0.000001)
				)
				(justify left mirror)
			)
		)
		(duplicate_pad_numbers_are_jumpers no)
		(fp_poly
			(pts
				(xy -0.635 1.0668) (xy -0.635 -1.0668) (xy 0.635 -1.0668) (xy 0.635 1.0668)
			)
			(stroke
				(width 0)
				(type default)
			)
			(fill no)
			(layer "B.CrtYd")
		)
		(fp_line
			(start -0.254 -0.508)
			(end -0.254 0.508)
			(stroke
				(width 0.0254)
				(type default)
			)
			(layer "B.Fab")
		)
		(fp_line
			(start -0.254 0.508)
			(end 0.254 0.508)
			(stroke
				(width 0.0254)
				(type default)
			)
			(layer "B.Fab")
		)
		(fp_line
			(start 0.254 -0.508)
			(end -0.254 -0.508)
			(stroke
				(width 0.0254)
				(type default)
			)
			(layer "B.Fab")
		)
		(fp_line
			(start 0.254 0.508)
			(end 0.254 -0.508)
			(stroke
				(width 0.0254)
				(type default)
			)
			(layer "B.Fab")
		)
		(pad "1" smd rect
			(at 0 -0.4191 180)
			(size 0.508 0.5334)
			(layers "B.Cu" "B.Mask" "B.Paste")
			(net "NFP_PCIE0_WAKE_L")
		)
		(pad "2" smd rect
			(at 0 0.4191 180)
			(size 0.508 0.5334)
			(layers "B.Cu" "B.Mask" "B.Paste")
			(net "EXT_3.3V")
		)
		(zone
			(layer "B.Cu")
			(hatch none 0.5)
			(connect_pads
				(clearance 0)
			)
			(min_thickness 0.25)
			(keepout
				(tracks not_allowed)
				(vias allowed)
				(pads allowed)
				(copperpour not_allowed)
				(footprints allowed)
			)
			(placement
				(enabled no)
				(sheetname "")
			)
			(fill
				(thermal_gap 0.5)
				(thermal_bridge_width 0.5)
				(island_removal_mode 0)
			)
			(polygon
				(pts
					(xy 22.3266 2.7686) (xy 22.3266 2.8194) (xy 22.3774 2.8194) (xy 22.3774 2.7686)
				)
			)
		)
	)
	(footprint ""
		(layer "B.Cu")
		(at 72.251011 3.499002)
		(property "Reference" "V_A-DQ14"
			(at 0 0 0)
			(layer "B.SilkS")
			(hide yes)
			(effects
				(font
					(size 1.27 1.27)
				)
				(justify mirror)
			)
		)
		(property "Value" ""
			(at 0 0 0)
			(layer "B.Fab")
			(effects
				(font
					(size 1.27 1.27)
				)
				(justify mirror)
			)
		)
		(duplicate_pad_numbers_are_jumpers no)
		(pad "1" thru_hole circle
			(at 0 0 180)
			(size 0.4572 0.4572)
			(drill 0.20574)
			(layers "*.Cu" "*.Mask")
			(remove_unused_layers no)
			(net "DDR0_32A_DQ14")
			(clearance 0.1143)
			(thermal_gap 0.1143)
		)
	)
	(footprint ""
		(layer "B.Cu")
		(at 45.737018 17.042003 90)
		(property "Reference" "C269"
			(at 0 0 90)
			(layer "B.SilkS")
			(hide yes)
			(effects
				(font
					(size 1.27 1.27)
				)
				(justify mirror)
			)
		)
		(property "Value" ""
			(at 0 0 90)
			(layer "B.Fab")
			(effects
				(font
					(size 1.27 1.27)
				)
				(justify mirror)
			)
		)
		(duplicate_pad_numbers_are_jumpers no)
		(fp_circle
			(center 0 0)
			(end 0 0.104648)
			(stroke
				(width 0.1016)
				(type default)
			)
			(fill no)
			(layer "B.SilkS")
		)
		(fp_poly
			(pts
				(xy 0.381 -0.889) (xy 0.381 0.889) (xy -0.381 0.889) (xy -0.381 -0.889)
			)
			(stroke
				(width 0)
				(type default)
			)
			(fill no)
			(layer "B.CrtYd")
		)
		(fp_line
			(start 0.508 -1.016)
			(end 0.254 -1.016)
			(stroke
				(width 0.0254)
				(type default)
			)
			(layer "B.Fab")
		)
		(fp_line
			(start 0.254 -1.016)
			(end -0.508 -1.016)
			(stroke
				(width 0.0254)
				(type default)
			)
			(layer "B.Fab")
		)
		(fp_line
			(start -0.508 -1.016)
			(end -0.508 1.016)
			(stroke
				(width 0.0254)
				(type default)
			)
			(layer "B.Fab")
		)
		(fp_line
			(start 0.508 1.016)
			(end 0.508 -1.016)
			(stroke
				(width 0.0254)
				(type default)
			)
			(layer "B.Fab")
		)
		(fp_line
			(start -0.508 1.016)
			(end 0.508 1.016)
			(stroke
				(width 0.0254)
				(type default)
			)
			(layer "B.Fab")
		)
		(pad "1" smd custom
			(at 0 -0.500126 270)
			(size 0.127 0.127)
			(layers "B.Cu" "B.Mask" "B.Paste")
			(net "VDD_1.8V")
			(options
				(clearance outline)
				(anchor circle)
			)
			(primitives
				(gr_poly
					(pts
						(xy -0.1778 0.254) (xy 0.1778 0.254) (xy 0.254 0.1778) (xy 0.254 -0.1778) (xy 0.1778 -0.254) (xy -0.1778 -0.254)
						(xy -0.254 -0.1778) (xy -0.254 0.1778)
					)
					(width 0)
					(fill yes)
				)
			)
		)
		(pad "2" smd custom
			(at 0 0.500126 270)
			(size 0.127 0.127)
			(layers "B.Cu" "B.Mask" "B.Paste")
			(net "GND")
			(options
				(clearance outline)
				(anchor circle)
			)
			(primitives
				(gr_poly
					(pts
						(xy -0.1778 0.254) (xy 0.1778 0.254) (xy 0.254 0.1778) (xy 0.254 -0.1778) (xy 0.1778 -0.254) (xy -0.1778 -0.254)
						(xy -0.254 -0.1778) (xy -0.254 0.1778)
					)
					(width 0)
					(fill yes)
				)
			)
		)
	)
	(footprint ""
		(layer "B.Cu")
		(at 82.65099 19.055994)
		(property "Reference" "V2_A-A04"
			(at 0 0 0)
			(layer "B.SilkS")
			(hide yes)
			(effects
				(font
					(size 1.27 1.27)
				)
				(justify mirror)
			)
		)
		(property "Value" ""
			(at 0 0 0)
			(layer "B.Fab")
			(effects
				(font
					(size 1.27 1.27)
				)
				(justify mirror)
			)
		)
		(duplicate_pad_numbers_are_jumpers no)
		(pad "1" thru_hole circle
			(at 0 0 180)
			(size 0.4572 0.4572)
			(drill 0.20574)
			(layers "*.Cu" "*.Mask")
			(remove_unused_layers no)
			(net "DDR0_32A_A4")
			(clearance 0.1143)
			(thermal_gap 0.1143)
		)
	)
	(footprint ""
		(layer "B.Cu")
		(at 44.73702 16.042005 90)
		(property "Reference" "C268"
			(at 0 0 90)
			(layer "B.SilkS")
			(hide yes)
			(effects
				(font
					(size 1.27 1.27)
				)
				(justify mirror)
			)
		)
		(property "Value" ""
			(at 0 0 90)
			(layer "B.Fab")
			(effects
				(font
					(size 1.27 1.27)
				)
				(justify mirror)
			)
		)
		(duplicate_pad_numbers_are_jumpers no)
		(fp_circle
			(center 0 0)
			(end 0 0.104648)
			(stroke
				(width 0.1016)
				(type default)
			)
			(fill no)
			(layer "B.SilkS")
		)
		(fp_poly
			(pts
				(xy 0.381 -0.889) (xy 0.381 0.889) (xy -0.381 0.889) (xy -0.381 -0.889)
			)
			(stroke
				(width 0)
				(type default)
			)
			(fill no)
			(layer "B.CrtYd")
		)
		(fp_line
			(start 0.508 -1.016)
			(end 0.254 -1.016)
			(stroke
				(width 0.0254)
				(type default)
			)
			(layer "B.Fab")
		)
		(fp_line
			(start 0.254 -1.016)
			(end -0.508 -1.016)
			(stroke
				(width 0.0254)
				(type default)
			)
			(layer "B.Fab")
		)
		(fp_line
			(start -0.508 -1.016)
			(end -0.508 1.016)
			(stroke
				(width 0.0254)
				(type default)
			)
			(layer "B.Fab")
		)
		(fp_line
			(start 0.508 1.016)
			(end 0.508 -1.016)
			(stroke
				(width 0.0254)
				(type default)
			)
			(layer "B.Fab")
		)
		(fp_line
			(start -0.508 1.016)
			(end 0.508 1.016)
			(stroke
				(width 0.0254)
				(type default)
			)
			(layer "B.Fab")
		)
		(pad "1" smd custom
			(at 0 -0.500126 270)
			(size 0.127 0.127)
			(layers "B.Cu" "B.Mask" "B.Paste")
			(net "VDD_3.3V")
			(options
				(clearance outline)
				(anchor circle)
			)
			(primitives
				(gr_poly
					(pts
						(xy -0.1778 0.254) (xy 0.1778 0.254) (xy 0.254 0.1778) (xy 0.254 -0.1778) (xy 0.1778 -0.254) (xy -0.1778 -0.254)
						(xy -0.254 -0.1778) (xy -0.254 0.1778)
					)
					(width 0)
					(fill yes)
				)
			)
		)
		(pad "2" smd custom
			(at 0 0.500126 270)
			(size 0.127 0.127)
			(layers "B.Cu" "B.Mask" "B.Paste")
			(net "GND")
			(options
				(clearance outline)
				(anchor circle)
			)
			(primitives
				(gr_poly
					(pts
						(xy -0.1778 0.254) (xy 0.1778 0.254) (xy 0.254 0.1778) (xy 0.254 -0.1778) (xy 0.1778 -0.254) (xy -0.1778 -0.254)
						(xy -0.254 -0.1778) (xy -0.254 0.1778)
					)
					(width 0)
					(fill yes)
				)
			)
		)
	)
	(footprint ""
		(layer "B.Cu")
		(at 56.736996 11.042015 -90)
		(property "Reference" "C78"
			(at 0 0 90)
			(layer "B.SilkS")
			(hide yes)
			(effects
				(font
					(size 1.27 1.27)
				)
				(justify mirror)
			)
		)
		(property "Value" ""
			(at 0 0 90)
			(layer "B.Fab")
			(effects
				(font
					(size 1.27 1.27)
				)
				(justify mirror)
			)
		)
		(duplicate_pad_numbers_are_jumpers no)
		(fp_circle
			(center 0 0)
			(end 0 -0.104648)
			(stroke
				(width 0.1016)
				(type default)
			)
			(fill no)
			(layer "B.SilkS")
		)
		(fp_poly
			(pts
				(xy 0.381 -0.889) (xy 0.381 0.889) (xy -0.381 0.889) (xy -0.381 -0.889)
			)
			(stroke
				(width 0)
				(type default)
			)
			(fill no)
			(layer "B.CrtYd")
		)
		(fp_line
			(start -0.508 1.016)
			(end 0.508 1.016)
			(stroke
				(width 0.0254)
				(type default)
			)
			(layer "B.Fab")
		)
		(fp_line
			(start 0.508 1.016)
			(end 0.508 -1.016)
			(stroke
				(width 0.0254)
				(type default)
			)
			(layer "B.Fab")
		)
		(fp_line
			(start -0.508 -1.016)
			(end -0.508 1.016)
			(stroke
				(width 0.0254)
				(type default)
			)
			(layer "B.Fab")
		)
		(fp_line
			(start 0.254 -1.016)
			(end -0.508 -1.016)
			(stroke
				(width 0.0254)
				(type default)
			)
			(layer "B.Fab")
		)
		(fp_line
			(start 0.508 -1.016)
			(end 0.254 -1.016)
			(stroke
				(width 0.0254)
				(type default)
			)
			(layer "B.Fab")
		)
		(pad "1" smd custom
			(at 0 -0.500126 90)
			(size 0.127 0.127)
			(layers "B.Cu" "B.Mask" "B.Paste")
			(net "VDD_CORE")
			(options
				(clearance outline)
				(anchor circle)
			)
			(primitives
				(gr_poly
					(pts
						(xy -0.1778 0.254) (xy 0.1778 0.254) (xy 0.254 0.1778) (xy 0.254 -0.1778) (xy 0.1778 -0.254) (xy -0.1778 -0.254)
						(xy -0.254 -0.1778) (xy -0.254 0.1778)
					)
					(width 0)
					(fill yes)
				)
			)
		)
		(pad "2" smd custom
			(at 0 0.500126 90)
			(size 0.127 0.127)
			(layers "B.Cu" "B.Mask" "B.Paste")
			(net "GND")
			(options
				(clearance outline)
				(anchor circle)
			)
			(primitives
				(gr_poly
					(pts
						(xy -0.1778 0.254) (xy 0.1778 0.254) (xy 0.254 0.1778) (xy 0.254 -0.1778) (xy 0.1778 -0.254) (xy -0.1778 -0.254)
						(xy -0.254 -0.1778) (xy -0.254 0.1778)
					)
					(width 0)
					(fill yes)
				)
			)
		)
	)
	(footprint ""
		(layer "B.Cu")
		(at 22.225 8.128)
		(property "Reference" "R25"
			(at 0 0 0)
			(layer "B.SilkS")
			(hide yes)
			(effects
				(font
					(size 1.27 1.27)
				)
				(justify mirror)
			)
		)
		(property "Value" "4.75K"
			(at 0.148158 1.3462 270)
			(unlocked yes)
			(layer "B.Fab")
			(hide yes)
			(effects
				(font
					(size 1.27 0.9652)
					(thickness 0.000001)
				)
				(justify left mirror)
			)
		)
		(property "Device Type" "REST4024"
			(at 0.148158 1.3462 270)
			(unlocked yes)
			(layer "B.Fab")
			(hide yes)
			(effects
				(font
					(size 1.27 0.9652)
					(thickness 0.000001)
				)
				(justify left mirror)
			)
		)
		(duplicate_pad_numbers_are_jumpers no)
		(fp_poly
			(pts
				(xy -0.635 1.0668) (xy -0.635 -1.0668) (xy 0.635 -1.0668) (xy 0.635 1.0668)
			)
			(stroke
				(width 0)
				(type default)
			)
			(fill no)
			(layer "B.CrtYd")
		)
		(fp_line
			(start -0.254 -0.508)
			(end -0.254 0.508)
			(stroke
				(width 0.0254)
				(type default)
			)
			(layer "B.Fab")
		)
		(fp_line
			(start -0.254 0.508)
			(end 0.254 0.508)
			(stroke
				(width 0.0254)
				(type default)
			)
			(layer "B.Fab")
		)
		(fp_line
			(start 0.254 -0.508)
			(end -0.254 -0.508)
			(stroke
				(width 0.0254)
				(type default)
			)
			(layer "B.Fab")
		)
		(fp_line
			(start 0.254 0.508)
			(end 0.254 -0.508)
			(stroke
				(width 0.0254)
				(type default)
			)
			(layer "B.Fab")
		)
		(pad "1" smd rect
			(at 0 -0.4191 180)
			(size 0.508 0.5334)
			(layers "B.Cu" "B.Mask" "B.Paste")
			(net "VDD_3.3V")
		)
		(pad "2" smd rect
			(at 0 0.4191 180)
			(size 0.508 0.5334)
			(layers "B.Cu" "B.Mask" "B.Paste")
			(net "NFP_CFG_SPI_FLASH_HOLD_L")
		)
		(zone
			(layer "B.Cu")
			(hatch none 0.5)
			(connect_pads
				(clearance 0)
			)
			(min_thickness 0.25)
			(keepout
				(tracks not_allowed)
				(vias allowed)
				(pads allowed)
				(copperpour not_allowed)
				(footprints allowed)
			)
			(placement
				(enabled no)
				(sheetname "")
			)
			(fill
				(thermal_gap 0.5)
				(thermal_bridge_width 0.5)
				(island_removal_mode 0)
			)
			(polygon
				(pts
					(xy 22.1996 8.1026) (xy 22.1996 8.1534) (xy 22.2504 8.1534) (xy 22.2504 8.1026)
				)
			)
		)
	)
	(footprint ""
		(layer "B.Cu")
		(at 37.5285 29.845)
		(property "Reference" "C57"
			(at -1.48717 -1.016 270)
			(unlocked yes)
			(layer "B.SilkS")
			(effects
				(font
					(size 0.7874 0.5842)
					(thickness 0.127)
				)
				(justify left mirror)
			)
		)
		(property "Value" "100UF"
			(at 0.78232 0.4826 270)
			(unlocked yes)
			(layer "B.Fab")
			(hide yes)
			(effects
				(font
					(size 1.27 0.9652)
					(thickness 0.000001)
				)
				(justify left mirror)
			)
		)
		(property "Device Type" "CAPC0087"
			(at 0.78232 0.4826 270)
			(unlocked yes)
			(layer "B.Fab")
			(hide yes)
			(effects
				(font
					(size 1.27 0.9652)
					(thickness 0.000001)
				)
				(justify left mirror)
			)
		)
		(duplicate_pad_numbers_are_jumpers no)
		(fp_circle
			(center 0 0)
			(end 0.508 0)
			(stroke
				(width 0.2032)
				(type default)
			)
			(fill no)
			(layer "B.SilkS")
		)
		(fp_poly
			(pts
				(xy 1.27 2.9464) (xy -1.27 2.9464) (xy -1.27 -2.9464) (xy 1.27 -2.9464)
			)
			(stroke
				(width 0)
				(type default)
			)
			(fill no)
			(layer "B.CrtYd")
		)
		(fp_line
			(start -1.016 -2.794)
			(end -1.016 2.794)
			(stroke
				(width 0.0254)
				(type default)
			)
			(layer "B.Fab")
		)
		(fp_line
			(start -1.016 2.794)
			(end 1.016 2.794)
			(stroke
				(width 0.0254)
				(type default)
			)
			(layer "B.Fab")
		)
		(fp_line
			(start 1.016 -2.794)
			(end -1.016 -2.794)
			(stroke
				(width 0.0254)
				(type default)
			)
			(layer "B.Fab")
		)
		(fp_line
			(start 1.016 2.794)
			(end 1.016 -2.794)
			(stroke
				(width 0.0254)
				(type default)
			)
			(layer "B.Fab")
		)
		(pad "1" smd rect
			(at 0 -1.6764 180)
			(size 1.524 1.524)
			(layers "B.Cu" "B.Mask" "B.Paste")
			(net "VDDA_PLL")
		)
		(pad "2" smd rect
			(at 0 1.6764 180)
			(size 1.524 1.524)
			(layers "B.Cu" "B.Mask" "B.Paste")
			(net "GND")
		)
		(zone
			(layer "B.Cu")
			(hatch none 0.5)
			(connect_pads
				(clearance 0)
			)
			(min_thickness 0.25)
			(keepout
				(tracks not_allowed)
				(vias allowed)
				(pads allowed)
				(copperpour not_allowed)
				(footprints allowed)
			)
			(placement
				(enabled no)
				(sheetname "")
			)
			(fill
				(thermal_gap 0.5)
				(thermal_bridge_width 0.5)
				(island_removal_mode 0)
			)
			(polygon
				(pts
					(xy 38.3159 28.956) (xy 36.7411 28.956) (xy 36.7411 29.1084) (xy 38.3159 29.1084)
				)
			)
		)
		(zone
			(layer "B.Cu")
			(hatch none 0.5)
			(connect_pads
				(clearance 0)
			)
			(min_thickness 0.25)
			(keepout
				(tracks not_allowed)
				(vias allowed)
				(pads allowed)
				(copperpour not_allowed)
				(footprints allowed)
			)
			(placement
				(enabled no)
				(sheetname "")
			)
			(fill
				(thermal_gap 0.5)
				(thermal_bridge_width 0.5)
				(island_removal_mode 0)
			)
			(polygon
				(pts
					(xy 38.3159 30.5816) (xy 36.7411 30.5816) (xy 36.7411 30.734) (xy 38.3159 30.734)
				)
			)
		)
		(zone
			(layer "B.Cu")
			(hatch none 0.5)
			(connect_pads
				(clearance 0)
			)
			(min_thickness 0.25)
			(keepout
				(tracks allowed)
				(vias not_allowed)
				(pads allowed)
				(copperpour not_allowed)
				(footprints allowed)
			)
			(placement
				(enabled no)
				(sheetname "")
			)
			(fill
				(thermal_gap 0.5)
				(thermal_bridge_width 0.5)
				(island_removal_mode 0)
			)
			(polygon
				(pts
					(xy 38.3159 31.4452) (xy 36.7411 31.4452) (xy 36.7411 28.956) (xy 38.3159 28.956)
				)
			)
		)
	)
	(footprint ""
		(layer "B.Cu")
		(at 73.851008 18.255996)
		(property "Reference" "V_A-DQ27"
			(at 0 0 0)
			(layer "B.SilkS")
			(hide yes)
			(effects
				(font
					(size 1.27 1.27)
				)
				(justify mirror)
			)
		)
		(property "Value" ""
			(at 0 0 0)
			(layer "B.Fab")
			(effects
				(font
					(size 1.27 1.27)
				)
				(justify mirror)
			)
		)
		(duplicate_pad_numbers_are_jumpers no)
		(pad "1" thru_hole circle
			(at 0 0 180)
			(size 0.4572 0.4572)
			(drill 0.20574)
			(layers "*.Cu" "*.Mask")
			(remove_unused_layers no)
			(net "DDR0_32A_DQ27")
			(clearance 0.1143)
			(thermal_gap 0.1143)
		)
	)
	(footprint ""
		(layer "B.Cu")
		(at 37.6428 21.082 -90)
		(property "Reference" "R205"
			(at 0 0 90)
			(layer "B.SilkS")
			(hide yes)
			(effects
				(font
					(size 1.27 1.27)
				)
				(justify mirror)
			)
		)
		(property "Value" "39.0"
			(at 0.148158 1.3462 180)
			(unlocked yes)
			(layer "B.Fab")
			(hide yes)
			(effects
				(font
					(size 1.27 0.9652)
					(thickness 0.000001)
				)
				(justify left mirror)
			)
		)
		(property "Device Type" "REST0108"
			(at 0.148158 1.3462 180)
			(unlocked yes)
			(layer "B.Fab")
			(hide yes)
			(effects
				(font
					(size 1.27 0.9652)
					(thickness 0.000001)
				)
				(justify left mirror)
			)
		)
		(duplicate_pad_numbers_are_jumpers no)
		(fp_poly
			(pts
				(xy -0.635 1.0668) (xy -0.635 -1.0668) (xy 0.635 -1.0668) (xy 0.635 1.0668)
			)
			(stroke
				(width 0)
				(type default)
			)
			(fill no)
			(layer "B.CrtYd")
		)
		(fp_line
			(start -0.254 0.508)
			(end 0.254 0.508)
			(stroke
				(width 0.0254)
				(type default)
			)
			(layer "B.Fab")
		)
		(fp_line
			(start 0.254 0.508)
			(end 0.254 -0.508)
			(stroke
				(width 0.0254)
				(type default)
			)
			(layer "B.Fab")
		)
		(fp_line
			(start -0.254 -0.508)
			(end -0.254 0.508)
			(stroke
				(width 0.0254)
				(type default)
			)
			(layer "B.Fab")
		)
		(fp_line
			(start 0.254 -0.508)
			(end -0.254 -0.508)
			(stroke
				(width 0.0254)
				(type default)
			)
			(layer "B.Fab")
		)
		(pad "1" smd rect
			(at 0 -0.4191 90)
			(size 0.508 0.5334)
			(layers "B.Cu" "B.Mask" "B.Paste")
			(net "_NFP_CFG_SPI_FLASH_SCK")
		)
		(pad "2" smd rect
			(at 0 0.4191 90)
			(size 0.508 0.5334)
			(layers "B.Cu" "B.Mask" "B.Paste")
			(net "NFP_CFG_SPI_FLASH_SCK")
		)
		(zone
			(layer "B.Cu")
			(hatch none 0.5)
			(connect_pads
				(clearance 0)
			)
			(min_thickness 0.25)
			(keepout
				(tracks not_allowed)
				(vias allowed)
				(pads allowed)
				(copperpour not_allowed)
				(footprints allowed)
			)
			(placement
				(enabled no)
				(sheetname "")
			)
			(fill
				(thermal_gap 0.5)
				(thermal_bridge_width 0.5)
				(island_removal_mode 0)
			)
			(polygon
				(pts
					(xy 37.6682 21.0566) (xy 37.6174 21.0566) (xy 37.6174 21.1074) (xy 37.6682 21.1074)
				)
			)
		)
	)
	(footprint ""
		(layer "B.Cu")
		(at 44.73702 20.041997 -90)
		(property "Reference" "R320"
			(at 0 0 90)
			(layer "B.SilkS")
			(hide yes)
			(effects
				(font
					(size 1.27 1.27)
				)
				(justify mirror)
			)
		)
		(property "Value" ""
			(at 0 0 90)
			(layer "B.Fab")
			(effects
				(font
					(size 1.27 1.27)
				)
				(justify mirror)
			)
		)
		(duplicate_pad_numbers_are_jumpers no)
		(fp_circle
			(center 0 0)
			(end 0 -0.104648)
			(stroke
				(width 0.1016)
				(type default)
			)
			(fill no)
			(layer "B.SilkS")
		)
		(fp_poly
			(pts
				(xy 0.381 -0.889) (xy 0.381 0.889) (xy -0.381 0.889) (xy -0.381 -0.889)
			)
			(stroke
				(width 0)
				(type default)
			)
			(fill no)
			(layer "B.CrtYd")
		)
		(fp_line
			(start -0.508 1.016)
			(end 0.508 1.016)
			(stroke
				(width 0.0254)
				(type default)
			)
			(layer "B.Fab")
		)
		(fp_line
			(start 0.508 1.016)
			(end 0.508 -1.016)
			(stroke
				(width 0.0254)
				(type default)
			)
			(layer "B.Fab")
		)
		(fp_line
			(start -0.508 -1.016)
			(end -0.508 1.016)
			(stroke
				(width 0.0254)
				(type default)
			)
			(layer "B.Fab")
		)
		(fp_line
			(start 0.254 -1.016)
			(end -0.508 -1.016)
			(stroke
				(width 0.0254)
				(type default)
			)
			(layer "B.Fab")
		)
		(fp_line
			(start 0.508 -1.016)
			(end 0.254 -1.016)
			(stroke
				(width 0.0254)
				(type default)
			)
			(layer "B.Fab")
		)
		(pad "1" smd custom
			(at 0 -0.500126 90)
			(size 0.127 0.127)
			(layers "B.Cu" "B.Mask" "B.Paste")
			(net "GND")
			(options
				(clearance outline)
				(anchor circle)
			)
			(primitives
				(gr_poly
					(pts
						(xy -0.1778 0.254) (xy 0.1778 0.254) (xy 0.254 0.1778) (xy 0.254 -0.1778) (xy 0.1778 -0.254) (xy -0.1778 -0.254)
						(xy -0.254 -0.1778) (xy -0.254 0.1778)
					)
					(width 0)
					(fill yes)
				)
			)
		)
		(pad "2" smd custom
			(at 0 0.500126 90)
			(size 0.127 0.127)
			(layers "B.Cu" "B.Mask" "B.Paste")
			(net "NFP_CLK_REF_P")
			(options
				(clearance outline)
				(anchor circle)
			)
			(primitives
				(gr_poly
					(pts
						(xy -0.1778 0.254) (xy 0.1778 0.254) (xy 0.254 0.1778) (xy 0.254 -0.1778) (xy 0.1778 -0.254) (xy -0.1778 -0.254)
						(xy -0.254 -0.1778) (xy -0.254 0.1778)
					)
					(width 0)
					(fill yes)
				)
			)
		)
	)
	(footprint ""
		(layer "B.Cu")
		(at 82.65099 7.498994)
		(property "Reference" "V1_A-A04"
			(at 0 0 0)
			(layer "B.SilkS")
			(hide yes)
			(effects
				(font
					(size 1.27 1.27)
				)
				(justify mirror)
			)
		)
		(property "Value" ""
			(at 0 0 0)
			(layer "B.Fab")
			(effects
				(font
					(size 1.27 1.27)
				)
				(justify mirror)
			)
		)
		(duplicate_pad_numbers_are_jumpers no)
		(pad "1" thru_hole circle
			(at 0 0 180)
			(size 0.4572 0.4572)
			(drill 0.20574)
			(layers "*.Cu" "*.Mask")
			(remove_unused_layers no)
			(net "DDR0_32A_A4")
			(clearance 0.1143)
			(thermal_gap 0.1143)
		)
	)
	(footprint ""
		(layer "B.Cu")
		(at 37.084 46.736)
		(property "Reference" "TP8"
			(at 0 0 0)
			(layer "B.SilkS")
			(hide yes)
			(effects
				(font
					(size 1.27 1.27)
				)
				(justify mirror)
			)
		)
		(property "Value" "*"
			(at 0.4826 -0.14732 0)
			(unlocked yes)
			(layer "B.Fab")
			(hide yes)
			(effects
				(font
					(size 1.27 0.9652)
					(thickness 0.000001)
				)
				(justify left mirror)
			)
		)
		(property "Device Type" "TP_SMALL"
			(at 0.4826 -0.14732 0)
			(unlocked yes)
			(layer "B.Fab")
			(hide yes)
			(effects
				(font
					(size 1.27 0.9652)
					(thickness 0.000001)
				)
				(justify left mirror)
			)
		)
		(duplicate_pad_numbers_are_jumpers no)
		(fp_line
			(start -0.8636 -0.8636)
			(end 0.8636 -0.8636)
			(stroke
				(width 0.1524)
				(type default)
			)
			(layer "B.SilkS")
		)
		(fp_line
			(start -0.8636 0.8636)
			(end -0.8636 -0.8636)
			(stroke
				(width 0.1524)
				(type default)
			)
			(layer "B.SilkS")
		)
		(fp_line
			(start 0.8636 -0.8636)
			(end 0.8636 0.8636)
			(stroke
				(width 0.1524)
				(type default)
			)
			(layer "B.SilkS")
		)
		(fp_line
			(start 0.8636 0.8636)
			(end -0.8636 0.8636)
			(stroke
				(width 0.1524)
				(type default)
			)
			(layer "B.SilkS")
		)
		(fp_poly
			(pts
				(xy 0.635 -0.635) (xy 0.635 0.635) (xy -0.635 0.635) (xy -0.635 -0.635)
			)
			(stroke
				(width 0)
				(type default)
			)
			(fill no)
			(layer "B.CrtYd")
		)
		(pad "1" smd rect
			(at 0 0 180)
			(size 1.27 1.27)
			(layers "B.Cu" "B.Mask" "B.Paste")
			(net "NFP_JTAG_ARM_TDO")
		)
	)
	(footprint ""
		(layer "B.Cu")
		(at 40.894 46.736)
		(property "Reference" "TP5"
			(at 3.302 1.16967 0)
			(unlocked yes)
			(layer "B.SilkS")
			(effects
				(font
					(size 0.7874 0.5842)
					(thickness 0.127)
				)
				(justify left mirror)
			)
		)
		(property "Value" "*"
			(at 0.4826 -0.14732 0)
			(unlocked yes)
			(layer "B.Fab")
			(hide yes)
			(effects
				(font
					(size 1.27 0.9652)
					(thickness 0.000001)
				)
				(justify left mirror)
			)
		)
		(property "Device Type" "TP_SMALL"
			(at 0.4826 -0.14732 0)
			(unlocked yes)
			(layer "B.Fab")
			(hide yes)
			(effects
				(font
					(size 1.27 0.9652)
					(thickness 0.000001)
				)
				(justify left mirror)
			)
		)
		(duplicate_pad_numbers_are_jumpers no)
		(fp_line
			(start -0.8636 -0.8636)
			(end 0.8636 -0.8636)
			(stroke
				(width 0.1524)
				(type default)
			)
			(layer "B.SilkS")
		)
		(fp_line
			(start -0.8636 0.8636)
			(end -0.8636 -0.8636)
			(stroke
				(width 0.1524)
				(type default)
			)
			(layer "B.SilkS")
		)
		(fp_line
			(start 0.8636 -0.8636)
			(end 0.8636 0.8636)
			(stroke
				(width 0.1524)
				(type default)
			)
			(layer "B.SilkS")
		)
		(fp_line
			(start 0.8636 0.8636)
			(end -0.8636 0.8636)
			(stroke
				(width 0.1524)
				(type default)
			)
			(layer "B.SilkS")
		)
		(fp_poly
			(pts
				(xy 0.635 -0.635) (xy 0.635 0.635) (xy -0.635 0.635) (xy -0.635 -0.635)
			)
			(stroke
				(width 0)
				(type default)
			)
			(fill no)
			(layer "B.CrtYd")
		)
		(pad "1" smd rect
			(at 0 0 180)
			(size 1.27 1.27)
			(layers "B.Cu" "B.Mask" "B.Paste")
			(net "NFP_JTAG_ARM_TRST_L")
		)
	)
	(footprint ""
		(layer "B.Cu")
		(at 34.163 26.162 90)
		(property "Reference" "R48"
			(at 0 0 90)
			(layer "B.SilkS")
			(hide yes)
			(effects
				(font
					(size 1.27 1.27)
				)
				(justify mirror)
			)
		)
		(property "Value" "4.75K"
			(at 0.148158 1.3462 0)
			(unlocked yes)
			(layer "B.Fab")
			(hide yes)
			(effects
				(font
					(size 1.27 0.9652)
					(thickness 0.000001)
				)
				(justify left mirror)
			)
		)
		(property "Device Type" "REST4024"
			(at 0.148158 1.3462 0)
			(unlocked yes)
			(layer "B.Fab")
			(hide yes)
			(effects
				(font
					(size 1.27 0.9652)
					(thickness 0.000001)
				)
				(justify left mirror)
			)
		)
		(duplicate_pad_numbers_are_jumpers no)
		(fp_poly
			(pts
				(xy -0.635 1.0668) (xy -0.635 -1.0668) (xy 0.635 -1.0668) (xy 0.635 1.0668)
			)
			(stroke
				(width 0)
				(type default)
			)
			(fill no)
			(layer "B.CrtYd")
		)
		(fp_line
			(start 0.254 -0.508)
			(end -0.254 -0.508)
			(stroke
				(width 0.0254)
				(type default)
			)
			(layer "B.Fab")
		)
		(fp_line
			(start -0.254 -0.508)
			(end -0.254 0.508)
			(stroke
				(width 0.0254)
				(type default)
			)
			(layer "B.Fab")
		)
		(fp_line
			(start 0.254 0.508)
			(end 0.254 -0.508)
			(stroke
				(width 0.0254)
				(type default)
			)
			(layer "B.Fab")
		)
		(fp_line
			(start -0.254 0.508)
			(end 0.254 0.508)
			(stroke
				(width 0.0254)
				(type default)
			)
			(layer "B.Fab")
		)
		(pad "1" smd rect
			(at 0 -0.4191 270)
			(size 0.508 0.5334)
			(layers "B.Cu" "B.Mask" "B.Paste")
			(net "EXT_3.3V")
		)
		(pad "2" smd rect
			(at 0 0.4191 270)
			(size 0.508 0.5334)
			(layers "B.Cu" "B.Mask" "B.Paste")
			(net "HOST_RESET_REQ_L")
		)
		(zone
			(layer "B.Cu")
			(hatch none 0.5)
			(connect_pads
				(clearance 0)
			)
			(min_thickness 0.25)
			(keepout
				(tracks not_allowed)
				(vias allowed)
				(pads allowed)
				(copperpour not_allowed)
				(footprints allowed)
			)
			(placement
				(enabled no)
				(sheetname "")
			)
			(fill
				(thermal_gap 0.5)
				(thermal_bridge_width 0.5)
				(island_removal_mode 0)
			)
			(polygon
				(pts
					(xy 34.1376 26.1874) (xy 34.1884 26.1874) (xy 34.1884 26.1366) (xy 34.1376 26.1366)
				)
			)
		)
	)
	(footprint ""
		(layer "B.Cu")
		(at 56.236997 9.542018)
		(property "Reference" "C30"
			(at 0 0 0)
			(layer "B.SilkS")
			(hide yes)
			(effects
				(font
					(size 1.27 1.27)
				)
				(justify mirror)
			)
		)
		(property "Value" ""
			(at 0 0 0)
			(layer "B.Fab")
			(effects
				(font
					(size 1.27 1.27)
				)
				(justify mirror)
			)
		)
		(duplicate_pad_numbers_are_jumpers no)
		(fp_circle
			(center 0 0)
			(end 0.104648 0)
			(stroke
				(width 0.1016)
				(type default)
			)
			(fill no)
			(layer "B.SilkS")
		)
		(fp_poly
			(pts
				(xy 0.381 -0.889) (xy 0.381 0.889) (xy -0.381 0.889) (xy -0.381 -0.889)
			)
			(stroke
				(width 0)
				(type default)
			)
			(fill no)
			(layer "B.CrtYd")
		)
		(fp_line
			(start -0.508 -1.016)
			(end -0.508 1.016)
			(stroke
				(width 0.0254)
				(type default)
			)
			(layer "B.Fab")
		)
		(fp_line
			(start -0.508 1.016)
			(end 0.508 1.016)
			(stroke
				(width 0.0254)
				(type default)
			)
			(layer "B.Fab")
		)
		(fp_line
			(start 0.254 -1.016)
			(end -0.508 -1.016)
			(stroke
				(width 0.0254)
				(type default)
			)
			(layer "B.Fab")
		)
		(fp_line
			(start 0.508 -1.016)
			(end 0.254 -1.016)
			(stroke
				(width 0.0254)
				(type default)
			)
			(layer "B.Fab")
		)
		(fp_line
			(start 0.508 1.016)
			(end 0.508 -1.016)
			(stroke
				(width 0.0254)
				(type default)
			)
			(layer "B.Fab")
		)
		(pad "1" smd custom
			(at 0 -0.500126 180)
			(size 0.127 0.127)
			(layers "B.Cu" "B.Mask" "B.Paste")
			(net "VDDAH_PCIE0")
			(options
				(clearance outline)
				(anchor circle)
			)
			(primitives
				(gr_poly
					(pts
						(xy -0.1778 0.254) (xy 0.1778 0.254) (xy 0.254 0.1778) (xy 0.254 -0.1778) (xy 0.1778 -0.254) (xy -0.1778 -0.254)
						(xy -0.254 -0.1778) (xy -0.254 0.1778)
					)
					(width 0)
					(fill yes)
				)
			)
		)
		(pad "2" smd custom
			(at 0 0.500126 180)
			(size 0.127 0.127)
			(layers "B.Cu" "B.Mask" "B.Paste")
			(net "GND")
			(options
				(clearance outline)
				(anchor circle)
			)
			(primitives
				(gr_poly
					(pts
						(xy -0.1778 0.254) (xy 0.1778 0.254) (xy 0.254 0.1778) (xy 0.254 -0.1778) (xy 0.1778 -0.254) (xy -0.1778 -0.254)
						(xy -0.254 -0.1778) (xy -0.254 0.1778)
					)
					(width 0)
					(fill yes)
				)
			)
		)
	)
	(footprint ""
		(layer "B.Cu")
		(at 40.259 37.846)
		(property "Reference" "TP34"
			(at -1.143 -0.73533 0)
			(unlocked yes)
			(layer "B.SilkS")
			(effects
				(font
					(size 0.7874 0.5842)
					(thickness 0.127)
				)
				(justify left mirror)
			)
		)
		(property "Value" "*"
			(at 0.4826 -0.14732 0)
			(unlocked yes)
			(layer "B.Fab")
			(hide yes)
			(effects
				(font
					(size 1.27 0.9652)
					(thickness 0.000001)
				)
				(justify left mirror)
			)
		)
		(property "Device Type" "TP_SMALL"
			(at 0.4826 -0.14732 0)
			(unlocked yes)
			(layer "B.Fab")
			(hide yes)
			(effects
				(font
					(size 1.27 0.9652)
					(thickness 0.000001)
				)
				(justify left mirror)
			)
		)
		(duplicate_pad_numbers_are_jumpers no)
		(fp_line
			(start -0.8636 -0.8636)
			(end 0.8636 -0.8636)
			(stroke
				(width 0.1524)
				(type default)
			)
			(layer "B.SilkS")
		)
		(fp_line
			(start -0.8636 0.8636)
			(end -0.8636 -0.8636)
			(stroke
				(width 0.1524)
				(type default)
			)
			(layer "B.SilkS")
		)
		(fp_line
			(start 0.8636 -0.8636)
			(end 0.8636 0.8636)
			(stroke
				(width 0.1524)
				(type default)
			)
			(layer "B.SilkS")
		)
		(fp_line
			(start 0.8636 0.8636)
			(end -0.8636 0.8636)
			(stroke
				(width 0.1524)
				(type default)
			)
			(layer "B.SilkS")
		)
		(fp_poly
			(pts
				(xy 0.635 -0.635) (xy 0.635 0.635) (xy -0.635 0.635) (xy -0.635 -0.635)
			)
			(stroke
				(width 0)
				(type default)
			)
			(fill no)
			(layer "B.CrtYd")
		)
		(pad "1" smd rect
			(at 0 0 180)
			(size 1.27 1.27)
			(layers "B.Cu" "B.Mask" "B.Paste")
			(net "CORE_FB_PH2_THERM_L")
		)
	)
	(footprint ""
		(layer "B.Cu")
		(at 78.650998 2.699004)
		(property "Reference" "V1_A-RAS"
			(at 0 0 0)
			(layer "B.SilkS")
			(hide yes)
			(effects
				(font
					(size 1.27 1.27)
				)
				(justify mirror)
			)
		)
		(property "Value" ""
			(at 0 0 0)
			(layer "B.Fab")
			(effects
				(font
					(size 1.27 1.27)
				)
				(justify mirror)
			)
		)
		(duplicate_pad_numbers_are_jumpers no)
		(pad "1" thru_hole circle
			(at 0 0 180)
			(size 0.4572 0.4572)
			(drill 0.20574)
			(layers "*.Cu" "*.Mask")
			(remove_unused_layers no)
			(net "DDR0_32A_RAS_L")
			(clearance 0.1143)
			(thermal_gap 0.1143)
		)
	)
	(footprint ""
		(layer "B.Cu")
		(at 52.237005 13.54201)
		(property "Reference" "C162"
			(at 0 0 0)
			(layer "B.SilkS")
			(hide yes)
			(effects
				(font
					(size 1.27 1.27)
				)
				(justify mirror)
			)
		)
		(property "Value" ""
			(at 0 0 0)
			(layer "B.Fab")
			(effects
				(font
					(size 1.27 1.27)
				)
				(justify mirror)
			)
		)
		(duplicate_pad_numbers_are_jumpers no)
		(fp_circle
			(center 0 0)
			(end 0.104648 0)
			(stroke
				(width 0.1016)
				(type default)
			)
			(fill no)
			(layer "B.SilkS")
		)
		(fp_poly
			(pts
				(xy 0.381 -0.889) (xy 0.381 0.889) (xy -0.381 0.889) (xy -0.381 -0.889)
			)
			(stroke
				(width 0)
				(type default)
			)
			(fill no)
			(layer "B.CrtYd")
		)
		(fp_line
			(start -0.508 -1.016)
			(end -0.508 1.016)
			(stroke
				(width 0.0254)
				(type default)
			)
			(layer "B.Fab")
		)
		(fp_line
			(start -0.508 1.016)
			(end 0.508 1.016)
			(stroke
				(width 0.0254)
				(type default)
			)
			(layer "B.Fab")
		)
		(fp_line
			(start 0.254 -1.016)
			(end -0.508 -1.016)
			(stroke
				(width 0.0254)
				(type default)
			)
			(layer "B.Fab")
		)
		(fp_line
			(start 0.508 -1.016)
			(end 0.254 -1.016)
			(stroke
				(width 0.0254)
				(type default)
			)
			(layer "B.Fab")
		)
		(fp_line
			(start 0.508 1.016)
			(end 0.508 -1.016)
			(stroke
				(width 0.0254)
				(type default)
			)
			(layer "B.Fab")
		)
		(pad "1" smd custom
			(at 0 -0.500126 180)
			(size 0.127 0.127)
			(layers "B.Cu" "B.Mask" "B.Paste")
			(net "VDD_CORE")
			(options
				(clearance outline)
				(anchor circle)
			)
			(primitives
				(gr_poly
					(pts
						(xy -0.1778 0.254) (xy 0.1778 0.254) (xy 0.254 0.1778) (xy 0.254 -0.1778) (xy 0.1778 -0.254) (xy -0.1778 -0.254)
						(xy -0.254 -0.1778) (xy -0.254 0.1778)
					)
					(width 0)
					(fill yes)
				)
			)
		)
		(pad "2" smd custom
			(at 0 0.500126 180)
			(size 0.127 0.127)
			(layers "B.Cu" "B.Mask" "B.Paste")
			(net "GND")
			(options
				(clearance outline)
				(anchor circle)
			)
			(primitives
				(gr_poly
					(pts
						(xy -0.1778 0.254) (xy 0.1778 0.254) (xy 0.254 0.1778) (xy 0.254 -0.1778) (xy 0.1778 -0.254) (xy -0.1778 -0.254)
						(xy -0.254 -0.1778) (xy -0.254 0.1778)
					)
					(width 0)
					(fill yes)
				)
			)
		)
	)
	(footprint ""
		(layer "B.Cu")
		(at 54.737 30.8356)
		(property "Reference" "C13"
			(at -1.16967 1.2573 270)
			(unlocked yes)
			(layer "B.SilkS")
			(effects
				(font
					(size 0.7874 0.5842)
					(thickness 0.127)
				)
				(justify left mirror)
			)
		)
		(property "Value" "22UF"
			(at 0.148158 1.7526 270)
			(unlocked yes)
			(layer "B.Fab")
			(hide yes)
			(effects
				(font
					(size 1.27 0.9652)
					(thickness 0.000001)
				)
				(justify left mirror)
			)
		)
		(property "Device Type" "CAPC0063"
			(at 0.148158 1.7526 270)
			(unlocked yes)
			(layer "B.Fab")
			(hide yes)
			(effects
				(font
					(size 1.27 0.9652)
					(thickness 0.000001)
				)
				(justify left mirror)
			)
		)
		(duplicate_pad_numbers_are_jumpers no)
		(fp_circle
			(center 0 0)
			(end 0.127 0)
			(stroke
				(width 0.2032)
				(type default)
			)
			(fill no)
			(layer "B.SilkS")
		)
		(fp_poly
			(pts
				(xy -0.7874 -1.6637) (xy 0.7874 -1.6637) (xy 0.7874 1.6637) (xy -0.7874 1.6637)
			)
			(stroke
				(width 0)
				(type default)
			)
			(fill no)
			(layer "B.CrtYd")
		)
		(fp_line
			(start -0.4064 -0.7874)
			(end -0.4064 0.8128)
			(stroke
				(width 0.0254)
				(type default)
			)
			(layer "B.Fab")
		)
		(fp_line
			(start -0.4064 0.8128)
			(end 0.4064 0.8128)
			(stroke
				(width 0.0254)
				(type default)
			)
			(layer "B.Fab")
		)
		(fp_line
			(start 0.4064 -0.7874)
			(end -0.4064 -0.7874)
			(stroke
				(width 0.0254)
				(type default)
			)
			(layer "B.Fab")
		)
		(fp_line
			(start 0.4064 0.8128)
			(end 0.4064 -0.7874)
			(stroke
				(width 0.0254)
				(type default)
			)
			(layer "B.Fab")
		)
		(pad "1" smd rect
			(at 0 -0.8001 180)
			(size 0.8636 0.9652)
			(layers "B.Cu" "B.Mask" "B.Paste")
			(net "VDD_CORE")
		)
		(pad "2" smd rect
			(at 0 0.8001 180)
			(size 0.8636 0.9652)
			(layers "B.Cu" "B.Mask" "B.Paste")
			(net "GND")
		)
		(zone
			(layer "B.Cu")
			(hatch none 0.5)
			(connect_pads
				(clearance 0)
			)
			(min_thickness 0.25)
			(keepout
				(tracks not_allowed)
				(vias allowed)
				(pads allowed)
				(copperpour not_allowed)
				(footprints allowed)
			)
			(placement
				(enabled no)
				(sheetname "")
			)
			(fill
				(thermal_gap 0.5)
				(thermal_bridge_width 0.5)
				(island_removal_mode 0)
			)
			(polygon
				(pts
					(xy 54.8005 30.5816) (xy 54.6735 30.5816) (xy 54.6735 31.0896) (xy 54.8005 31.0896)
				)
			)
		)
	)
	(footprint ""
		(layer "B.Cu")
		(at 56.736996 7.042023 90)
		(property "Reference" "C38"
			(at 0 0 90)
			(layer "B.SilkS")
			(hide yes)
			(effects
				(font
					(size 1.27 1.27)
				)
				(justify mirror)
			)
		)
		(property "Value" ""
			(at 0 0 90)
			(layer "B.Fab")
			(effects
				(font
					(size 1.27 1.27)
				)
				(justify mirror)
			)
		)
		(duplicate_pad_numbers_are_jumpers no)
		(fp_circle
			(center 0 0)
			(end 0 0.104648)
			(stroke
				(width 0.1016)
				(type default)
			)
			(fill no)
			(layer "B.SilkS")
		)
		(fp_poly
			(pts
				(xy 0.381 -0.889) (xy 0.381 0.889) (xy -0.381 0.889) (xy -0.381 -0.889)
			)
			(stroke
				(width 0)
				(type default)
			)
			(fill no)
			(layer "B.CrtYd")
		)
		(fp_line
			(start 0.508 -1.016)
			(end 0.254 -1.016)
			(stroke
				(width 0.0254)
				(type default)
			)
			(layer "B.Fab")
		)
		(fp_line
			(start 0.254 -1.016)
			(end -0.508 -1.016)
			(stroke
				(width 0.0254)
				(type default)
			)
			(layer "B.Fab")
		)
		(fp_line
			(start -0.508 -1.016)
			(end -0.508 1.016)
			(stroke
				(width 0.0254)
				(type default)
			)
			(layer "B.Fab")
		)
		(fp_line
			(start 0.508 1.016)
			(end 0.508 -1.016)
			(stroke
				(width 0.0254)
				(type default)
			)
			(layer "B.Fab")
		)
		(fp_line
			(start -0.508 1.016)
			(end 0.508 1.016)
			(stroke
				(width 0.0254)
				(type default)
			)
			(layer "B.Fab")
		)
		(pad "1" smd custom
			(at 0 -0.500126 270)
			(size 0.127 0.127)
			(layers "B.Cu" "B.Mask" "B.Paste")
			(net "VDDAH_PCIE0")
			(options
				(clearance outline)
				(anchor circle)
			)
			(primitives
				(gr_poly
					(pts
						(xy -0.1778 0.254) (xy 0.1778 0.254) (xy 0.254 0.1778) (xy 0.254 -0.1778) (xy 0.1778 -0.254) (xy -0.1778 -0.254)
						(xy -0.254 -0.1778) (xy -0.254 0.1778)
					)
					(width 0)
					(fill yes)
				)
			)
		)
		(pad "2" smd custom
			(at 0 0.500126 270)
			(size 0.127 0.127)
			(layers "B.Cu" "B.Mask" "B.Paste")
			(net "GND")
			(options
				(clearance outline)
				(anchor circle)
			)
			(primitives
				(gr_poly
					(pts
						(xy -0.1778 0.254) (xy 0.1778 0.254) (xy 0.254 0.1778) (xy 0.254 -0.1778) (xy 0.1778 -0.254) (xy -0.1778 -0.254)
						(xy -0.254 -0.1778) (xy -0.254 0.1778)
					)
					(width 0)
					(fill yes)
				)
			)
		)
	)
	(footprint ""
		(layer "B.Cu")
		(at 44.237021 11.542014 180)
		(property "Reference" "C276"
			(at 0 0 0)
			(layer "B.SilkS")
			(hide yes)
			(effects
				(font
					(size 1.27 1.27)
				)
				(justify mirror)
			)
		)
		(property "Value" ""
			(at 0 0 0)
			(layer "B.Fab")
			(effects
				(font
					(size 1.27 1.27)
				)
				(justify mirror)
			)
		)
		(duplicate_pad_numbers_are_jumpers no)
		(fp_circle
			(center 0 0)
			(end -0.104648 0)
			(stroke
				(width 0.1016)
				(type default)
			)
			(fill no)
			(layer "B.SilkS")
		)
		(fp_poly
			(pts
				(xy 0.381 -0.889) (xy 0.381 0.889) (xy -0.381 0.889) (xy -0.381 -0.889)
			)
			(stroke
				(width 0)
				(type default)
			)
			(fill no)
			(layer "B.CrtYd")
		)
		(fp_line
			(start 0.508 1.016)
			(end 0.508 -1.016)
			(stroke
				(width 0.0254)
				(type default)
			)
			(layer "B.Fab")
		)
		(fp_line
			(start 0.508 -1.016)
			(end 0.254 -1.016)
			(stroke
				(width 0.0254)
				(type default)
			)
			(layer "B.Fab")
		)
		(fp_line
			(start 0.254 -1.016)
			(end -0.508 -1.016)
			(stroke
				(width 0.0254)
				(type default)
			)
			(layer "B.Fab")
		)
		(fp_line
			(start -0.508 1.016)
			(end 0.508 1.016)
			(stroke
				(width 0.0254)
				(type default)
			)
			(layer "B.Fab")
		)
		(fp_line
			(start -0.508 -1.016)
			(end -0.508 1.016)
			(stroke
				(width 0.0254)
				(type default)
			)
			(layer "B.Fab")
		)
		(pad "1" smd custom
			(at 0 -0.500126)
			(size 0.127 0.127)
			(layers "B.Cu" "B.Mask" "B.Paste")
			(net "VDD_3.3V")
			(options
				(clearance outline)
				(anchor circle)
			)
			(primitives
				(gr_poly
					(pts
						(xy -0.1778 0.254) (xy 0.1778 0.254) (xy 0.254 0.1778) (xy 0.254 -0.1778) (xy 0.1778 -0.254) (xy -0.1778 -0.254)
						(xy -0.254 -0.1778) (xy -0.254 0.1778)
					)
					(width 0)
					(fill yes)
				)
			)
		)
		(pad "2" smd custom
			(at 0 0.500126)
			(size 0.127 0.127)
			(layers "B.Cu" "B.Mask" "B.Paste")
			(net "GND")
			(options
				(clearance outline)
				(anchor circle)
			)
			(primitives
				(gr_poly
					(pts
						(xy -0.1778 0.254) (xy 0.1778 0.254) (xy 0.254 0.1778) (xy 0.254 -0.1778) (xy 0.1778 -0.254) (xy -0.1778 -0.254)
						(xy -0.254 -0.1778) (xy -0.254 0.1778)
					)
					(width 0)
					(fill yes)
				)
			)
		)
	)
	(footprint ""
		(layer "B.Cu")
		(at 51.237007 26.541984)
		(property "Reference" "C9"
			(at 0.933323 0.001016 270)
			(unlocked yes)
			(layer "B.SilkS")
			(effects
				(font
					(size 0.7874 0.5842)
					(thickness 0.127)
				)
				(justify mirror)
			)
		)
		(property "Value" ""
			(at 0 0 0)
			(layer "B.Fab")
			(effects
				(font
					(size 1.27 1.27)
				)
				(justify mirror)
			)
		)
		(duplicate_pad_numbers_are_jumpers no)
		(fp_circle
			(center 0 0)
			(end 0.104648 0)
			(stroke
				(width 0.1016)
				(type default)
			)
			(fill no)
			(layer "B.SilkS")
		)
		(fp_poly
			(pts
				(xy 0.381 -0.889) (xy 0.381 0.889) (xy -0.381 0.889) (xy -0.381 -0.889)
			)
			(stroke
				(width 0)
				(type default)
			)
			(fill no)
			(layer "B.CrtYd")
		)
		(fp_line
			(start -0.508 -1.016)
			(end -0.508 1.016)
			(stroke
				(width 0.0254)
				(type default)
			)
			(layer "B.Fab")
		)
		(fp_line
			(start -0.508 1.016)
			(end 0.508 1.016)
			(stroke
				(width 0.0254)
				(type default)
			)
			(layer "B.Fab")
		)
		(fp_line
			(start 0.254 -1.016)
			(end -0.508 -1.016)
			(stroke
				(width 0.0254)
				(type default)
			)
			(layer "B.Fab")
		)
		(fp_line
			(start 0.508 -1.016)
			(end 0.254 -1.016)
			(stroke
				(width 0.0254)
				(type default)
			)
			(layer "B.Fab")
		)
		(fp_line
			(start 0.508 1.016)
			(end 0.508 -1.016)
			(stroke
				(width 0.0254)
				(type default)
			)
			(layer "B.Fab")
		)
		(pad "1" smd custom
			(at 0 -0.500126 180)
			(size 0.127 0.127)
			(layers "B.Cu" "B.Mask" "B.Paste")
			(net "VDD_CORE")
			(options
				(clearance outline)
				(anchor circle)
			)
			(primitives
				(gr_poly
					(pts
						(xy -0.1778 0.254) (xy 0.1778 0.254) (xy 0.254 0.1778) (xy 0.254 -0.1778) (xy 0.1778 -0.254) (xy -0.1778 -0.254)
						(xy -0.254 -0.1778) (xy -0.254 0.1778)
					)
					(width 0)
					(fill yes)
				)
			)
		)
		(pad "2" smd custom
			(at 0 0.500126 180)
			(size 0.127 0.127)
			(layers "B.Cu" "B.Mask" "B.Paste")
			(net "GND")
			(options
				(clearance outline)
				(anchor circle)
			)
			(primitives
				(gr_poly
					(pts
						(xy -0.1778 0.254) (xy 0.1778 0.254) (xy 0.254 0.1778) (xy 0.254 -0.1778) (xy 0.1778 -0.254) (xy -0.1778 -0.254)
						(xy -0.254 -0.1778) (xy -0.254 0.1778)
					)
					(width 0)
					(fill yes)
				)
			)
		)
	)
	(footprint ""
		(layer "B.Cu")
		(at 84.250987 19.055994)
		(property "Reference" "V2_A-A08"
			(at 0 0 0)
			(layer "B.SilkS")
			(hide yes)
			(effects
				(font
					(size 1.27 1.27)
				)
				(justify mirror)
			)
		)
		(property "Value" ""
			(at 0 0 0)
			(layer "B.Fab")
			(effects
				(font
					(size 1.27 1.27)
				)
				(justify mirror)
			)
		)
		(duplicate_pad_numbers_are_jumpers no)
		(pad "1" thru_hole circle
			(at 0 0 180)
			(size 0.4572 0.4572)
			(drill 0.20574)
			(layers "*.Cu" "*.Mask")
			(remove_unused_layers no)
			(net "DDR0_32A_A8")
			(clearance 0.1143)
			(thermal_gap 0.1143)
		)
	)
	(footprint ""
		(layer "B.Cu")
		(at 28.321 32.639)
		(property "Reference" "R176"
			(at -0.15367 4.826 270)
			(unlocked yes)
			(layer "B.SilkS")
			(effects
				(font
					(size 0.7874 0.5842)
					(thickness 0.127)
				)
				(justify left mirror)
			)
		)
		(property "Value" "0"
			(at 0.148158 1.3462 270)
			(unlocked yes)
			(layer "B.Fab")
			(hide yes)
			(effects
				(font
					(size 1.27 0.9652)
					(thickness 0.000001)
				)
				(justify left mirror)
			)
		)
		(property "Device Type" "REST1111"
			(at 0.148158 1.3462 270)
			(unlocked yes)
			(layer "B.Fab")
			(hide yes)
			(effects
				(font
					(size 1.27 0.9652)
					(thickness 0.000001)
				)
				(justify left mirror)
			)
		)
		(duplicate_pad_numbers_are_jumpers no)
		(fp_poly
			(pts
				(xy -0.635 1.0668) (xy -0.635 -1.0668) (xy 0.635 -1.0668) (xy 0.635 1.0668)
			)
			(stroke
				(width 0)
				(type default)
			)
			(fill no)
			(layer "B.CrtYd")
		)
		(fp_line
			(start -0.254 -0.508)
			(end -0.254 0.508)
			(stroke
				(width 0.0254)
				(type default)
			)
			(layer "B.Fab")
		)
		(fp_line
			(start -0.254 0.508)
			(end 0.254 0.508)
			(stroke
				(width 0.0254)
				(type default)
			)
			(layer "B.Fab")
		)
		(fp_line
			(start 0.254 -0.508)
			(end -0.254 -0.508)
			(stroke
				(width 0.0254)
				(type default)
			)
			(layer "B.Fab")
		)
		(fp_line
			(start 0.254 0.508)
			(end 0.254 -0.508)
			(stroke
				(width 0.0254)
				(type default)
			)
			(layer "B.Fab")
		)
		(pad "1" smd rect
			(at 0 -0.4191 180)
			(size 0.508 0.5334)
			(layers "B.Cu" "B.Mask" "B.Paste")
			(net "NFP_CORE_VID1")
		)
		(pad "2" smd rect
			(at 0 0.4191 180)
			(size 0.508 0.5334)
			(layers "B.Cu" "B.Mask" "B.Paste")
			(net "_NFP_CORE_VID1")
		)
		(zone
			(layer "B.Cu")
			(hatch none 0.5)
			(connect_pads
				(clearance 0)
			)
			(min_thickness 0.25)
			(keepout
				(tracks not_allowed)
				(vias allowed)
				(pads allowed)
				(copperpour not_allowed)
				(footprints allowed)
			)
			(placement
				(enabled no)
				(sheetname "")
			)
			(fill
				(thermal_gap 0.5)
				(thermal_bridge_width 0.5)
				(island_removal_mode 0)
			)
			(polygon
				(pts
					(xy 28.2956 32.6136) (xy 28.2956 32.6644) (xy 28.3464 32.6644) (xy 28.3464 32.6136)
				)
			)
		)
	)
	(footprint ""
		(layer "B.Cu")
		(at 42.237025 7.542022 180)
		(property "Reference" "C270"
			(at -0.408305 2.843022 270)
			(unlocked yes)
			(layer "B.SilkS")
			(effects
				(font
					(size 0.7874 0.5842)
					(thickness 0.127)
				)
				(justify mirror)
			)
		)
		(property "Value" ""
			(at 0 0 0)
			(layer "B.Fab")
			(effects
				(font
					(size 1.27 1.27)
				)
				(justify mirror)
			)
		)
		(duplicate_pad_numbers_are_jumpers no)
		(fp_circle
			(center 0 0)
			(end -0.104648 0)
			(stroke
				(width 0.1016)
				(type default)
			)
			(fill no)
			(layer "B.SilkS")
		)
		(fp_poly
			(pts
				(xy 0.381 -0.889) (xy 0.381 0.889) (xy -0.381 0.889) (xy -0.381 -0.889)
			)
			(stroke
				(width 0)
				(type default)
			)
			(fill no)
			(layer "B.CrtYd")
		)
		(fp_line
			(start 0.508 1.016)
			(end 0.508 -1.016)
			(stroke
				(width 0.0254)
				(type default)
			)
			(layer "B.Fab")
		)
		(fp_line
			(start 0.508 -1.016)
			(end 0.254 -1.016)
			(stroke
				(width 0.0254)
				(type default)
			)
			(layer "B.Fab")
		)
		(fp_line
			(start 0.254 -1.016)
			(end -0.508 -1.016)
			(stroke
				(width 0.0254)
				(type default)
			)
			(layer "B.Fab")
		)
		(fp_line
			(start -0.508 1.016)
			(end 0.508 1.016)
			(stroke
				(width 0.0254)
				(type default)
			)
			(layer "B.Fab")
		)
		(fp_line
			(start -0.508 -1.016)
			(end -0.508 1.016)
			(stroke
				(width 0.0254)
				(type default)
			)
			(layer "B.Fab")
		)
		(pad "1" smd custom
			(at 0 -0.500126)
			(size 0.127 0.127)
			(layers "B.Cu" "B.Mask" "B.Paste")
			(net "VDD_1.2V")
			(options
				(clearance outline)
				(anchor circle)
			)
			(primitives
				(gr_poly
					(pts
						(xy -0.1778 0.254) (xy 0.1778 0.254) (xy 0.254 0.1778) (xy 0.254 -0.1778) (xy 0.1778 -0.254) (xy -0.1778 -0.254)
						(xy -0.254 -0.1778) (xy -0.254 0.1778)
					)
					(width 0)
					(fill yes)
				)
			)
		)
		(pad "2" smd custom
			(at 0 0.500126)
			(size 0.127 0.127)
			(layers "B.Cu" "B.Mask" "B.Paste")
			(net "GND")
			(options
				(clearance outline)
				(anchor circle)
			)
			(primitives
				(gr_poly
					(pts
						(xy -0.1778 0.254) (xy 0.1778 0.254) (xy 0.254 0.1778) (xy 0.254 -0.1778) (xy 0.1778 -0.254) (xy -0.1778 -0.254)
						(xy -0.254 -0.1778) (xy -0.254 0.1778)
					)
					(width 0)
					(fill yes)
				)
			)
		)
	)
	(footprint ""
		(layer "B.Cu")
		(at 37.973 18.415 -90)
		(property "Reference" "R201"
			(at 0 0 90)
			(layer "B.SilkS")
			(hide yes)
			(effects
				(font
					(size 1.27 1.27)
				)
				(justify mirror)
			)
		)
		(property "Value" "39.0"
			(at 0.148158 1.3462 180)
			(unlocked yes)
			(layer "B.Fab")
			(hide yes)
			(effects
				(font
					(size 1.27 0.9652)
					(thickness 0.000001)
				)
				(justify left mirror)
			)
		)
		(property "Device Type" "REST0108"
			(at 0.148158 1.3462 180)
			(unlocked yes)
			(layer "B.Fab")
			(hide yes)
			(effects
				(font
					(size 1.27 0.9652)
					(thickness 0.000001)
				)
				(justify left mirror)
			)
		)
		(duplicate_pad_numbers_are_jumpers no)
		(fp_poly
			(pts
				(xy -0.635 1.0668) (xy -0.635 -1.0668) (xy 0.635 -1.0668) (xy 0.635 1.0668)
			)
			(stroke
				(width 0)
				(type default)
			)
			(fill no)
			(layer "B.CrtYd")
		)
		(fp_line
			(start -0.254 0.508)
			(end 0.254 0.508)
			(stroke
				(width 0.0254)
				(type default)
			)
			(layer "B.Fab")
		)
		(fp_line
			(start 0.254 0.508)
			(end 0.254 -0.508)
			(stroke
				(width 0.0254)
				(type default)
			)
			(layer "B.Fab")
		)
		(fp_line
			(start -0.254 -0.508)
			(end -0.254 0.508)
			(stroke
				(width 0.0254)
				(type default)
			)
			(layer "B.Fab")
		)
		(fp_line
			(start 0.254 -0.508)
			(end -0.254 -0.508)
			(stroke
				(width 0.0254)
				(type default)
			)
			(layer "B.Fab")
		)
		(pad "1" smd rect
			(at 0 -0.4191 90)
			(size 0.508 0.5334)
			(layers "B.Cu" "B.Mask" "B.Paste")
			(net "_NFP_ARM_SPI_FLASH_MOSI")
		)
		(pad "2" smd rect
			(at 0 0.4191 90)
			(size 0.508 0.5334)
			(layers "B.Cu" "B.Mask" "B.Paste")
			(net "NFP_ARM_SPI_FLASH_MOSI")
		)
		(zone
			(layer "B.Cu")
			(hatch none 0.5)
			(connect_pads
				(clearance 0)
			)
			(min_thickness 0.25)
			(keepout
				(tracks not_allowed)
				(vias allowed)
				(pads allowed)
				(copperpour not_allowed)
				(footprints allowed)
			)
			(placement
				(enabled no)
				(sheetname "")
			)
			(fill
				(thermal_gap 0.5)
				(thermal_bridge_width 0.5)
				(island_removal_mode 0)
			)
			(polygon
				(pts
					(xy 37.9984 18.3896) (xy 37.9476 18.3896) (xy 37.9476 18.4404) (xy 37.9984 18.4404)
				)
			)
		)
	)
	(footprint ""
		(layer "B.Cu")
		(at 44.237021 9.542018 180)
		(property "Reference" "C277"
			(at 0 0 0)
			(layer "B.SilkS")
			(hide yes)
			(effects
				(font
					(size 1.27 1.27)
				)
				(justify mirror)
			)
		)
		(property "Value" ""
			(at 0 0 0)
			(layer "B.Fab")
			(effects
				(font
					(size 1.27 1.27)
				)
				(justify mirror)
			)
		)
		(duplicate_pad_numbers_are_jumpers no)
		(fp_circle
			(center 0 0)
			(end -0.104648 0)
			(stroke
				(width 0.1016)
				(type default)
			)
			(fill no)
			(layer "B.SilkS")
		)
		(fp_poly
			(pts
				(xy 0.381 -0.889) (xy 0.381 0.889) (xy -0.381 0.889) (xy -0.381 -0.889)
			)
			(stroke
				(width 0)
				(type default)
			)
			(fill no)
			(layer "B.CrtYd")
		)
		(fp_line
			(start 0.508 1.016)
			(end 0.508 -1.016)
			(stroke
				(width 0.0254)
				(type default)
			)
			(layer "B.Fab")
		)
		(fp_line
			(start 0.508 -1.016)
			(end 0.254 -1.016)
			(stroke
				(width 0.0254)
				(type default)
			)
			(layer "B.Fab")
		)
		(fp_line
			(start 0.254 -1.016)
			(end -0.508 -1.016)
			(stroke
				(width 0.0254)
				(type default)
			)
			(layer "B.Fab")
		)
		(fp_line
			(start -0.508 1.016)
			(end 0.508 1.016)
			(stroke
				(width 0.0254)
				(type default)
			)
			(layer "B.Fab")
		)
		(fp_line
			(start -0.508 -1.016)
			(end -0.508 1.016)
			(stroke
				(width 0.0254)
				(type default)
			)
			(layer "B.Fab")
		)
		(pad "1" smd custom
			(at 0 -0.500126)
			(size 0.127 0.127)
			(layers "B.Cu" "B.Mask" "B.Paste")
			(net "VDD_3.3V")
			(options
				(clearance outline)
				(anchor circle)
			)
			(primitives
				(gr_poly
					(pts
						(xy -0.1778 0.254) (xy 0.1778 0.254) (xy 0.254 0.1778) (xy 0.254 -0.1778) (xy 0.1778 -0.254) (xy -0.1778 -0.254)
						(xy -0.254 -0.1778) (xy -0.254 0.1778)
					)
					(width 0)
					(fill yes)
				)
			)
		)
		(pad "2" smd custom
			(at 0 0.500126)
			(size 0.127 0.127)
			(layers "B.Cu" "B.Mask" "B.Paste")
			(net "GND")
			(options
				(clearance outline)
				(anchor circle)
			)
			(primitives
				(gr_poly
					(pts
						(xy -0.1778 0.254) (xy 0.1778 0.254) (xy 0.254 0.1778) (xy 0.254 -0.1778) (xy 0.1778 -0.254) (xy -0.1778 -0.254)
						(xy -0.254 -0.1778) (xy -0.254 0.1778)
					)
					(width 0)
					(fill yes)
				)
			)
		)
	)
	(footprint ""
		(layer "B.Cu")
		(at 24.638 32.639 180)
		(property "Reference" "C123"
			(at -0.22733 -4.953 270)
			(unlocked yes)
			(layer "B.SilkS")
			(effects
				(font
					(size 0.7874 0.5842)
					(thickness 0.127)
				)
				(justify left mirror)
			)
		)
		(property "Value" "0.1UF"
			(at 0.091846 0.2921 90)
			(unlocked yes)
			(layer "B.Fab")
			(hide yes)
			(effects
				(font
					(size 0.7874 0.5842)
					(thickness 0.2032)
				)
				(justify left mirror)
			)
		)
		(property "Device Type" "CAPC0073"
			(at 0.091846 0.2921 90)
			(unlocked yes)
			(layer "B.Fab")
			(hide yes)
			(effects
				(font
					(size 0.7874 0.5842)
					(thickness 0.2032)
				)
				(justify left mirror)
			)
		)
		(duplicate_pad_numbers_are_jumpers no)
		(fp_poly
			(pts
				(xy -0.635 1.0668) (xy -0.635 -1.0668) (xy 0.635 -1.0668) (xy 0.635 1.0668)
			)
			(stroke
				(width 0)
				(type default)
			)
			(fill no)
			(layer "B.CrtYd")
		)
		(fp_line
			(start 0.254 0.508)
			(end 0.254 -0.508)
			(stroke
				(width 0.0254)
				(type default)
			)
			(layer "B.Fab")
		)
		(fp_line
			(start 0.254 -0.508)
			(end -0.254 -0.508)
			(stroke
				(width 0.0254)
				(type default)
			)
			(layer "B.Fab")
		)
		(fp_line
			(start -0.254 0.508)
			(end 0.254 0.508)
			(stroke
				(width 0.0254)
				(type default)
			)
			(layer "B.Fab")
		)
		(fp_line
			(start -0.254 -0.508)
			(end -0.254 0.508)
			(stroke
				(width 0.0254)
				(type default)
			)
			(layer "B.Fab")
		)
		(pad "1" smd rect
			(at 0 -0.4191)
			(size 0.508 0.5334)
			(layers "B.Cu" "B.Mask" "B.Paste")
			(net "EXT_3.3V")
		)
		(pad "2" smd rect
			(at 0 0.4191)
			(size 0.508 0.5334)
			(layers "B.Cu" "B.Mask" "B.Paste")
			(net "GND")
		)
		(zone
			(layer "B.Cu")
			(hatch none 0.5)
			(connect_pads
				(clearance 0)
			)
			(min_thickness 0.25)
			(keepout
				(tracks not_allowed)
				(vias allowed)
				(pads allowed)
				(copperpour not_allowed)
				(footprints allowed)
			)
			(placement
				(enabled no)
				(sheetname "")
			)
			(fill
				(thermal_gap 0.5)
				(thermal_bridge_width 0.5)
				(island_removal_mode 0)
			)
			(polygon
				(pts
					(xy 24.6634 32.6644) (xy 24.6634 32.6136) (xy 24.6126 32.6136) (xy 24.6126 32.6644)
				)
			)
		)
	)
	(footprint ""
		(layer "B.Cu")
		(at 81.850992 13.456006)
		(property "Reference" "V2_A-A03"
			(at 0 0 0)
			(layer "B.SilkS")
			(hide yes)
			(effects
				(font
					(size 1.27 1.27)
				)
				(justify mirror)
			)
		)
		(property "Value" ""
			(at 0 0 0)
			(layer "B.Fab")
			(effects
				(font
					(size 1.27 1.27)
				)
				(justify mirror)
			)
		)
		(duplicate_pad_numbers_are_jumpers no)
		(pad "1" thru_hole circle
			(at 0 0 180)
			(size 0.4572 0.4572)
			(drill 0.20574)
			(layers "*.Cu" "*.Mask")
			(remove_unused_layers no)
			(net "DDR0_32A_A3")
			(clearance 0.1143)
			(thermal_gap 0.1143)
		)
	)
	(footprint ""
		(layer "B.Cu")
		(at 76.251003 25.013006)
		(property "Reference" "V_A-CB6"
			(at 0 0 0)
			(layer "B.SilkS")
			(hide yes)
			(effects
				(font
					(size 1.27 1.27)
				)
				(justify mirror)
			)
		)
		(property "Value" ""
			(at 0 0 0)
			(layer "B.Fab")
			(effects
				(font
					(size 1.27 1.27)
				)
				(justify mirror)
			)
		)
		(duplicate_pad_numbers_are_jumpers no)
		(pad "1" thru_hole circle
			(at 0 0 180)
			(size 0.4572 0.4572)
			(drill 0.20574)
			(layers "*.Cu" "*.Mask")
			(remove_unused_layers no)
			(net "DDR0_32A_CB6")
			(clearance 0.1143)
			(thermal_gap 0.1143)
		)
	)
	(footprint ""
		(layer "B.Cu")
		(at 35.179 48.641 90)
		(property "Reference" "TP57"
			(at 0 0 90)
			(layer "B.SilkS")
			(hide yes)
			(effects
				(font
					(size 1.27 1.27)
				)
				(justify mirror)
			)
		)
		(property "Value" "*"
			(at 0.4826 -0.14732 90)
			(unlocked yes)
			(layer "B.Fab")
			(hide yes)
			(effects
				(font
					(size 1.27 0.9652)
					(thickness 0.000001)
				)
				(justify left mirror)
			)
		)
		(property "Device Type" "TP_SMALL"
			(at 0.4826 -0.14732 90)
			(unlocked yes)
			(layer "B.Fab")
			(hide yes)
			(effects
				(font
					(size 1.27 0.9652)
					(thickness 0.000001)
				)
				(justify left mirror)
			)
		)
		(duplicate_pad_numbers_are_jumpers no)
		(fp_line
			(start 0.8636 -0.8636)
			(end 0.8636 0.8636)
			(stroke
				(width 0.1524)
				(type default)
			)
			(layer "B.SilkS")
		)
		(fp_line
			(start -0.8636 -0.8636)
			(end 0.8636 -0.8636)
			(stroke
				(width 0.1524)
				(type default)
			)
			(layer "B.SilkS")
		)
		(fp_line
			(start 0.8636 0.8636)
			(end -0.8636 0.8636)
			(stroke
				(width 0.1524)
				(type default)
			)
			(layer "B.SilkS")
		)
		(fp_line
			(start -0.8636 0.8636)
			(end -0.8636 -0.8636)
			(stroke
				(width 0.1524)
				(type default)
			)
			(layer "B.SilkS")
		)
		(fp_poly
			(pts
				(xy 0.635 -0.635) (xy 0.635 0.635) (xy -0.635 0.635) (xy -0.635 -0.635)
			)
			(stroke
				(width 0)
				(type default)
			)
			(fill no)
			(layer "B.CrtYd")
		)
		(pad "1" smd rect
			(at 0 0 270)
			(size 1.27 1.27)
			(layers "B.Cu" "B.Mask" "B.Paste")
			(net "CNTRL_SPI_SCK")
		)
	)
	(footprint ""
		(layer "B.Cu")
		(at 56.736996 8.042021 90)
		(property "Reference" "C91"
			(at 0 0 90)
			(layer "B.SilkS")
			(hide yes)
			(effects
				(font
					(size 1.27 1.27)
				)
				(justify mirror)
			)
		)
		(property "Value" ""
			(at 0 0 90)
			(layer "B.Fab")
			(effects
				(font
					(size 1.27 1.27)
				)
				(justify mirror)
			)
		)
		(duplicate_pad_numbers_are_jumpers no)
		(fp_circle
			(center 0 0)
			(end 0 0.104648)
			(stroke
				(width 0.1016)
				(type default)
			)
			(fill no)
			(layer "B.SilkS")
		)
		(fp_poly
			(pts
				(xy 0.381 -0.889) (xy 0.381 0.889) (xy -0.381 0.889) (xy -0.381 -0.889)
			)
			(stroke
				(width 0)
				(type default)
			)
			(fill no)
			(layer "B.CrtYd")
		)
		(fp_line
			(start 0.508 -1.016)
			(end 0.254 -1.016)
			(stroke
				(width 0.0254)
				(type default)
			)
			(layer "B.Fab")
		)
		(fp_line
			(start 0.254 -1.016)
			(end -0.508 -1.016)
			(stroke
				(width 0.0254)
				(type default)
			)
			(layer "B.Fab")
		)
		(fp_line
			(start -0.508 -1.016)
			(end -0.508 1.016)
			(stroke
				(width 0.0254)
				(type default)
			)
			(layer "B.Fab")
		)
		(fp_line
			(start 0.508 1.016)
			(end 0.508 -1.016)
			(stroke
				(width 0.0254)
				(type default)
			)
			(layer "B.Fab")
		)
		(fp_line
			(start -0.508 1.016)
			(end 0.508 1.016)
			(stroke
				(width 0.0254)
				(type default)
			)
			(layer "B.Fab")
		)
		(pad "1" smd custom
			(at 0 -0.500126 270)
			(size 0.127 0.127)
			(layers "B.Cu" "B.Mask" "B.Paste")
			(net "VDDAH_PCIE0")
			(options
				(clearance outline)
				(anchor circle)
			)
			(primitives
				(gr_poly
					(pts
						(xy -0.1778 0.254) (xy 0.1778 0.254) (xy 0.254 0.1778) (xy 0.254 -0.1778) (xy 0.1778 -0.254) (xy -0.1778 -0.254)
						(xy -0.254 -0.1778) (xy -0.254 0.1778)
					)
					(width 0)
					(fill yes)
				)
			)
		)
		(pad "2" smd custom
			(at 0 0.500126 270)
			(size 0.127 0.127)
			(layers "B.Cu" "B.Mask" "B.Paste")
			(net "GND")
			(options
				(clearance outline)
				(anchor circle)
			)
			(primitives
				(gr_poly
					(pts
						(xy -0.1778 0.254) (xy 0.1778 0.254) (xy 0.254 0.1778) (xy 0.254 -0.1778) (xy 0.1778 -0.254) (xy -0.1778 -0.254)
						(xy -0.254 -0.1778) (xy -0.254 0.1778)
					)
					(width 0)
					(fill yes)
				)
			)
		)
	)
	(footprint ""
		(layer "B.Cu")
		(at 42.237025 25.541986)
		(property "Reference" "R199"
			(at 0 0 0)
			(layer "B.SilkS")
			(hide yes)
			(effects
				(font
					(size 1.27 1.27)
				)
				(justify mirror)
			)
		)
		(property "Value" ""
			(at 0 0 0)
			(layer "B.Fab")
			(effects
				(font
					(size 1.27 1.27)
				)
				(justify mirror)
			)
		)
		(duplicate_pad_numbers_are_jumpers no)
		(fp_circle
			(center 0 0)
			(end 0.104648 0)
			(stroke
				(width 0.1016)
				(type default)
			)
			(fill no)
			(layer "B.SilkS")
		)
		(fp_poly
			(pts
				(xy 0.381 -0.889) (xy 0.381 0.889) (xy -0.381 0.889) (xy -0.381 -0.889)
			)
			(stroke
				(width 0)
				(type default)
			)
			(fill no)
			(layer "B.CrtYd")
		)
		(fp_line
			(start -0.508 -1.016)
			(end -0.508 1.016)
			(stroke
				(width 0.0254)
				(type default)
			)
			(layer "B.Fab")
		)
		(fp_line
			(start -0.508 1.016)
			(end 0.508 1.016)
			(stroke
				(width 0.0254)
				(type default)
			)
			(layer "B.Fab")
		)
		(fp_line
			(start 0.254 -1.016)
			(end -0.508 -1.016)
			(stroke
				(width 0.0254)
				(type default)
			)
			(layer "B.Fab")
		)
		(fp_line
			(start 0.508 -1.016)
			(end 0.254 -1.016)
			(stroke
				(width 0.0254)
				(type default)
			)
			(layer "B.Fab")
		)
		(fp_line
			(start 0.508 1.016)
			(end 0.508 -1.016)
			(stroke
				(width 0.0254)
				(type default)
			)
			(layer "B.Fab")
		)
		(pad "1" smd custom
			(at 0 -0.500126 180)
			(size 0.127 0.127)
			(layers "B.Cu" "B.Mask" "B.Paste")
			(net "_NFP_SPI2_SCK")
			(options
				(clearance outline)
				(anchor circle)
			)
			(primitives
				(gr_poly
					(pts
						(xy -0.1778 0.254) (xy 0.1778 0.254) (xy 0.254 0.1778) (xy 0.254 -0.1778) (xy 0.1778 -0.254) (xy -0.1778 -0.254)
						(xy -0.254 -0.1778) (xy -0.254 0.1778)
					)
					(width 0)
					(fill yes)
				)
			)
		)
		(pad "2" smd custom
			(at 0 0.500126 180)
			(size 0.127 0.127)
			(layers "B.Cu" "B.Mask" "B.Paste")
			(net "NFP_SPI2_SCK")
			(options
				(clearance outline)
				(anchor circle)
			)
			(primitives
				(gr_poly
					(pts
						(xy -0.1778 0.254) (xy 0.1778 0.254) (xy 0.254 0.1778) (xy 0.254 -0.1778) (xy 0.1778 -0.254) (xy -0.1778 -0.254)
						(xy -0.254 -0.1778) (xy -0.254 0.1778)
					)
					(width 0)
					(fill yes)
				)
			)
		)
	)
	(footprint ""
		(layer "B.Cu")
		(at 33.655 22.733 -90)
		(property "Reference" "R398"
			(at 0 0 90)
			(layer "B.SilkS")
			(hide yes)
			(effects
				(font
					(size 1.27 1.27)
				)
				(justify mirror)
			)
		)
		(property "Value" "4.75K"
			(at 0.148158 1.3462 180)
			(unlocked yes)
			(layer "B.Fab")
			(hide yes)
			(effects
				(font
					(size 1.27 0.9652)
					(thickness 0.000001)
				)
				(justify left mirror)
			)
		)
		(property "Device Type" "REST4024"
			(at 0.148158 1.3462 180)
			(unlocked yes)
			(layer "B.Fab")
			(hide yes)
			(effects
				(font
					(size 1.27 0.9652)
					(thickness 0.000001)
				)
				(justify left mirror)
			)
		)
		(duplicate_pad_numbers_are_jumpers no)
		(fp_poly
			(pts
				(xy -0.635 1.0668) (xy -0.635 -1.0668) (xy 0.635 -1.0668) (xy 0.635 1.0668)
			)
			(stroke
				(width 0)
				(type default)
			)
			(fill no)
			(layer "B.CrtYd")
		)
		(fp_line
			(start -0.254 0.508)
			(end 0.254 0.508)
			(stroke
				(width 0.0254)
				(type default)
			)
			(layer "B.Fab")
		)
		(fp_line
			(start 0.254 0.508)
			(end 0.254 -0.508)
			(stroke
				(width 0.0254)
				(type default)
			)
			(layer "B.Fab")
		)
		(fp_line
			(start -0.254 -0.508)
			(end -0.254 0.508)
			(stroke
				(width 0.0254)
				(type default)
			)
			(layer "B.Fab")
		)
		(fp_line
			(start 0.254 -0.508)
			(end -0.254 -0.508)
			(stroke
				(width 0.0254)
				(type default)
			)
			(layer "B.Fab")
		)
		(pad "1" smd rect
			(at 0 -0.4191 90)
			(size 0.508 0.5334)
			(layers "B.Cu" "B.Mask" "B.Paste")
			(net "EXT_3.3V")
		)
		(pad "2" smd rect
			(at 0 0.4191 90)
			(size 0.508 0.5334)
			(layers "B.Cu" "B.Mask" "B.Paste")
			(net "CPLD_SMBUS_SDA")
		)
		(zone
			(layer "B.Cu")
			(hatch none 0.5)
			(connect_pads
				(clearance 0)
			)
			(min_thickness 0.25)
			(keepout
				(tracks not_allowed)
				(vias allowed)
				(pads allowed)
				(copperpour not_allowed)
				(footprints allowed)
			)
			(placement
				(enabled no)
				(sheetname "")
			)
			(fill
				(thermal_gap 0.5)
				(thermal_bridge_width 0.5)
				(island_removal_mode 0)
			)
			(polygon
				(pts
					(xy 33.6804 22.7076) (xy 33.6296 22.7076) (xy 33.6296 22.7584) (xy 33.6804 22.7584)
				)
			)
		)
	)
	(footprint ""
		(layer "B.Cu")
		(at 5.207 6.35)
		(property "Reference" "TP26"
			(at 1.24333 -0.762 270)
			(unlocked yes)
			(layer "B.SilkS")
			(effects
				(font
					(size 0.7874 0.5842)
					(thickness 0.127)
				)
				(justify left mirror)
			)
		)
		(property "Value" "*"
			(at 0.4826 -0.14732 0)
			(unlocked yes)
			(layer "B.Fab")
			(hide yes)
			(effects
				(font
					(size 1.27 0.9652)
					(thickness 0.000001)
				)
				(justify left mirror)
			)
		)
		(property "Device Type" "TP_SMALL"
			(at 0.4826 -0.14732 0)
			(unlocked yes)
			(layer "B.Fab")
			(hide yes)
			(effects
				(font
					(size 1.27 0.9652)
					(thickness 0.000001)
				)
				(justify left mirror)
			)
		)
		(duplicate_pad_numbers_are_jumpers no)
		(fp_line
			(start -0.8636 -0.8636)
			(end 0.8636 -0.8636)
			(stroke
				(width 0.1524)
				(type default)
			)
			(layer "B.SilkS")
		)
		(fp_line
			(start -0.8636 0.8636)
			(end -0.8636 -0.8636)
			(stroke
				(width 0.1524)
				(type default)
			)
			(layer "B.SilkS")
		)
		(fp_line
			(start 0.8636 -0.8636)
			(end 0.8636 0.8636)
			(stroke
				(width 0.1524)
				(type default)
			)
			(layer "B.SilkS")
		)
		(fp_line
			(start 0.8636 0.8636)
			(end -0.8636 0.8636)
			(stroke
				(width 0.1524)
				(type default)
			)
			(layer "B.SilkS")
		)
		(fp_poly
			(pts
				(xy 0.635 -0.635) (xy 0.635 0.635) (xy -0.635 0.635) (xy -0.635 -0.635)
			)
			(stroke
				(width 0)
				(type default)
			)
			(fill no)
			(layer "B.CrtYd")
		)
		(pad "1" smd rect
			(at 0 0 180)
			(size 1.27 1.27)
			(layers "B.Cu" "B.Mask" "B.Paste")
			(net "PGRM_JTAG_TRST_L")
		)
	)
	(footprint ""
		(layer "B.Cu")
		(at 59.236991 7.542022 180)
		(property "Reference" "C89"
			(at -0.045339 2.462022 270)
			(unlocked yes)
			(layer "B.SilkS")
			(effects
				(font
					(size 0.7874 0.5842)
					(thickness 0.127)
				)
				(justify mirror)
			)
		)
		(property "Value" ""
			(at 0 0 0)
			(layer "B.Fab")
			(effects
				(font
					(size 1.27 1.27)
				)
				(justify mirror)
			)
		)
		(duplicate_pad_numbers_are_jumpers no)
		(fp_circle
			(center 0 0)
			(end -0.104648 0)
			(stroke
				(width 0.1016)
				(type default)
			)
			(fill no)
			(layer "B.SilkS")
		)
		(fp_poly
			(pts
				(xy 0.381 -0.889) (xy 0.381 0.889) (xy -0.381 0.889) (xy -0.381 -0.889)
			)
			(stroke
				(width 0)
				(type default)
			)
			(fill no)
			(layer "B.CrtYd")
		)
		(fp_line
			(start 0.508 1.016)
			(end 0.508 -1.016)
			(stroke
				(width 0.0254)
				(type default)
			)
			(layer "B.Fab")
		)
		(fp_line
			(start 0.508 -1.016)
			(end 0.254 -1.016)
			(stroke
				(width 0.0254)
				(type default)
			)
			(layer "B.Fab")
		)
		(fp_line
			(start 0.254 -1.016)
			(end -0.508 -1.016)
			(stroke
				(width 0.0254)
				(type default)
			)
			(layer "B.Fab")
		)
		(fp_line
			(start -0.508 1.016)
			(end 0.508 1.016)
			(stroke
				(width 0.0254)
				(type default)
			)
			(layer "B.Fab")
		)
		(fp_line
			(start -0.508 -1.016)
			(end -0.508 1.016)
			(stroke
				(width 0.0254)
				(type default)
			)
			(layer "B.Fab")
		)
		(pad "1" smd custom
			(at 0 -0.500126)
			(size 0.127 0.127)
			(layers "B.Cu" "B.Mask" "B.Paste")
			(net "VDDA_PCIE0")
			(options
				(clearance outline)
				(anchor circle)
			)
			(primitives
				(gr_poly
					(pts
						(xy -0.1778 0.254) (xy 0.1778 0.254) (xy 0.254 0.1778) (xy 0.254 -0.1778) (xy 0.1778 -0.254) (xy -0.1778 -0.254)
						(xy -0.254 -0.1778) (xy -0.254 0.1778)
					)
					(width 0)
					(fill yes)
				)
			)
		)
		(pad "2" smd custom
			(at 0 0.500126)
			(size 0.127 0.127)
			(layers "B.Cu" "B.Mask" "B.Paste")
			(net "GND")
			(options
				(clearance outline)
				(anchor circle)
			)
			(primitives
				(gr_poly
					(pts
						(xy -0.1778 0.254) (xy 0.1778 0.254) (xy 0.254 0.1778) (xy 0.254 -0.1778) (xy 0.1778 -0.254) (xy -0.1778 -0.254)
						(xy -0.254 -0.1778) (xy -0.254 0.1778)
					)
					(width 0)
					(fill yes)
				)
			)
		)
	)
	(footprint ""
		(layer "B.Cu")
		(at 37.846 24.003 90)
		(property "Reference" "L14"
			(at -0.508 -0.78867 270)
			(unlocked yes)
			(layer "B.SilkS")
			(effects
				(font
					(size 0.7874 0.5842)
					(thickness 0.127)
				)
				(justify left mirror)
			)
		)
		(property "Value" ""
			(at 0 0 90)
			(layer "B.Fab")
			(effects
				(font
					(size 1.27 1.27)
				)
				(justify mirror)
			)
		)
		(duplicate_pad_numbers_are_jumpers no)
		(fp_line
			(start 0.0254 -0.127)
			(end -0.0254 -0.127)
			(stroke
				(width 0.1016)
				(type default)
			)
			(layer "B.SilkS")
		)
		(fp_line
			(start -0.0254 -0.127)
			(end -0.0254 0.127)
			(stroke
				(width 0.1016)
				(type default)
			)
			(layer "B.SilkS")
		)
		(fp_line
			(start 0.0254 0.127)
			(end 0.0254 -0.127)
			(stroke
				(width 0.1016)
				(type default)
			)
			(layer "B.SilkS")
		)
		(fp_line
			(start -0.0254 0.127)
			(end 0.0254 0.127)
			(stroke
				(width 0.1016)
				(type default)
			)
			(layer "B.SilkS")
		)
		(fp_poly
			(pts
				(xy -0.889 -0.4953) (xy -0.889 0.4953) (xy 0.889 0.4953) (xy 0.889 -0.4953)
			)
			(stroke
				(width 0)
				(type default)
			)
			(fill no)
			(layer "B.CrtYd")
		)
		(fp_line
			(start 0.508 -0.254)
			(end 0.508 0.254)
			(stroke
				(width 0.0254)
				(type default)
			)
			(layer "B.Fab")
		)
		(fp_line
			(start -0.508 -0.254)
			(end 0.508 -0.254)
			(stroke
				(width 0.0254)
				(type default)
			)
			(layer "B.Fab")
		)
		(fp_line
			(start 0.508 0.254)
			(end -0.508 0.254)
			(stroke
				(width 0.0254)
				(type default)
			)
			(layer "B.Fab")
		)
		(fp_line
			(start -0.508 0.254)
			(end -0.508 -0.254)
			(stroke
				(width 0.0254)
				(type default)
			)
			(layer "B.Fab")
		)
		(pad "1" smd rect
			(at 0.4699 0 270)
			(size 0.5334 0.508)
			(layers "B.Cu" "B.Mask" "B.Paste")
			(net "VDDA_TS0")
		)
		(pad "2" smd rect
			(at -0.4699 0 270)
			(size 0.5334 0.508)
			(layers "B.Cu" "B.Mask" "B.Paste")
			(net "VDD_1.5V")
		)
	)
	(footprint ""
		(layer "B.Cu")
		(at 65.8368 32.004 90)
		(property "Reference" "C68"
			(at 0.22733 4.826 0)
			(unlocked yes)
			(layer "B.SilkS")
			(effects
				(font
					(size 0.7874 0.5842)
					(thickness 0.127)
				)
				(justify left mirror)
			)
		)
		(property "Value" "100UF"
			(at 0.78232 0.4826 0)
			(unlocked yes)
			(layer "B.Fab")
			(hide yes)
			(effects
				(font
					(size 1.27 0.9652)
					(thickness 0.000001)
				)
				(justify left mirror)
			)
		)
		(property "Device Type" "CAPC0087"
			(at 0.78232 0.4826 0)
			(unlocked yes)
			(layer "B.Fab")
			(hide yes)
			(effects
				(font
					(size 1.27 0.9652)
					(thickness 0.000001)
				)
				(justify left mirror)
			)
		)
		(duplicate_pad_numbers_are_jumpers no)
		(fp_circle
			(center 0 0)
			(end 0 0.508)
			(stroke
				(width 0.2032)
				(type default)
			)
			(fill no)
			(layer "B.SilkS")
		)
		(fp_poly
			(pts
				(xy 1.27 2.9464) (xy -1.27 2.9464) (xy -1.27 -2.846095) (xy 1.27 -2.846095)
			)
			(stroke
				(width 0)
				(type default)
			)
			(fill no)
			(layer "B.CrtYd")
		)
		(fp_line
			(start 1.016 -2.794)
			(end -1.016 -2.794)
			(stroke
				(width 0.0254)
				(type default)
			)
			(layer "B.Fab")
		)
		(fp_line
			(start -1.016 -2.794)
			(end -1.016 2.794)
			(stroke
				(width 0.0254)
				(type default)
			)
			(layer "B.Fab")
		)
		(fp_line
			(start 1.016 2.794)
			(end 1.016 -2.794)
			(stroke
				(width 0.0254)
				(type default)
			)
			(layer "B.Fab")
		)
		(fp_line
			(start -1.016 2.794)
			(end 1.016 2.794)
			(stroke
				(width 0.0254)
				(type default)
			)
			(layer "B.Fab")
		)
		(pad "1" smd rect
			(at 0 -1.6764 270)
			(size 1.524 1.524)
			(layers "B.Cu" "B.Mask" "B.Paste")
			(net "DDR_VDDQ")
		)
		(pad "2" smd rect
			(at 0 1.6764 270)
			(size 1.524 1.524)
			(layers "B.Cu" "B.Mask" "B.Paste")
			(net "GND")
		)
		(zone
			(layer "B.Cu")
			(hatch none 0.5)
			(connect_pads
				(clearance 0)
			)
			(min_thickness 0.25)
			(keepout
				(tracks not_allowed)
				(vias allowed)
				(pads allowed)
				(copperpour not_allowed)
				(footprints allowed)
			)
			(placement
				(enabled no)
				(sheetname "")
			)
			(fill
				(thermal_gap 0.5)
				(thermal_bridge_width 0.5)
				(island_removal_mode 0)
			)
			(polygon
				(pts
					(xy 64.9478 31.2166) (xy 64.9478 32.7914) (xy 65.1002 32.7914) (xy 65.1002 31.2166)
				)
			)
		)
		(zone
			(layer "B.Cu")
			(hatch none 0.5)
			(connect_pads
				(clearance 0)
			)
			(min_thickness 0.25)
			(keepout
				(tracks not_allowed)
				(vias allowed)
				(pads allowed)
				(copperpour not_allowed)
				(footprints allowed)
			)
			(placement
				(enabled no)
				(sheetname "")
			)
			(fill
				(thermal_gap 0.5)
				(thermal_bridge_width 0.5)
				(island_removal_mode 0)
			)
			(polygon
				(pts
					(xy 66.5734 31.2166) (xy 66.5734 32.7914) (xy 66.7258 32.7914) (xy 66.7258 31.2166)
				)
			)
		)
		(zone
			(layer "B.Cu")
			(hatch none 0.5)
			(connect_pads
				(clearance 0)
			)
			(min_thickness 0.25)
			(keepout
				(tracks allowed)
				(vias not_allowed)
				(pads allowed)
				(copperpour not_allowed)
				(footprints allowed)
			)
			(placement
				(enabled no)
				(sheetname "")
			)
			(fill
				(thermal_gap 0.5)
				(thermal_bridge_width 0.5)
				(island_removal_mode 0)
			)
			(polygon
				(pts
					(xy 67.437 31.2166) (xy 67.437 32.7914) (xy 64.2366 32.7914) (xy 64.2366 31.2166)
				)
			)
		)
	)
	(footprint ""
		(layer "B.Cu")
		(at 22.733 30.861 -90)
		(property "Reference" "R89"
			(at -0.35433 0.889 0)
			(unlocked yes)
			(layer "B.SilkS")
			(effects
				(font
					(size 0.7874 0.5842)
					(thickness 0.127)
				)
				(justify left mirror)
			)
		)
		(property "Value" "4.75K"
			(at 0.148158 1.3462 180)
			(unlocked yes)
			(layer "B.Fab")
			(hide yes)
			(effects
				(font
					(size 1.27 0.9652)
					(thickness 0.000001)
				)
				(justify left mirror)
			)
		)
		(property "Device Type" "REST4024"
			(at 0.148158 1.3462 180)
			(unlocked yes)
			(layer "B.Fab")
			(hide yes)
			(effects
				(font
					(size 1.27 0.9652)
					(thickness 0.000001)
				)
				(justify left mirror)
			)
		)
		(duplicate_pad_numbers_are_jumpers no)
		(fp_poly
			(pts
				(xy -0.635 1.0668) (xy -0.635 -1.0668) (xy 0.635 -1.0668) (xy 0.635 1.0668)
			)
			(stroke
				(width 0)
				(type default)
			)
			(fill no)
			(layer "B.CrtYd")
		)
		(fp_line
			(start -0.254 0.508)
			(end 0.254 0.508)
			(stroke
				(width 0.0254)
				(type default)
			)
			(layer "B.Fab")
		)
		(fp_line
			(start 0.254 0.508)
			(end 0.254 -0.508)
			(stroke
				(width 0.0254)
				(type default)
			)
			(layer "B.Fab")
		)
		(fp_line
			(start -0.254 -0.508)
			(end -0.254 0.508)
			(stroke
				(width 0.0254)
				(type default)
			)
			(layer "B.Fab")
		)
		(fp_line
			(start 0.254 -0.508)
			(end -0.254 -0.508)
			(stroke
				(width 0.0254)
				(type default)
			)
			(layer "B.Fab")
		)
		(pad "1" smd rect
			(at 0 -0.4191 90)
			(size 0.508 0.5334)
			(layers "B.Cu" "B.Mask" "B.Paste")
			(net "CPLD_CORE_PSI_L")
		)
		(pad "2" smd rect
			(at 0 0.4191 90)
			(size 0.508 0.5334)
			(layers "B.Cu" "B.Mask" "B.Paste")
			(net "VDD_3.3V")
		)
		(zone
			(layer "B.Cu")
			(hatch none 0.5)
			(connect_pads
				(clearance 0)
			)
			(min_thickness 0.25)
			(keepout
				(tracks not_allowed)
				(vias allowed)
				(pads allowed)
				(copperpour not_allowed)
				(footprints allowed)
			)
			(placement
				(enabled no)
				(sheetname "")
			)
			(fill
				(thermal_gap 0.5)
				(thermal_bridge_width 0.5)
				(island_removal_mode 0)
			)
			(polygon
				(pts
					(xy 22.7584 30.8356) (xy 22.7076 30.8356) (xy 22.7076 30.8864) (xy 22.7584 30.8864)
				)
			)
		)
	)
	(footprint ""
		(layer "B.Cu")
		(at 33.655 21.844 -90)
		(property "Reference" "R397"
			(at -0.86233 -0.762 0)
			(unlocked yes)
			(layer "B.SilkS")
			(effects
				(font
					(size 0.7874 0.5842)
					(thickness 0.127)
				)
				(justify left mirror)
			)
		)
		(property "Value" "4.75K"
			(at 0.148158 1.3462 180)
			(unlocked yes)
			(layer "B.Fab")
			(hide yes)
			(effects
				(font
					(size 1.27 0.9652)
					(thickness 0.000001)
				)
				(justify left mirror)
			)
		)
		(property "Device Type" "REST4024"
			(at 0.148158 1.3462 180)
			(unlocked yes)
			(layer "B.Fab")
			(hide yes)
			(effects
				(font
					(size 1.27 0.9652)
					(thickness 0.000001)
				)
				(justify left mirror)
			)
		)
		(duplicate_pad_numbers_are_jumpers no)
		(fp_poly
			(pts
				(xy -0.635 1.0668) (xy -0.635 -1.0668) (xy 0.635 -1.0668) (xy 0.635 1.0668)
			)
			(stroke
				(width 0)
				(type default)
			)
			(fill no)
			(layer "B.CrtYd")
		)
		(fp_line
			(start -0.254 0.508)
			(end 0.254 0.508)
			(stroke
				(width 0.0254)
				(type default)
			)
			(layer "B.Fab")
		)
		(fp_line
			(start 0.254 0.508)
			(end 0.254 -0.508)
			(stroke
				(width 0.0254)
				(type default)
			)
			(layer "B.Fab")
		)
		(fp_line
			(start -0.254 -0.508)
			(end -0.254 0.508)
			(stroke
				(width 0.0254)
				(type default)
			)
			(layer "B.Fab")
		)
		(fp_line
			(start 0.254 -0.508)
			(end -0.254 -0.508)
			(stroke
				(width 0.0254)
				(type default)
			)
			(layer "B.Fab")
		)
		(pad "1" smd rect
			(at 0 -0.4191 90)
			(size 0.508 0.5334)
			(layers "B.Cu" "B.Mask" "B.Paste")
			(net "EXT_3.3V")
		)
		(pad "2" smd rect
			(at 0 0.4191 90)
			(size 0.508 0.5334)
			(layers "B.Cu" "B.Mask" "B.Paste")
			(net "CPLD_PCIE0_WAKE_L")
		)
		(zone
			(layer "B.Cu")
			(hatch none 0.5)
			(connect_pads
				(clearance 0)
			)
			(min_thickness 0.25)
			(keepout
				(tracks not_allowed)
				(vias allowed)
				(pads allowed)
				(copperpour not_allowed)
				(footprints allowed)
			)
			(placement
				(enabled no)
				(sheetname "")
			)
			(fill
				(thermal_gap 0.5)
				(thermal_bridge_width 0.5)
				(island_removal_mode 0)
			)
			(polygon
				(pts
					(xy 33.6804 21.8186) (xy 33.6296 21.8186) (xy 33.6296 21.8694) (xy 33.6804 21.8694)
				)
			)
		)
	)
	(footprint ""
		(layer "B.Cu")
		(at 51.237007 29.541978)
		(property "Reference" "C197"
			(at 0 0 0)
			(layer "B.SilkS")
			(hide yes)
			(effects
				(font
					(size 1.27 1.27)
				)
				(justify mirror)
			)
		)
		(property "Value" ""
			(at 0 0 0)
			(layer "B.Fab")
			(effects
				(font
					(size 1.27 1.27)
				)
				(justify mirror)
			)
		)
		(duplicate_pad_numbers_are_jumpers no)
		(fp_circle
			(center 0 0)
			(end 0.104648 0)
			(stroke
				(width 0.1016)
				(type default)
			)
			(fill no)
			(layer "B.SilkS")
		)
		(fp_poly
			(pts
				(xy 0.381 -0.889) (xy 0.381 0.889) (xy -0.381 0.889) (xy -0.381 -0.889)
			)
			(stroke
				(width 0)
				(type default)
			)
			(fill no)
			(layer "B.CrtYd")
		)
		(fp_line
			(start -0.508 -1.016)
			(end -0.508 1.016)
			(stroke
				(width 0.0254)
				(type default)
			)
			(layer "B.Fab")
		)
		(fp_line
			(start -0.508 1.016)
			(end 0.508 1.016)
			(stroke
				(width 0.0254)
				(type default)
			)
			(layer "B.Fab")
		)
		(fp_line
			(start 0.254 -1.016)
			(end -0.508 -1.016)
			(stroke
				(width 0.0254)
				(type default)
			)
			(layer "B.Fab")
		)
		(fp_line
			(start 0.508 -1.016)
			(end 0.254 -1.016)
			(stroke
				(width 0.0254)
				(type default)
			)
			(layer "B.Fab")
		)
		(fp_line
			(start 0.508 1.016)
			(end 0.508 -1.016)
			(stroke
				(width 0.0254)
				(type default)
			)
			(layer "B.Fab")
		)
		(pad "1" smd custom
			(at 0 -0.500126 180)
			(size 0.127 0.127)
			(layers "B.Cu" "B.Mask" "B.Paste")
			(net "VDD_CORE")
			(options
				(clearance outline)
				(anchor circle)
			)
			(primitives
				(gr_poly
					(pts
						(xy -0.1778 0.254) (xy 0.1778 0.254) (xy 0.254 0.1778) (xy 0.254 -0.1778) (xy 0.1778 -0.254) (xy -0.1778 -0.254)
						(xy -0.254 -0.1778) (xy -0.254 0.1778)
					)
					(width 0)
					(fill yes)
				)
			)
		)
		(pad "2" smd custom
			(at 0 0.500126 180)
			(size 0.127 0.127)
			(layers "B.Cu" "B.Mask" "B.Paste")
			(net "GND")
			(options
				(clearance outline)
				(anchor circle)
			)
			(primitives
				(gr_poly
					(pts
						(xy -0.1778 0.254) (xy 0.1778 0.254) (xy 0.254 0.1778) (xy 0.254 -0.1778) (xy 0.1778 -0.254) (xy -0.1778 -0.254)
						(xy -0.254 -0.1778) (xy -0.254 0.1778)
					)
					(width 0)
					(fill yes)
				)
			)
		)
	)
	(footprint ""
		(layer "B.Cu")
		(at 34.29762 23.622 -90)
		(property "Reference" "R50"
			(at 0 0 90)
			(layer "B.SilkS")
			(hide yes)
			(effects
				(font
					(size 1.27 1.27)
				)
				(justify mirror)
			)
		)
		(property "Value" "4.75K"
			(at 0.148158 1.3462 180)
			(unlocked yes)
			(layer "B.Fab")
			(hide yes)
			(effects
				(font
					(size 1.27 0.9652)
					(thickness 0.000001)
				)
				(justify left mirror)
			)
		)
		(property "Device Type" "REST4024"
			(at 0.148158 1.3462 180)
			(unlocked yes)
			(layer "B.Fab")
			(hide yes)
			(effects
				(font
					(size 1.27 0.9652)
					(thickness 0.000001)
				)
				(justify left mirror)
			)
		)
		(duplicate_pad_numbers_are_jumpers no)
		(fp_poly
			(pts
				(xy -0.635 1.0668) (xy -0.635 -1.0668) (xy 0.635 -1.0668) (xy 0.635 1.0668)
			)
			(stroke
				(width 0)
				(type default)
			)
			(fill no)
			(layer "B.CrtYd")
		)
		(fp_line
			(start -0.254 0.508)
			(end 0.254 0.508)
			(stroke
				(width 0.0254)
				(type default)
			)
			(layer "B.Fab")
		)
		(fp_line
			(start 0.254 0.508)
			(end 0.254 -0.508)
			(stroke
				(width 0.0254)
				(type default)
			)
			(layer "B.Fab")
		)
		(fp_line
			(start -0.254 -0.508)
			(end -0.254 0.508)
			(stroke
				(width 0.0254)
				(type default)
			)
			(layer "B.Fab")
		)
		(fp_line
			(start 0.254 -0.508)
			(end -0.254 -0.508)
			(stroke
				(width 0.0254)
				(type default)
			)
			(layer "B.Fab")
		)
		(pad "1" smd rect
			(at 0 -0.4191 90)
			(size 0.508 0.5334)
			(layers "B.Cu" "B.Mask" "B.Paste")
			(net "EXT_3.3V")
		)
		(pad "2" smd rect
			(at 0 0.4191 90)
			(size 0.508 0.5334)
			(layers "B.Cu" "B.Mask" "B.Paste")
			(net "CPLD_VERSION_0")
		)
		(zone
			(layer "B.Cu")
			(hatch none 0.5)
			(connect_pads
				(clearance 0)
			)
			(min_thickness 0.25)
			(keepout
				(tracks not_allowed)
				(vias allowed)
				(pads allowed)
				(copperpour not_allowed)
				(footprints allowed)
			)
			(placement
				(enabled no)
				(sheetname "")
			)
			(fill
				(thermal_gap 0.5)
				(thermal_bridge_width 0.5)
				(island_removal_mode 0)
			)
			(polygon
				(pts
					(xy 34.32302 23.5966) (xy 34.27222 23.5966) (xy 34.27222 23.6474) (xy 34.32302 23.6474)
				)
			)
		)
	)
	(footprint ""
		(layer "B.Cu")
		(at 22.479 4.953 90)
		(property "Reference" "R379"
			(at 0.60833 -1.143 0)
			(unlocked yes)
			(layer "B.SilkS")
			(effects
				(font
					(size 0.7874 0.5842)
					(thickness 0.127)
				)
				(justify left mirror)
			)
		)
		(property "Value" "4.75K"
			(at 0.148158 1.3462 0)
			(unlocked yes)
			(layer "B.Fab")
			(hide yes)
			(effects
				(font
					(size 1.27 0.9652)
					(thickness 0.000001)
				)
				(justify left mirror)
			)
		)
		(property "Device Type" "REST4024"
			(at 0.148158 1.3462 0)
			(unlocked yes)
			(layer "B.Fab")
			(hide yes)
			(effects
				(font
					(size 1.27 0.9652)
					(thickness 0.000001)
				)
				(justify left mirror)
			)
		)
		(duplicate_pad_numbers_are_jumpers no)
		(fp_poly
			(pts
				(xy -0.635 1.0668) (xy -0.635 -1.0668) (xy 0.635 -1.0668) (xy 0.635 1.0668)
			)
			(stroke
				(width 0)
				(type default)
			)
			(fill no)
			(layer "B.CrtYd")
		)
		(fp_line
			(start 0.254 -0.508)
			(end -0.254 -0.508)
			(stroke
				(width 0.0254)
				(type default)
			)
			(layer "B.Fab")
		)
		(fp_line
			(start -0.254 -0.508)
			(end -0.254 0.508)
			(stroke
				(width 0.0254)
				(type default)
			)
			(layer "B.Fab")
		)
		(fp_line
			(start 0.254 0.508)
			(end 0.254 -0.508)
			(stroke
				(width 0.0254)
				(type default)
			)
			(layer "B.Fab")
		)
		(fp_line
			(start -0.254 0.508)
			(end 0.254 0.508)
			(stroke
				(width 0.0254)
				(type default)
			)
			(layer "B.Fab")
		)
		(pad "1" smd rect
			(at 0 -0.4191 270)
			(size 0.508 0.5334)
			(layers "B.Cu" "B.Mask" "B.Paste")
			(net "NFP_SMBUS_ALERT_L")
		)
		(pad "2" smd rect
			(at 0 0.4191 270)
			(size 0.508 0.5334)
			(layers "B.Cu" "B.Mask" "B.Paste")
			(net "EXT_3.3V")
		)
		(zone
			(layer "B.Cu")
			(hatch none 0.5)
			(connect_pads
				(clearance 0)
			)
			(min_thickness 0.25)
			(keepout
				(tracks not_allowed)
				(vias allowed)
				(pads allowed)
				(copperpour not_allowed)
				(footprints allowed)
			)
			(placement
				(enabled no)
				(sheetname "")
			)
			(fill
				(thermal_gap 0.5)
				(thermal_bridge_width 0.5)
				(island_removal_mode 0)
			)
			(polygon
				(pts
					(xy 22.4536 4.9784) (xy 22.5044 4.9784) (xy 22.5044 4.9276) (xy 22.4536 4.9276)
				)
			)
		)
	)
	(footprint ""
		(layer "B.Cu")
		(at 61.236987 10.542016 180)
		(property "Reference" "C187"
			(at 0 0 0)
			(layer "B.SilkS")
			(hide yes)
			(effects
				(font
					(size 1.27 1.27)
				)
				(justify mirror)
			)
		)
		(property "Value" ""
			(at 0 0 0)
			(layer "B.Fab")
			(effects
				(font
					(size 1.27 1.27)
				)
				(justify mirror)
			)
		)
		(duplicate_pad_numbers_are_jumpers no)
		(fp_circle
			(center 0 0)
			(end -0.104648 0)
			(stroke
				(width 0.1016)
				(type default)
			)
			(fill no)
			(layer "B.SilkS")
		)
		(fp_poly
			(pts
				(xy 0.381 -0.889) (xy 0.381 0.889) (xy -0.381 0.889) (xy -0.381 -0.889)
			)
			(stroke
				(width 0)
				(type default)
			)
			(fill no)
			(layer "B.CrtYd")
		)
		(fp_line
			(start 0.508 1.016)
			(end 0.508 -1.016)
			(stroke
				(width 0.0254)
				(type default)
			)
			(layer "B.Fab")
		)
		(fp_line
			(start 0.508 -1.016)
			(end 0.254 -1.016)
			(stroke
				(width 0.0254)
				(type default)
			)
			(layer "B.Fab")
		)
		(fp_line
			(start 0.254 -1.016)
			(end -0.508 -1.016)
			(stroke
				(width 0.0254)
				(type default)
			)
			(layer "B.Fab")
		)
		(fp_line
			(start -0.508 1.016)
			(end 0.508 1.016)
			(stroke
				(width 0.0254)
				(type default)
			)
			(layer "B.Fab")
		)
		(fp_line
			(start -0.508 -1.016)
			(end -0.508 1.016)
			(stroke
				(width 0.0254)
				(type default)
			)
			(layer "B.Fab")
		)
		(pad "1" smd custom
			(at 0 -0.500126)
			(size 0.127 0.127)
			(layers "B.Cu" "B.Mask" "B.Paste")
			(net "VDDA_DDR0_32A")
			(options
				(clearance outline)
				(anchor circle)
			)
			(primitives
				(gr_poly
					(pts
						(xy -0.1778 0.254) (xy 0.1778 0.254) (xy 0.254 0.1778) (xy 0.254 -0.1778) (xy 0.1778 -0.254) (xy -0.1778 -0.254)
						(xy -0.254 -0.1778) (xy -0.254 0.1778)
					)
					(width 0)
					(fill yes)
				)
			)
		)
		(pad "2" smd custom
			(at 0 0.500126)
			(size 0.127 0.127)
			(layers "B.Cu" "B.Mask" "B.Paste")
			(net "GND")
			(options
				(clearance outline)
				(anchor circle)
			)
			(primitives
				(gr_poly
					(pts
						(xy -0.1778 0.254) (xy 0.1778 0.254) (xy 0.254 0.1778) (xy 0.254 -0.1778) (xy 0.1778 -0.254) (xy -0.1778 -0.254)
						(xy -0.254 -0.1778) (xy -0.254 0.1778)
					)
					(width 0)
					(fill yes)
				)
			)
		)
	)
	(footprint ""
		(layer "B.Cu")
		(at 81.850992 1.899006)
		(property "Reference" "V1_A-A03"
			(at 0 0 0)
			(layer "B.SilkS")
			(hide yes)
			(effects
				(font
					(size 1.27 1.27)
				)
				(justify mirror)
			)
		)
		(property "Value" ""
			(at 0 0 0)
			(layer "B.Fab")
			(effects
				(font
					(size 1.27 1.27)
				)
				(justify mirror)
			)
		)
		(duplicate_pad_numbers_are_jumpers no)
		(pad "1" thru_hole circle
			(at 0 0 180)
			(size 0.4572 0.4572)
			(drill 0.20574)
			(layers "*.Cu" "*.Mask")
			(remove_unused_layers no)
			(net "DDR0_32A_A3")
			(clearance 0.1143)
			(thermal_gap 0.1143)
		)
	)
	(footprint ""
		(layer "B.Cu")
		(at 63.736982 22.041993 90)
		(property "Reference" "R310"
			(at -0.844677 0.652018 0)
			(unlocked yes)
			(layer "B.SilkS")
			(effects
				(font
					(size 0.7874 0.5842)
					(thickness 0.127)
				)
				(justify mirror)
			)
		)
		(property "Value" ""
			(at 0 0 90)
			(layer "B.Fab")
			(effects
				(font
					(size 1.27 1.27)
				)
				(justify mirror)
			)
		)
		(duplicate_pad_numbers_are_jumpers no)
		(fp_circle
			(center 0 0)
			(end 0 0.104648)
			(stroke
				(width 0.1016)
				(type default)
			)
			(fill no)
			(layer "B.SilkS")
		)
		(fp_poly
			(pts
				(xy 0.381 -0.889) (xy 0.381 0.889) (xy -0.381 0.889) (xy -0.381 -0.889)
			)
			(stroke
				(width 0)
				(type default)
			)
			(fill no)
			(layer "B.CrtYd")
		)
		(fp_line
			(start 0.508 -1.016)
			(end 0.254 -1.016)
			(stroke
				(width 0.0254)
				(type default)
			)
			(layer "B.Fab")
		)
		(fp_line
			(start 0.254 -1.016)
			(end -0.508 -1.016)
			(stroke
				(width 0.0254)
				(type default)
			)
			(layer "B.Fab")
		)
		(fp_line
			(start -0.508 -1.016)
			(end -0.508 1.016)
			(stroke
				(width 0.0254)
				(type default)
			)
			(layer "B.Fab")
		)
		(fp_line
			(start 0.508 1.016)
			(end 0.508 -1.016)
			(stroke
				(width 0.0254)
				(type default)
			)
			(layer "B.Fab")
		)
		(fp_line
			(start -0.508 1.016)
			(end 0.508 1.016)
			(stroke
				(width 0.0254)
				(type default)
			)
			(layer "B.Fab")
		)
		(pad "1" smd custom
			(at 0 -0.500126 270)
			(size 0.127 0.127)
			(layers "B.Cu" "B.Mask" "B.Paste")
			(net "6N3963")
			(options
				(clearance outline)
				(anchor circle)
			)
			(primitives
				(gr_poly
					(pts
						(xy -0.1778 0.254) (xy 0.1778 0.254) (xy 0.254 0.1778) (xy 0.254 -0.1778) (xy 0.1778 -0.254) (xy -0.1778 -0.254)
						(xy -0.254 -0.1778) (xy -0.254 0.1778)
					)
					(width 0)
					(fill yes)
				)
			)
		)
		(pad "2" smd custom
			(at 0 0.500126 270)
			(size 0.127 0.127)
			(layers "B.Cu" "B.Mask" "B.Paste")
			(net "DDR_VDDQ")
			(options
				(clearance outline)
				(anchor circle)
			)
			(primitives
				(gr_poly
					(pts
						(xy -0.1778 0.254) (xy 0.1778 0.254) (xy 0.254 0.1778) (xy 0.254 -0.1778) (xy 0.1778 -0.254) (xy -0.1778 -0.254)
						(xy -0.254 -0.1778) (xy -0.254 0.1778)
					)
					(width 0)
					(fill yes)
				)
			)
		)
	)
	(footprint ""
		(layer "B.Cu")
		(at 82.65099 2.699004)
		(property "Reference" "V1_A-A02"
			(at 0 0 0)
			(layer "B.SilkS")
			(hide yes)
			(effects
				(font
					(size 1.27 1.27)
				)
				(justify mirror)
			)
		)
		(property "Value" ""
			(at 0 0 0)
			(layer "B.Fab")
			(effects
				(font
					(size 1.27 1.27)
				)
				(justify mirror)
			)
		)
		(duplicate_pad_numbers_are_jumpers no)
		(pad "1" thru_hole circle
			(at 0 0 180)
			(size 0.4572 0.4572)
			(drill 0.20574)
			(layers "*.Cu" "*.Mask")
			(remove_unused_layers no)
			(net "DDR0_32A_A2")
			(clearance 0.1143)
			(thermal_gap 0.1143)
		)
	)
	(footprint ""
		(layer "B.Cu")
		(at 60.728987 18.542 -90)
		(property "Reference" "C1"
			(at 0.15367 1.419987 0)
			(unlocked yes)
			(layer "B.SilkS")
			(effects
				(font
					(size 0.7874 0.5842)
					(thickness 0.127)
				)
				(justify left mirror)
			)
		)
		(property "Value" "22UF"
			(at 0.148158 1.7526 180)
			(unlocked yes)
			(layer "B.Fab")
			(hide yes)
			(effects
				(font
					(size 1.27 0.9652)
					(thickness 0.000001)
				)
				(justify left mirror)
			)
		)
		(property "Device Type" "CAPC0063"
			(at 0.148158 1.7526 180)
			(unlocked yes)
			(layer "B.Fab")
			(hide yes)
			(effects
				(font
					(size 1.27 0.9652)
					(thickness 0.000001)
				)
				(justify left mirror)
			)
		)
		(duplicate_pad_numbers_are_jumpers no)
		(fp_circle
			(center 0 0)
			(end 0 -0.127)
			(stroke
				(width 0.2032)
				(type default)
			)
			(fill no)
			(layer "B.SilkS")
		)
		(fp_poly
			(pts
				(xy -0.7874 -1.6637) (xy 0.7874 -1.6637) (xy 0.7874 1.6637) (xy -0.7874 1.6637)
			)
			(stroke
				(width 0)
				(type default)
			)
			(fill no)
			(layer "B.CrtYd")
		)
		(fp_line
			(start -0.4064 0.8128)
			(end 0.4064 0.8128)
			(stroke
				(width 0.0254)
				(type default)
			)
			(layer "B.Fab")
		)
		(fp_line
			(start 0.4064 0.8128)
			(end 0.4064 -0.7874)
			(stroke
				(width 0.0254)
				(type default)
			)
			(layer "B.Fab")
		)
		(fp_line
			(start -0.4064 -0.7874)
			(end -0.4064 0.8128)
			(stroke
				(width 0.0254)
				(type default)
			)
			(layer "B.Fab")
		)
		(fp_line
			(start 0.4064 -0.7874)
			(end -0.4064 -0.7874)
			(stroke
				(width 0.0254)
				(type default)
			)
			(layer "B.Fab")
		)
		(pad "1" smd rect
			(at 0 -0.8001 90)
			(size 0.8636 0.9652)
			(layers "B.Cu" "B.Mask" "B.Paste")
			(net "DDR_VDDQ")
		)
		(pad "2" smd rect
			(at 0 0.8001 90)
			(size 0.8636 0.9652)
			(layers "B.Cu" "B.Mask" "B.Paste")
			(net "GND")
		)
		(zone
			(layer "B.Cu")
			(hatch none 0.5)
			(connect_pads
				(clearance 0)
			)
			(min_thickness 0.25)
			(keepout
				(tracks not_allowed)
				(vias allowed)
				(pads allowed)
				(copperpour not_allowed)
				(footprints allowed)
			)
			(placement
				(enabled no)
				(sheetname "")
			)
			(fill
				(thermal_gap 0.5)
				(thermal_bridge_width 0.5)
				(island_removal_mode 0)
			)
			(polygon
				(pts
					(xy 60.982987 18.6055) (xy 60.982987 18.4785) (xy 60.474987 18.4785) (xy 60.474987 18.6055)
				)
			)
		)
	)
	(footprint ""
		(layer "B.Cu")
		(at 1.2319 11.176 90)
		(property "Reference" "R387"
			(at 0.22733 -0.9779 0)
			(unlocked yes)
			(layer "B.SilkS")
			(effects
				(font
					(size 0.7874 0.5842)
					(thickness 0.127)
				)
				(justify left mirror)
			)
		)
		(property "Value" "0"
			(at 0.148158 1.3462 0)
			(unlocked yes)
			(layer "B.Fab")
			(hide yes)
			(effects
				(font
					(size 1.27 0.9652)
					(thickness 0.000001)
				)
				(justify left mirror)
			)
		)
		(property "Device Type" "REST1111"
			(at 0.148158 1.3462 0)
			(unlocked yes)
			(layer "B.Fab")
			(hide yes)
			(effects
				(font
					(size 1.27 0.9652)
					(thickness 0.000001)
				)
				(justify left mirror)
			)
		)
		(duplicate_pad_numbers_are_jumpers no)
		(fp_poly
			(pts
				(xy -0.635 1.0668) (xy -0.635 -1.0668) (xy 0.635 -1.0668) (xy 0.635 1.0668)
			)
			(stroke
				(width 0)
				(type default)
			)
			(fill no)
			(layer "B.CrtYd")
		)
		(fp_line
			(start 0.254 -0.508)
			(end -0.254 -0.508)
			(stroke
				(width 0.0254)
				(type default)
			)
			(layer "B.Fab")
		)
		(fp_line
			(start -0.254 -0.508)
			(end -0.254 0.508)
			(stroke
				(width 0.0254)
				(type default)
			)
			(layer "B.Fab")
		)
		(fp_line
			(start 0.254 0.508)
			(end 0.254 -0.508)
			(stroke
				(width 0.0254)
				(type default)
			)
			(layer "B.Fab")
		)
		(fp_line
			(start -0.254 0.508)
			(end 0.254 0.508)
			(stroke
				(width 0.0254)
				(type default)
			)
			(layer "B.Fab")
		)
		(pad "1" smd rect
			(at 0 -0.4191 270)
			(size 0.508 0.5334)
			(layers "B.Cu" "B.Mask" "B.Paste")
			(net "NWK1_I2C_SCL")
		)
		(pad "2" smd rect
			(at 0 0.4191 270)
			(size 0.508 0.5334)
			(layers "B.Cu" "B.Mask" "B.Paste")
			(net "MUX_NFP_GPIO2_NWK1_I2C_SCL")
		)
		(zone
			(layer "B.Cu")
			(hatch none 0.5)
			(connect_pads
				(clearance 0)
			)
			(min_thickness 0.25)
			(keepout
				(tracks not_allowed)
				(vias allowed)
				(pads allowed)
				(copperpour not_allowed)
				(footprints allowed)
			)
			(placement
				(enabled no)
				(sheetname "")
			)
			(fill
				(thermal_gap 0.5)
				(thermal_bridge_width 0.5)
				(island_removal_mode 0)
			)
			(polygon
				(pts
					(xy 1.2065 11.2014) (xy 1.2573 11.2014) (xy 1.2573 11.1506) (xy 1.2065 11.1506)
				)
			)
		)
	)
	(footprint ""
		(layer "B.Cu")
		(at 63.236983 14.542008 180)
		(property "Reference" "R284"
			(at 0 0 0)
			(layer "B.SilkS")
			(hide yes)
			(effects
				(font
					(size 1.27 1.27)
				)
				(justify mirror)
			)
		)
		(property "Value" ""
			(at 0 0 0)
			(layer "B.Fab")
			(effects
				(font
					(size 1.27 1.27)
				)
				(justify mirror)
			)
		)
		(duplicate_pad_numbers_are_jumpers no)
		(fp_circle
			(center 0 0)
			(end -0.104648 0)
			(stroke
				(width 0.1016)
				(type default)
			)
			(fill no)
			(layer "B.SilkS")
		)
		(fp_poly
			(pts
				(xy 0.381 -0.889) (xy 0.381 0.889) (xy -0.381 0.889) (xy -0.381 -0.889)
			)
			(stroke
				(width 0)
				(type default)
			)
			(fill no)
			(layer "B.CrtYd")
		)
		(fp_line
			(start 0.508 1.016)
			(end 0.508 -1.016)
			(stroke
				(width 0.0254)
				(type default)
			)
			(layer "B.Fab")
		)
		(fp_line
			(start 0.508 -1.016)
			(end 0.254 -1.016)
			(stroke
				(width 0.0254)
				(type default)
			)
			(layer "B.Fab")
		)
		(fp_line
			(start 0.254 -1.016)
			(end -0.508 -1.016)
			(stroke
				(width 0.0254)
				(type default)
			)
			(layer "B.Fab")
		)
		(fp_line
			(start -0.508 1.016)
			(end 0.508 1.016)
			(stroke
				(width 0.0254)
				(type default)
			)
			(layer "B.Fab")
		)
		(fp_line
			(start -0.508 -1.016)
			(end -0.508 1.016)
			(stroke
				(width 0.0254)
				(type default)
			)
			(layer "B.Fab")
		)
		(pad "1" smd custom
			(at 0 -0.500126)
			(size 0.127 0.127)
			(layers "B.Cu" "B.Mask" "B.Paste")
			(net "DDR0_32A_VREF")
			(options
				(clearance outline)
				(anchor circle)
			)
			(primitives
				(gr_poly
					(pts
						(xy -0.1778 0.254) (xy 0.1778 0.254) (xy 0.254 0.1778) (xy 0.254 -0.1778) (xy 0.1778 -0.254) (xy -0.1778 -0.254)
						(xy -0.254 -0.1778) (xy -0.254 0.1778)
					)
					(width 0)
					(fill yes)
				)
			)
		)
		(pad "2" smd custom
			(at 0 0.500126)
			(size 0.127 0.127)
			(layers "B.Cu" "B.Mask" "B.Paste")
			(net "DDR_VDDQ")
			(options
				(clearance outline)
				(anchor circle)
			)
			(primitives
				(gr_poly
					(pts
						(xy -0.1778 0.254) (xy 0.1778 0.254) (xy 0.254 0.1778) (xy 0.254 -0.1778) (xy 0.1778 -0.254) (xy -0.1778 -0.254)
						(xy -0.254 -0.1778) (xy -0.254 0.1778)
					)
					(width 0)
					(fill yes)
				)
			)
		)
	)
	(footprint ""
		(layer "B.Cu")
		(at 28.194 24.003 90)
		(property "Reference" "R58"
			(at -0.40767 3.175 0)
			(unlocked yes)
			(layer "B.SilkS")
			(effects
				(font
					(size 0.7874 0.5842)
					(thickness 0.127)
				)
				(justify left mirror)
			)
		)
		(property "Value" "4.75K"
			(at 0.148158 1.3462 0)
			(unlocked yes)
			(layer "B.Fab")
			(hide yes)
			(effects
				(font
					(size 1.27 0.9652)
					(thickness 0.000001)
				)
				(justify left mirror)
			)
		)
		(property "Device Type" "REST4024"
			(at 0.148158 1.3462 0)
			(unlocked yes)
			(layer "B.Fab")
			(hide yes)
			(effects
				(font
					(size 1.27 0.9652)
					(thickness 0.000001)
				)
				(justify left mirror)
			)
		)
		(duplicate_pad_numbers_are_jumpers no)
		(fp_poly
			(pts
				(xy -0.635 1.0668) (xy -0.635 -1.0668) (xy 0.635 -1.0668) (xy 0.635 1.0668)
			)
			(stroke
				(width 0)
				(type default)
			)
			(fill no)
			(layer "B.CrtYd")
		)
		(fp_line
			(start 0.254 -0.508)
			(end -0.254 -0.508)
			(stroke
				(width 0.0254)
				(type default)
			)
			(layer "B.Fab")
		)
		(fp_line
			(start -0.254 -0.508)
			(end -0.254 0.508)
			(stroke
				(width 0.0254)
				(type default)
			)
			(layer "B.Fab")
		)
		(fp_line
			(start 0.254 0.508)
			(end 0.254 -0.508)
			(stroke
				(width 0.0254)
				(type default)
			)
			(layer "B.Fab")
		)
		(fp_line
			(start -0.254 0.508)
			(end 0.254 0.508)
			(stroke
				(width 0.0254)
				(type default)
			)
			(layer "B.Fab")
		)
		(pad "1" smd rect
			(at 0 -0.4191 270)
			(size 0.508 0.5334)
			(layers "B.Cu" "B.Mask" "B.Paste")
			(net "NFP_CPLD_INT_L")
		)
		(pad "2" smd rect
			(at 0 0.4191 270)
			(size 0.508 0.5334)
			(layers "B.Cu" "B.Mask" "B.Paste")
			(net "GND")
		)
		(zone
			(layer "B.Cu")
			(hatch none 0.5)
			(connect_pads
				(clearance 0)
			)
			(min_thickness 0.25)
			(keepout
				(tracks not_allowed)
				(vias allowed)
				(pads allowed)
				(copperpour not_allowed)
				(footprints allowed)
			)
			(placement
				(enabled no)
				(sheetname "")
			)
			(fill
				(thermal_gap 0.5)
				(thermal_bridge_width 0.5)
				(island_removal_mode 0)
			)
			(polygon
				(pts
					(xy 28.1686 24.0284) (xy 28.2194 24.0284) (xy 28.2194 23.9776) (xy 28.1686 23.9776)
				)
			)
		)
	)
	(footprint ""
		(layer "B.Cu")
		(at 60.236989 27.541982)
		(property "Reference" "C177"
			(at 1.458341 0.906018 270)
			(unlocked yes)
			(layer "B.SilkS")
			(effects
				(font
					(size 0.7874 0.5842)
					(thickness 0.127)
				)
				(justify mirror)
			)
		)
		(property "Value" ""
			(at 0 0 0)
			(layer "B.Fab")
			(effects
				(font
					(size 1.27 1.27)
				)
				(justify mirror)
			)
		)
		(duplicate_pad_numbers_are_jumpers no)
		(fp_circle
			(center 0 0)
			(end 0.104648 0)
			(stroke
				(width 0.1016)
				(type default)
			)
			(fill no)
			(layer "B.SilkS")
		)
		(fp_poly
			(pts
				(xy 0.381 -0.889) (xy 0.381 0.889) (xy -0.381 0.889) (xy -0.381 -0.889)
			)
			(stroke
				(width 0)
				(type default)
			)
			(fill no)
			(layer "B.CrtYd")
		)
		(fp_line
			(start -0.508 -1.016)
			(end -0.508 1.016)
			(stroke
				(width 0.0254)
				(type default)
			)
			(layer "B.Fab")
		)
		(fp_line
			(start -0.508 1.016)
			(end 0.508 1.016)
			(stroke
				(width 0.0254)
				(type default)
			)
			(layer "B.Fab")
		)
		(fp_line
			(start 0.254 -1.016)
			(end -0.508 -1.016)
			(stroke
				(width 0.0254)
				(type default)
			)
			(layer "B.Fab")
		)
		(fp_line
			(start 0.508 -1.016)
			(end 0.254 -1.016)
			(stroke
				(width 0.0254)
				(type default)
			)
			(layer "B.Fab")
		)
		(fp_line
			(start 0.508 1.016)
			(end 0.508 -1.016)
			(stroke
				(width 0.0254)
				(type default)
			)
			(layer "B.Fab")
		)
		(pad "1" smd custom
			(at 0 -0.500126 180)
			(size 0.127 0.127)
			(layers "B.Cu" "B.Mask" "B.Paste")
			(net "VDD_CORE")
			(options
				(clearance outline)
				(anchor circle)
			)
			(primitives
				(gr_poly
					(pts
						(xy -0.1778 0.254) (xy 0.1778 0.254) (xy 0.254 0.1778) (xy 0.254 -0.1778) (xy 0.1778 -0.254) (xy -0.1778 -0.254)
						(xy -0.254 -0.1778) (xy -0.254 0.1778)
					)
					(width 0)
					(fill yes)
				)
			)
		)
		(pad "2" smd custom
			(at 0 0.500126 180)
			(size 0.127 0.127)
			(layers "B.Cu" "B.Mask" "B.Paste")
			(net "GND")
			(options
				(clearance outline)
				(anchor circle)
			)
			(primitives
				(gr_poly
					(pts
						(xy -0.1778 0.254) (xy 0.1778 0.254) (xy 0.254 0.1778) (xy 0.254 -0.1778) (xy 0.1778 -0.254) (xy -0.1778 -0.254)
						(xy -0.254 -0.1778) (xy -0.254 0.1778)
					)
					(width 0)
					(fill yes)
				)
			)
		)
	)
	(footprint ""
		(layer "B.Cu")
		(at 82.931 41.5798)
		(property "Reference" "R4"
			(at 0.86233 0.9652 270)
			(unlocked yes)
			(layer "B.SilkS")
			(effects
				(font
					(size 0.7874 0.5842)
					(thickness 0.127)
				)
				(justify left mirror)
			)
		)
		(property "Value" "30.1K"
			(at 0.148158 1.3462 270)
			(unlocked yes)
			(layer "B.Fab")
			(hide yes)
			(effects
				(font
					(size 1.27 0.9652)
					(thickness 0.000001)
				)
				(justify left mirror)
			)
		)
		(property "Device Type" "REST0216"
			(at 0.148158 1.3462 270)
			(unlocked yes)
			(layer "B.Fab")
			(hide yes)
			(effects
				(font
					(size 1.27 0.9652)
					(thickness 0.000001)
				)
				(justify left mirror)
			)
		)
		(duplicate_pad_numbers_are_jumpers no)
		(fp_poly
			(pts
				(xy -0.635 1.0668) (xy -0.635 -1.0668) (xy 0.635 -1.0668) (xy 0.635 1.0668)
			)
			(stroke
				(width 0)
				(type default)
			)
			(fill no)
			(layer "B.CrtYd")
		)
		(fp_line
			(start -0.254 -0.508)
			(end -0.254 0.508)
			(stroke
				(width 0.0254)
				(type default)
			)
			(layer "B.Fab")
		)
		(fp_line
			(start -0.254 0.508)
			(end 0.254 0.508)
			(stroke
				(width 0.0254)
				(type default)
			)
			(layer "B.Fab")
		)
		(fp_line
			(start 0.254 -0.508)
			(end -0.254 -0.508)
			(stroke
				(width 0.0254)
				(type default)
			)
			(layer "B.Fab")
		)
		(fp_line
			(start 0.254 0.508)
			(end 0.254 -0.508)
			(stroke
				(width 0.0254)
				(type default)
			)
			(layer "B.Fab")
		)
		(pad "1" smd rect
			(at 0 -0.4191 180)
			(size 0.508 0.5334)
			(layers "B.Cu" "B.Mask" "B.Paste")
			(net "GND")
		)
		(pad "2" smd rect
			(at 0 0.4191 180)
			(size 0.508 0.5334)
			(layers "B.Cu" "B.Mask" "B.Paste")
			(net "11N2146")
		)
		(zone
			(layer "B.Cu")
			(hatch none 0.5)
			(connect_pads
				(clearance 0)
			)
			(min_thickness 0.25)
			(keepout
				(tracks not_allowed)
				(vias allowed)
				(pads allowed)
				(copperpour not_allowed)
				(footprints allowed)
			)
			(placement
				(enabled no)
				(sheetname "")
			)
			(fill
				(thermal_gap 0.5)
				(thermal_bridge_width 0.5)
				(island_removal_mode 0)
			)
			(polygon
				(pts
					(xy 82.9056 41.5544) (xy 82.9056 41.6052) (xy 82.9564 41.6052) (xy 82.9564 41.5544)
				)
			)
		)
	)
	(footprint ""
		(layer "B.Cu")
		(at 81.050994 14.256004)
		(property "Reference" "V2_A-BA2"
			(at 0 0 0)
			(layer "B.SilkS")
			(hide yes)
			(effects
				(font
					(size 1.27 1.27)
				)
				(justify mirror)
			)
		)
		(property "Value" ""
			(at 0 0 0)
			(layer "B.Fab")
			(effects
				(font
					(size 1.27 1.27)
				)
				(justify mirror)
			)
		)
		(duplicate_pad_numbers_are_jumpers no)
		(pad "1" thru_hole circle
			(at 0 0 180)
			(size 0.4572 0.4572)
			(drill 0.20574)
			(layers "*.Cu" "*.Mask")
			(remove_unused_layers no)
			(net "DDR0_32A_BA2")
			(clearance 0.1143)
			(thermal_gap 0.1143)
		)
	)
	(footprint ""
		(layer "B.Cu")
		(at 77.051002 7.498994)
		(property "Reference" "V_A-DQ02"
			(at 0 0 0)
			(layer "B.SilkS")
			(hide yes)
			(effects
				(font
					(size 1.27 1.27)
				)
				(justify mirror)
			)
		)
		(property "Value" ""
			(at 0 0 0)
			(layer "B.Fab")
			(effects
				(font
					(size 1.27 1.27)
				)
				(justify mirror)
			)
		)
		(duplicate_pad_numbers_are_jumpers no)
		(pad "1" thru_hole circle
			(at 0 0 180)
			(size 0.4572 0.4572)
			(drill 0.20574)
			(layers "*.Cu" "*.Mask")
			(remove_unused_layers no)
			(net "DDR0_32A_DQ2")
			(clearance 0.1143)
			(thermal_gap 0.1143)
		)
	)
	(footprint ""
		(layer "B.Cu")
		(at 65.532 3.556)
		(property "Reference" "L1"
			(at 0.762 -1.11633 0)
			(unlocked yes)
			(layer "B.SilkS")
			(effects
				(font
					(size 0.7874 0.5842)
					(thickness 0.127)
				)
				(justify left mirror)
			)
		)
		(property "Value" ""
			(at 0 0 0)
			(layer "B.Fab")
			(effects
				(font
					(size 1.27 1.27)
				)
				(justify mirror)
			)
		)
		(duplicate_pad_numbers_are_jumpers no)
		(fp_rect
			(start -1.7907 0.889)
			(end 1.7907 -0.889)
			(stroke
				(width 0)
				(type default)
			)
			(fill no)
			(layer "B.CrtYd")
		)
		(fp_line
			(start -1.778 -0.762)
			(end -1.778 0.762)
			(stroke
				(width 0.0254)
				(type default)
			)
			(layer "B.Fab")
		)
		(fp_line
			(start -1.778 0.762)
			(end 1.778 0.762)
			(stroke
				(width 0.0254)
				(type default)
			)
			(layer "B.Fab")
		)
		(fp_line
			(start 1.778 -0.762)
			(end -1.778 -0.762)
			(stroke
				(width 0.0254)
				(type default)
			)
			(layer "B.Fab")
		)
		(fp_line
			(start 1.778 0.762)
			(end 1.778 -0.762)
			(stroke
				(width 0.0254)
				(type default)
			)
			(layer "B.Fab")
		)
		(pad "1" smd rect
			(at 0.7493 0 90)
			(size 0.7874 0.8128)
			(layers "B.Cu" "B.Mask" "B.Paste")
			(net "VDD_1.8V")
		)
		(pad "2" smd rect
			(at -0.7493 0 90)
			(size 0.7874 0.8128)
			(layers "B.Cu" "B.Mask" "B.Paste")
			(net "VDDAH_PCIE0")
		)
		(zone
			(layer "B.Cu")
			(hatch none 0.5)
			(connect_pads
				(clearance 0)
			)
			(min_thickness 0.25)
			(keepout
				(tracks not_allowed)
				(vias allowed)
				(pads allowed)
				(copperpour not_allowed)
				(footprints allowed)
			)
			(placement
				(enabled no)
				(sheetname "")
			)
			(fill
				(thermal_gap 0.5)
				(thermal_bridge_width 0.5)
				(island_removal_mode 0)
			)
			(polygon
				(pts
					(xy 65.8114 3.1496) (xy 65.8114 3.9624) (xy 65.2526 3.9624) (xy 65.2526 3.1496)
				)
			)
		)
	)
	(footprint ""
		(layer "B.Cu")
		(at 63.119 36.957 180)
		(property "Reference" "R75"
			(at 0.91567 -1.016 270)
			(unlocked yes)
			(layer "B.SilkS")
			(effects
				(font
					(size 0.7874 0.5842)
					(thickness 0.127)
				)
				(justify left mirror)
			)
		)
		(property "Value" "4.75K"
			(at 0.148158 1.3462 90)
			(unlocked yes)
			(layer "B.Fab")
			(hide yes)
			(effects
				(font
					(size 1.27 0.9652)
					(thickness 0.000001)
				)
				(justify left mirror)
			)
		)
		(property "Device Type" "REST4024"
			(at 0.148158 1.3462 90)
			(unlocked yes)
			(layer "B.Fab")
			(hide yes)
			(effects
				(font
					(size 1.27 0.9652)
					(thickness 0.000001)
				)
				(justify left mirror)
			)
		)
		(duplicate_pad_numbers_are_jumpers no)
		(fp_poly
			(pts
				(xy -0.635 1.0668) (xy -0.635 -1.0668) (xy 0.635 -1.0668) (xy 0.635 1.0668)
			)
			(stroke
				(width 0)
				(type default)
			)
			(fill no)
			(layer "B.CrtYd")
		)
		(fp_line
			(start 0.254 0.508)
			(end 0.254 -0.508)
			(stroke
				(width 0.0254)
				(type default)
			)
			(layer "B.Fab")
		)
		(fp_line
			(start 0.254 -0.508)
			(end -0.254 -0.508)
			(stroke
				(width 0.0254)
				(type default)
			)
			(layer "B.Fab")
		)
		(fp_line
			(start -0.254 0.508)
			(end 0.254 0.508)
			(stroke
				(width 0.0254)
				(type default)
			)
			(layer "B.Fab")
		)
		(fp_line
			(start -0.254 -0.508)
			(end -0.254 0.508)
			(stroke
				(width 0.0254)
				(type default)
			)
			(layer "B.Fab")
		)
		(pad "1" smd rect
			(at 0 -0.4191)
			(size 0.508 0.5334)
			(layers "B.Cu" "B.Mask" "B.Paste")
			(net "CORE_FB_PH1_THERM_L")
		)
		(pad "2" smd rect
			(at 0 0.4191)
			(size 0.508 0.5334)
			(layers "B.Cu" "B.Mask" "B.Paste")
			(net "VDD_3.3V")
		)
		(zone
			(layer "B.Cu")
			(hatch none 0.5)
			(connect_pads
				(clearance 0)
			)
			(min_thickness 0.25)
			(keepout
				(tracks not_allowed)
				(vias allowed)
				(pads allowed)
				(copperpour not_allowed)
				(footprints allowed)
			)
			(placement
				(enabled no)
				(sheetname "")
			)
			(fill
				(thermal_gap 0.5)
				(thermal_bridge_width 0.5)
				(island_removal_mode 0)
			)
			(polygon
				(pts
					(xy 63.1444 36.9824) (xy 63.1444 36.9316) (xy 63.0936 36.9316) (xy 63.0936 36.9824)
				)
			)
		)
	)
	(footprint ""
		(layer "B.Cu")
		(at 22.606 22.352 90)
		(property "Reference" "U7"
			(at -3.81 -2.94767 270)
			(unlocked yes)
			(layer "B.SilkS")
			(effects
				(font
					(size 0.7874 0.5842)
					(thickness 0.127)
				)
				(justify left mirror)
			)
		)
		(property "Value" "*"
			(at 2.0066 1.756842 90)
			(unlocked yes)
			(layer "B.Fab")
			(hide yes)
			(effects
				(font
					(size 1.27 0.9652)
					(thickness 0.000001)
				)
				(justify left mirror)
			)
		)
		(property "Device Type" "PROG0053"
			(at 2.0066 1.756842 90)
			(unlocked yes)
			(layer "B.Fab")
			(hide yes)
			(effects
				(font
					(size 1.27 0.9652)
					(thickness 0.000001)
				)
				(justify left mirror)
			)
		)
		(duplicate_pad_numbers_are_jumpers no)
		(fp_line
			(start 2.286 -2.794)
			(end -2.286 -2.794)
			(stroke
				(width 0.2032)
				(type default)
			)
			(layer "B.SilkS")
		)
		(fp_line
			(start 0.762 -2.794)
			(end 0.762 -1.905)
			(stroke
				(width 0.2032)
				(type default)
			)
			(layer "B.SilkS")
		)
		(fp_line
			(start -2.286 -2.794)
			(end -2.286 -2.54)
			(stroke
				(width 0.2032)
				(type default)
			)
			(layer "B.SilkS")
		)
		(fp_line
			(start 2.286 -2.54)
			(end 2.286 -2.794)
			(stroke
				(width 0.2032)
				(type default)
			)
			(layer "B.SilkS")
		)
		(fp_line
			(start 0.762 -1.905)
			(end -0.762 -1.905)
			(stroke
				(width 0.2032)
				(type default)
			)
			(layer "B.SilkS")
		)
		(fp_line
			(start -0.762 -1.905)
			(end -0.762 -2.794)
			(stroke
				(width 0.2032)
				(type default)
			)
			(layer "B.SilkS")
		)
		(fp_line
			(start 2.286 2.54)
			(end 2.286 2.794)
			(stroke
				(width 0.2032)
				(type default)
			)
			(layer "B.SilkS")
		)
		(fp_line
			(start 2.286 2.794)
			(end -2.286 2.794)
			(stroke
				(width 0.2032)
				(type default)
			)
			(layer "B.SilkS")
		)
		(fp_line
			(start -2.286 2.794)
			(end -2.286 2.54)
			(stroke
				(width 0.2032)
				(type default)
			)
			(layer "B.SilkS")
		)
		(fp_circle
			(center 2.794 -2.794)
			(end 2.794 -2.54)
			(stroke
				(width 0.2032)
				(type default)
			)
			(fill no)
			(layer "B.SilkS")
		)
		(fp_poly
			(pts
				(xy -2.54 3.048) (xy -2.54 2.921) (xy -4.191 2.921) (xy -4.191 -2.921) (xy -2.54 -2.921) (xy -2.54 -3.048)
				(xy 2.54 -3.048) (xy 2.54 -2.921) (xy 4.191 -2.921) (xy 4.191 2.921) (xy 2.54 2.921) (xy 2.54 3.048)
			)
			(stroke
				(width 0)
				(type default)
			)
			(fill no)
			(layer "B.CrtYd")
		)
		(fp_line
			(start 2.0066 -2.5019)
			(end 2.0066 2.5019)
			(stroke
				(width 0.2032)
				(type default)
			)
			(layer "B.Fab")
		)
		(fp_line
			(start -2.0066 -2.5019)
			(end 2.0066 -2.5019)
			(stroke
				(width 0.2032)
				(type default)
			)
			(layer "B.Fab")
		)
		(fp_line
			(start 0.635 -2.4892)
			(end 0.635 -1.7272)
			(stroke
				(width 0.2032)
				(type default)
			)
			(layer "B.Fab")
		)
		(fp_line
			(start 0.635 -1.7272)
			(end -0.635 -1.7272)
			(stroke
				(width 0.2032)
				(type default)
			)
			(layer "B.Fab")
		)
		(fp_line
			(start -0.635 -1.7272)
			(end -0.635 -2.4892)
			(stroke
				(width 0.2032)
				(type default)
			)
			(layer "B.Fab")
		)
		(fp_line
			(start 2.0066 2.5019)
			(end -2.0066 2.5019)
			(stroke
				(width 0.2032)
				(type default)
			)
			(layer "B.Fab")
		)
		(fp_line
			(start -2.0066 2.5019)
			(end -2.0066 -2.5019)
			(stroke
				(width 0.2032)
				(type default)
			)
			(layer "B.Fab")
		)
		(fp_circle
			(center 1.524 -1.905)
			(end 1.524 -1.621028)
			(stroke
				(width 0.2032)
				(type default)
			)
			(fill no)
			(layer "B.Fab")
		)
		(pad "1" smd rect
			(at 2.667 -1.905 270)
			(size 2.032 0.635)
			(layers "B.Cu" "B.Mask" "B.Paste")
			(net "NFP_ARM_SPI_FLASH_SEL")
		)
		(pad "2" smd rect
			(at 2.667 -0.635 270)
			(size 2.032 0.635)
			(layers "B.Cu" "B.Mask" "B.Paste")
			(net "NFP_ARM_SPI_FLASH_MISO")
		)
		(pad "3" smd rect
			(at 2.667 0.635 270)
			(size 2.032 0.635)
			(layers "B.Cu" "B.Mask" "B.Paste")
			(net "NFP_ARM_SPI_FLASH_WP_L")
		)
		(pad "4" smd rect
			(at 2.667 1.905 270)
			(size 2.032 0.635)
			(layers "B.Cu" "B.Mask" "B.Paste")
			(net "GND")
		)
		(pad "5" smd rect
			(at -2.667 1.905 270)
			(size 2.032 0.635)
			(layers "B.Cu" "B.Mask" "B.Paste")
			(net "NFP_ARM_SPI_FLASH_MOSI")
		)
		(pad "6" smd rect
			(at -2.667 0.635 270)
			(size 2.032 0.635)
			(layers "B.Cu" "B.Mask" "B.Paste")
			(net "NFP_ARM_SPI_FLASH_SCK")
		)
		(pad "7" smd rect
			(at -2.667 -0.635 270)
			(size 2.032 0.635)
			(layers "B.Cu" "B.Mask" "B.Paste")
			(net "3N2521")
		)
		(pad "8" smd rect
			(at -2.667 -1.905 270)
			(size 2.032 0.635)
			(layers "B.Cu" "B.Mask" "B.Paste")
			(net "VDD_3.3V")
		)
	)
	(footprint ""
		(layer "B.Cu")
		(at 15.113 32.131)
		(property "Reference" "TP68"
			(at -1.016 -0.73533 0)
			(unlocked yes)
			(layer "B.SilkS")
			(effects
				(font
					(size 0.7874 0.5842)
					(thickness 0.127)
				)
				(justify left mirror)
			)
		)
		(property "Value" "*"
			(at 0.4826 -0.14732 0)
			(unlocked yes)
			(layer "B.Fab")
			(hide yes)
			(effects
				(font
					(size 1.27 0.9652)
					(thickness 0.000001)
				)
				(justify left mirror)
			)
		)
		(property "Device Type" "TP_SMALL"
			(at 0.4826 -0.14732 0)
			(unlocked yes)
			(layer "B.Fab")
			(hide yes)
			(effects
				(font
					(size 1.27 0.9652)
					(thickness 0.000001)
				)
				(justify left mirror)
			)
		)
		(duplicate_pad_numbers_are_jumpers no)
		(fp_line
			(start -0.8636 -0.8636)
			(end 0.8636 -0.8636)
			(stroke
				(width 0.1524)
				(type default)
			)
			(layer "B.SilkS")
		)
		(fp_line
			(start -0.8636 0.8636)
			(end -0.8636 -0.8636)
			(stroke
				(width 0.1524)
				(type default)
			)
			(layer "B.SilkS")
		)
		(fp_line
			(start 0.8636 -0.8636)
			(end 0.8636 0.8636)
			(stroke
				(width 0.1524)
				(type default)
			)
			(layer "B.SilkS")
		)
		(fp_line
			(start 0.8636 0.8636)
			(end -0.8636 0.8636)
			(stroke
				(width 0.1524)
				(type default)
			)
			(layer "B.SilkS")
		)
		(fp_poly
			(pts
				(xy 0.635 -0.635) (xy 0.635 0.635) (xy -0.635 0.635) (xy -0.635 -0.635)
			)
			(stroke
				(width 0)
				(type default)
			)
			(fill no)
			(layer "B.CrtYd")
		)
		(pad "1" smd rect
			(at 0 0 180)
			(size 1.27 1.27)
			(layers "B.Cu" "B.Mask" "B.Paste")
			(net "MAIN_3.3V")
		)
	)
	(footprint ""
		(layer "B.Cu")
		(at 78.650998 14.256004)
		(property "Reference" "V2_A-RAS"
			(at 0 0 0)
			(layer "B.SilkS")
			(hide yes)
			(effects
				(font
					(size 1.27 1.27)
				)
				(justify mirror)
			)
		)
		(property "Value" ""
			(at 0 0 0)
			(layer "B.Fab")
			(effects
				(font
					(size 1.27 1.27)
				)
				(justify mirror)
			)
		)
		(duplicate_pad_numbers_are_jumpers no)
		(pad "1" thru_hole circle
			(at 0 0 180)
			(size 0.4572 0.4572)
			(drill 0.20574)
			(layers "*.Cu" "*.Mask")
			(remove_unused_layers no)
			(net "DDR0_32A_RAS_L")
			(clearance 0.1143)
			(thermal_gap 0.1143)
		)
	)
	(footprint ""
		(layer "B.Cu")
		(at 63.119 38.735 180)
		(property "Reference" "C47"
			(at 0 0 0)
			(layer "B.SilkS")
			(hide yes)
			(effects
				(font
					(size 1.27 1.27)
				)
				(justify mirror)
			)
		)
		(property "Value" "1000PF"
			(at 0.091846 0.2921 90)
			(unlocked yes)
			(layer "B.Fab")
			(hide yes)
			(effects
				(font
					(size 0.7874 0.5842)
					(thickness 0.2032)
				)
				(justify left mirror)
			)
		)
		(property "Device Type" "CAPC0083"
			(at 0.091846 0.2921 90)
			(unlocked yes)
			(layer "B.Fab")
			(hide yes)
			(effects
				(font
					(size 0.7874 0.5842)
					(thickness 0.2032)
				)
				(justify left mirror)
			)
		)
		(duplicate_pad_numbers_are_jumpers no)
		(fp_poly
			(pts
				(xy -0.635 1.0668) (xy -0.635 -1.0668) (xy 0.635 -1.0668) (xy 0.635 1.0668)
			)
			(stroke
				(width 0)
				(type default)
			)
			(fill no)
			(layer "B.CrtYd")
		)
		(fp_line
			(start 0.254 0.508)
			(end 0.254 -0.508)
			(stroke
				(width 0.0254)
				(type default)
			)
			(layer "B.Fab")
		)
		(fp_line
			(start 0.254 -0.508)
			(end -0.254 -0.508)
			(stroke
				(width 0.0254)
				(type default)
			)
			(layer "B.Fab")
		)
		(fp_line
			(start -0.254 0.508)
			(end 0.254 0.508)
			(stroke
				(width 0.0254)
				(type default)
			)
			(layer "B.Fab")
		)
		(fp_line
			(start -0.254 -0.508)
			(end -0.254 0.508)
			(stroke
				(width 0.0254)
				(type default)
			)
			(layer "B.Fab")
		)
		(pad "1" smd rect
			(at 0 -0.4191)
			(size 0.508 0.5334)
			(layers "B.Cu" "B.Mask" "B.Paste")
			(net "10N2224")
		)
		(pad "2" smd rect
			(at 0 0.4191)
			(size 0.508 0.5334)
			(layers "B.Cu" "B.Mask" "B.Paste")
			(net "GND")
		)
		(zone
			(layer "B.Cu")
			(hatch none 0.5)
			(connect_pads
				(clearance 0)
			)
			(min_thickness 0.25)
			(keepout
				(tracks not_allowed)
				(vias allowed)
				(pads allowed)
				(copperpour not_allowed)
				(footprints allowed)
			)
			(placement
				(enabled no)
				(sheetname "")
			)
			(fill
				(thermal_gap 0.5)
				(thermal_bridge_width 0.5)
				(island_removal_mode 0)
			)
			(polygon
				(pts
					(xy 63.1444 38.7604) (xy 63.1444 38.7096) (xy 63.0936 38.7096) (xy 63.0936 38.7604)
				)
			)
		)
	)
	(footprint ""
		(layer "B.Cu")
		(at 3.556 10.16 90)
		(property "Reference" "R375"
			(at 0 0 90)
			(layer "B.SilkS")
			(hide yes)
			(effects
				(font
					(size 1.27 1.27)
				)
				(justify mirror)
			)
		)
		(property "Value" "4.75K"
			(at 0.148158 1.3462 0)
			(unlocked yes)
			(layer "B.Fab")
			(hide yes)
			(effects
				(font
					(size 1.27 0.9652)
					(thickness 0.000001)
				)
				(justify left mirror)
			)
		)
		(property "Device Type" "REST4024"
			(at 0.148158 1.3462 0)
			(unlocked yes)
			(layer "B.Fab")
			(hide yes)
			(effects
				(font
					(size 1.27 0.9652)
					(thickness 0.000001)
				)
				(justify left mirror)
			)
		)
		(duplicate_pad_numbers_are_jumpers no)
		(fp_poly
			(pts
				(xy -0.635 1.0668) (xy -0.635 -1.0668) (xy 0.635 -1.0668) (xy 0.635 1.0668)
			)
			(stroke
				(width 0)
				(type default)
			)
			(fill no)
			(layer "B.CrtYd")
		)
		(fp_line
			(start 0.254 -0.508)
			(end -0.254 -0.508)
			(stroke
				(width 0.0254)
				(type default)
			)
			(layer "B.Fab")
		)
		(fp_line
			(start -0.254 -0.508)
			(end -0.254 0.508)
			(stroke
				(width 0.0254)
				(type default)
			)
			(layer "B.Fab")
		)
		(fp_line
			(start 0.254 0.508)
			(end 0.254 -0.508)
			(stroke
				(width 0.0254)
				(type default)
			)
			(layer "B.Fab")
		)
		(fp_line
			(start -0.254 0.508)
			(end 0.254 0.508)
			(stroke
				(width 0.0254)
				(type default)
			)
			(layer "B.Fab")
		)
		(pad "1" smd rect
			(at 0 -0.4191 270)
			(size 0.508 0.5334)
			(layers "B.Cu" "B.Mask" "B.Paste")
			(net "13N4347")
		)
		(pad "2" smd rect
			(at 0 0.4191 270)
			(size 0.508 0.5334)
			(layers "B.Cu" "B.Mask" "B.Paste")
			(net "GND")
		)
		(zone
			(layer "B.Cu")
			(hatch none 0.5)
			(connect_pads
				(clearance 0)
			)
			(min_thickness 0.25)
			(keepout
				(tracks not_allowed)
				(vias allowed)
				(pads allowed)
				(copperpour not_allowed)
				(footprints allowed)
			)
			(placement
				(enabled no)
				(sheetname "")
			)
			(fill
				(thermal_gap 0.5)
				(thermal_bridge_width 0.5)
				(island_removal_mode 0)
			)
			(polygon
				(pts
					(xy 3.5306 10.1854) (xy 3.5814 10.1854) (xy 3.5814 10.1346) (xy 3.5306 10.1346)
				)
			)
		)
	)
	(footprint ""
		(layer "B.Cu")
		(at 73.05101 13.456006)
		(property "Reference" "V_A-DQ31"
			(at 0 0 0)
			(layer "B.SilkS")
			(hide yes)
			(effects
				(font
					(size 1.27 1.27)
				)
				(justify mirror)
			)
		)
		(property "Value" ""
			(at 0 0 0)
			(layer "B.Fab")
			(effects
				(font
					(size 1.27 1.27)
				)
				(justify mirror)
			)
		)
		(duplicate_pad_numbers_are_jumpers no)
		(pad "1" thru_hole circle
			(at 0 0 180)
			(size 0.4572 0.4572)
			(drill 0.20574)
			(layers "*.Cu" "*.Mask")
			(remove_unused_layers no)
			(net "DDR0_32A_DQ31")
			(clearance 0.1143)
			(thermal_gap 0.1143)
		)
	)
	(footprint ""
		(layer "B.Cu")
		(at 26.035 11.75512)
		(property "Reference" "R147"
			(at 0.73533 2.08788 270)
			(unlocked yes)
			(layer "B.SilkS")
			(effects
				(font
					(size 0.7874 0.5842)
					(thickness 0.127)
				)
				(justify left mirror)
			)
		)
		(property "Value" "0"
			(at 0.148158 1.3462 270)
			(unlocked yes)
			(layer "B.Fab")
			(hide yes)
			(effects
				(font
					(size 1.27 0.9652)
					(thickness 0.000001)
				)
				(justify left mirror)
			)
		)
		(property "Device Type" "REST1111"
			(at 0.148158 1.3462 270)
			(unlocked yes)
			(layer "B.Fab")
			(hide yes)
			(effects
				(font
					(size 1.27 0.9652)
					(thickness 0.000001)
				)
				(justify left mirror)
			)
		)
		(duplicate_pad_numbers_are_jumpers no)
		(fp_poly
			(pts
				(xy -0.635 1.0668) (xy -0.635 -1.0668) (xy 0.635 -1.0668) (xy 0.635 1.0668)
			)
			(stroke
				(width 0)
				(type default)
			)
			(fill no)
			(layer "B.CrtYd")
		)
		(fp_line
			(start -0.254 -0.508)
			(end -0.254 0.508)
			(stroke
				(width 0.0254)
				(type default)
			)
			(layer "B.Fab")
		)
		(fp_line
			(start -0.254 0.508)
			(end 0.254 0.508)
			(stroke
				(width 0.0254)
				(type default)
			)
			(layer "B.Fab")
		)
		(fp_line
			(start 0.254 -0.508)
			(end -0.254 -0.508)
			(stroke
				(width 0.0254)
				(type default)
			)
			(layer "B.Fab")
		)
		(fp_line
			(start 0.254 0.508)
			(end 0.254 -0.508)
			(stroke
				(width 0.0254)
				(type default)
			)
			(layer "B.Fab")
		)
		(pad "1" smd rect
			(at 0 -0.4191 180)
			(size 0.508 0.5334)
			(layers "B.Cu" "B.Mask" "B.Paste")
			(net "NFP_JTAG_ARM_TDI")
		)
		(pad "2" smd rect
			(at 0 0.4191 180)
			(size 0.508 0.5334)
			(layers "B.Cu" "B.Mask" "B.Paste")
			(net "NFP_JTAG_ARM_TDO")
		)
		(zone
			(layer "B.Cu")
			(hatch none 0.5)
			(connect_pads
				(clearance 0)
			)
			(min_thickness 0.25)
			(keepout
				(tracks not_allowed)
				(vias allowed)
				(pads allowed)
				(copperpour not_allowed)
				(footprints allowed)
			)
			(placement
				(enabled no)
				(sheetname "")
			)
			(fill
				(thermal_gap 0.5)
				(thermal_bridge_width 0.5)
				(island_removal_mode 0)
			)
			(polygon
				(pts
					(xy 26.0096 11.72972) (xy 26.0096 11.78052) (xy 26.0604 11.78052) (xy 26.0604 11.72972)
				)
			)
		)
	)
	(footprint ""
		(layer "B.Cu")
		(at 50.237009 31.541974)
		(property "Reference" "C174"
			(at -0.987679 0.081026 270)
			(unlocked yes)
			(layer "B.SilkS")
			(effects
				(font
					(size 0.7874 0.5842)
					(thickness 0.127)
				)
				(justify mirror)
			)
		)
		(property "Value" ""
			(at 0 0 0)
			(layer "B.Fab")
			(effects
				(font
					(size 1.27 1.27)
				)
				(justify mirror)
			)
		)
		(duplicate_pad_numbers_are_jumpers no)
		(fp_circle
			(center 0 0)
			(end 0.104648 0)
			(stroke
				(width 0.1016)
				(type default)
			)
			(fill no)
			(layer "B.SilkS")
		)
		(fp_poly
			(pts
				(xy 0.381 -0.889) (xy 0.381 0.889) (xy -0.381 0.889) (xy -0.381 -0.889)
			)
			(stroke
				(width 0)
				(type default)
			)
			(fill no)
			(layer "B.CrtYd")
		)
		(fp_line
			(start -0.508 -1.016)
			(end -0.508 1.016)
			(stroke
				(width 0.0254)
				(type default)
			)
			(layer "B.Fab")
		)
		(fp_line
			(start -0.508 1.016)
			(end 0.508 1.016)
			(stroke
				(width 0.0254)
				(type default)
			)
			(layer "B.Fab")
		)
		(fp_line
			(start 0.254 -1.016)
			(end -0.508 -1.016)
			(stroke
				(width 0.0254)
				(type default)
			)
			(layer "B.Fab")
		)
		(fp_line
			(start 0.508 -1.016)
			(end 0.254 -1.016)
			(stroke
				(width 0.0254)
				(type default)
			)
			(layer "B.Fab")
		)
		(fp_line
			(start 0.508 1.016)
			(end 0.508 -1.016)
			(stroke
				(width 0.0254)
				(type default)
			)
			(layer "B.Fab")
		)
		(pad "1" smd custom
			(at 0 -0.500126 180)
			(size 0.127 0.127)
			(layers "B.Cu" "B.Mask" "B.Paste")
			(net "VDD_CORE")
			(options
				(clearance outline)
				(anchor circle)
			)
			(primitives
				(gr_poly
					(pts
						(xy -0.1778 0.254) (xy 0.1778 0.254) (xy 0.254 0.1778) (xy 0.254 -0.1778) (xy 0.1778 -0.254) (xy -0.1778 -0.254)
						(xy -0.254 -0.1778) (xy -0.254 0.1778)
					)
					(width 0)
					(fill yes)
				)
			)
		)
		(pad "2" smd custom
			(at 0 0.500126 180)
			(size 0.127 0.127)
			(layers "B.Cu" "B.Mask" "B.Paste")
			(net "GND")
			(options
				(clearance outline)
				(anchor circle)
			)
			(primitives
				(gr_poly
					(pts
						(xy -0.1778 0.254) (xy 0.1778 0.254) (xy 0.254 0.1778) (xy 0.254 -0.1778) (xy 0.1778 -0.254) (xy -0.1778 -0.254)
						(xy -0.254 -0.1778) (xy -0.254 0.1778)
					)
					(width 0)
					(fill yes)
				)
			)
		)
	)
	(footprint ""
		(layer "B.Cu")
		(at 35.179 44.831)
		(property "Reference" "TP13"
			(at -1.16967 -2.159 270)
			(unlocked yes)
			(layer "B.SilkS")
			(effects
				(font
					(size 0.7874 0.5842)
					(thickness 0.127)
				)
				(justify left mirror)
			)
		)
		(property "Value" "*"
			(at 0.4826 -0.14732 0)
			(unlocked yes)
			(layer "B.Fab")
			(hide yes)
			(effects
				(font
					(size 1.27 0.9652)
					(thickness 0.000001)
				)
				(justify left mirror)
			)
		)
		(property "Device Type" "TP_SMALL"
			(at 0.4826 -0.14732 0)
			(unlocked yes)
			(layer "B.Fab")
			(hide yes)
			(effects
				(font
					(size 1.27 0.9652)
					(thickness 0.000001)
				)
				(justify left mirror)
			)
		)
		(duplicate_pad_numbers_are_jumpers no)
		(fp_line
			(start -0.8636 -0.8636)
			(end 0.8636 -0.8636)
			(stroke
				(width 0.1524)
				(type default)
			)
			(layer "B.SilkS")
		)
		(fp_line
			(start -0.8636 0.8636)
			(end -0.8636 -0.8636)
			(stroke
				(width 0.1524)
				(type default)
			)
			(layer "B.SilkS")
		)
		(fp_line
			(start 0.8636 -0.8636)
			(end 0.8636 0.8636)
			(stroke
				(width 0.1524)
				(type default)
			)
			(layer "B.SilkS")
		)
		(fp_line
			(start 0.8636 0.8636)
			(end -0.8636 0.8636)
			(stroke
				(width 0.1524)
				(type default)
			)
			(layer "B.SilkS")
		)
		(fp_poly
			(pts
				(xy 0.635 -0.635) (xy 0.635 0.635) (xy -0.635 0.635) (xy -0.635 -0.635)
			)
			(stroke
				(width 0)
				(type default)
			)
			(fill no)
			(layer "B.CrtYd")
		)
		(pad "1" smd rect
			(at 0 0 180)
			(size 1.27 1.27)
			(layers "B.Cu" "B.Mask" "B.Paste")
			(net "DEBUG_CPLD_PGRM_JTAG_TDI")
		)
	)
	(footprint ""
		(layer "B.Cu")
		(at 33.274 44.831)
		(property "Reference" "TP10"
			(at 0.127 -3.02133 0)
			(unlocked yes)
			(layer "B.SilkS")
			(effects
				(font
					(size 0.7874 0.5842)
					(thickness 0.127)
				)
				(justify left mirror)
			)
		)
		(property "Value" "*"
			(at 0.4826 -0.14732 0)
			(unlocked yes)
			(layer "B.Fab")
			(hide yes)
			(effects
				(font
					(size 1.27 0.9652)
					(thickness 0.000001)
				)
				(justify left mirror)
			)
		)
		(property "Device Type" "TP_SMALL"
			(at 0.4826 -0.14732 0)
			(unlocked yes)
			(layer "B.Fab")
			(hide yes)
			(effects
				(font
					(size 1.27 0.9652)
					(thickness 0.000001)
				)
				(justify left mirror)
			)
		)
		(duplicate_pad_numbers_are_jumpers no)
		(fp_line
			(start -0.8636 -0.8636)
			(end 0.8636 -0.8636)
			(stroke
				(width 0.1524)
				(type default)
			)
			(layer "B.SilkS")
		)
		(fp_line
			(start -0.8636 0.8636)
			(end -0.8636 -0.8636)
			(stroke
				(width 0.1524)
				(type default)
			)
			(layer "B.SilkS")
		)
		(fp_line
			(start 0.8636 -0.8636)
			(end 0.8636 0.8636)
			(stroke
				(width 0.1524)
				(type default)
			)
			(layer "B.SilkS")
		)
		(fp_line
			(start 0.8636 0.8636)
			(end -0.8636 0.8636)
			(stroke
				(width 0.1524)
				(type default)
			)
			(layer "B.SilkS")
		)
		(fp_poly
			(pts
				(xy 0.635 -0.635) (xy 0.635 0.635) (xy -0.635 0.635) (xy -0.635 -0.635)
			)
			(stroke
				(width 0)
				(type default)
			)
			(fill no)
			(layer "B.CrtYd")
		)
		(pad "1" smd rect
			(at 0 0 180)
			(size 1.27 1.27)
			(layers "B.Cu" "B.Mask" "B.Paste")
			(net "DEBUG_CPLD_PGRM_JTAG_TCK")
		)
	)
	(footprint ""
		(layer "B.Cu")
		(at 75.451005 30.612994)
		(property "Reference" "V_A-CB4"
			(at 0 0 0)
			(layer "B.SilkS")
			(hide yes)
			(effects
				(font
					(size 1.27 1.27)
				)
				(justify mirror)
			)
		)
		(property "Value" ""
			(at 0 0 0)
			(layer "B.Fab")
			(effects
				(font
					(size 1.27 1.27)
				)
				(justify mirror)
			)
		)
		(duplicate_pad_numbers_are_jumpers no)
		(pad "1" thru_hole circle
			(at 0 0 180)
			(size 0.4572 0.4572)
			(drill 0.20574)
			(layers "*.Cu" "*.Mask")
			(remove_unused_layers no)
			(net "DDR0_32A_CB4")
			(clearance 0.1143)
			(thermal_gap 0.1143)
		)
	)
	(footprint ""
		(layer "B.Cu")
		(at 31.877 22.225)
		(property "Reference" "R49"
			(at 0 0 0)
			(layer "B.SilkS")
			(hide yes)
			(effects
				(font
					(size 1.27 1.27)
				)
				(justify mirror)
			)
		)
		(property "Value" "4.75K"
			(at 0.148158 1.3462 270)
			(unlocked yes)
			(layer "B.Fab")
			(hide yes)
			(effects
				(font
					(size 1.27 0.9652)
					(thickness 0.000001)
				)
				(justify left mirror)
			)
		)
		(property "Device Type" "REST4024"
			(at 0.148158 1.3462 270)
			(unlocked yes)
			(layer "B.Fab")
			(hide yes)
			(effects
				(font
					(size 1.27 0.9652)
					(thickness 0.000001)
				)
				(justify left mirror)
			)
		)
		(duplicate_pad_numbers_are_jumpers no)
		(fp_poly
			(pts
				(xy -0.635 1.0668) (xy -0.635 -1.0668) (xy 0.635 -1.0668) (xy 0.635 1.0668)
			)
			(stroke
				(width 0)
				(type default)
			)
			(fill no)
			(layer "B.CrtYd")
		)
		(fp_line
			(start -0.254 -0.508)
			(end -0.254 0.508)
			(stroke
				(width 0.0254)
				(type default)
			)
			(layer "B.Fab")
		)
		(fp_line
			(start -0.254 0.508)
			(end 0.254 0.508)
			(stroke
				(width 0.0254)
				(type default)
			)
			(layer "B.Fab")
		)
		(fp_line
			(start 0.254 -0.508)
			(end -0.254 -0.508)
			(stroke
				(width 0.0254)
				(type default)
			)
			(layer "B.Fab")
		)
		(fp_line
			(start 0.254 0.508)
			(end 0.254 -0.508)
			(stroke
				(width 0.0254)
				(type default)
			)
			(layer "B.Fab")
		)
		(pad "1" smd rect
			(at 0 -0.4191 180)
			(size 0.508 0.5334)
			(layers "B.Cu" "B.Mask" "B.Paste")
			(net "CPLD_VERSION_0")
		)
		(pad "2" smd rect
			(at 0 0.4191 180)
			(size 0.508 0.5334)
			(layers "B.Cu" "B.Mask" "B.Paste")
			(net "GND")
		)
		(zone
			(layer "B.Cu")
			(hatch none 0.5)
			(connect_pads
				(clearance 0)
			)
			(min_thickness 0.25)
			(keepout
				(tracks not_allowed)
				(vias allowed)
				(pads allowed)
				(copperpour not_allowed)
				(footprints allowed)
			)
			(placement
				(enabled no)
				(sheetname "")
			)
			(fill
				(thermal_gap 0.5)
				(thermal_bridge_width 0.5)
				(island_removal_mode 0)
			)
			(polygon
				(pts
					(xy 31.8516 22.1996) (xy 31.8516 22.2504) (xy 31.9024 22.2504) (xy 31.9024 22.1996)
				)
			)
		)
	)
	(footprint ""
		(layer "B.Cu")
		(at 54.737 27.8892 180)
		(property "Reference" "C3"
			(at 1.04267 0.7112 270)
			(unlocked yes)
			(layer "B.SilkS")
			(effects
				(font
					(size 0.7874 0.5842)
					(thickness 0.127)
				)
				(justify left mirror)
			)
		)
		(property "Value" "22UF"
			(at 0.148158 1.7526 90)
			(unlocked yes)
			(layer "B.Fab")
			(hide yes)
			(effects
				(font
					(size 1.27 0.9652)
					(thickness 0.000001)
				)
				(justify left mirror)
			)
		)
		(property "Device Type" "CAPC0063"
			(at 0.148158 1.7526 90)
			(unlocked yes)
			(layer "B.Fab")
			(hide yes)
			(effects
				(font
					(size 1.27 0.9652)
					(thickness 0.000001)
				)
				(justify left mirror)
			)
		)
		(duplicate_pad_numbers_are_jumpers no)
		(fp_circle
			(center 0 0)
			(end -0.127 0)
			(stroke
				(width 0.2032)
				(type default)
			)
			(fill no)
			(layer "B.SilkS")
		)
		(fp_poly
			(pts
				(xy -0.7874 -1.6637) (xy 0.7874 -1.6637) (xy 0.7874 1.6637) (xy -0.7874 1.6637)
			)
			(stroke
				(width 0)
				(type default)
			)
			(fill no)
			(layer "B.CrtYd")
		)
		(fp_line
			(start 0.4064 0.8128)
			(end 0.4064 -0.7874)
			(stroke
				(width 0.0254)
				(type default)
			)
			(layer "B.Fab")
		)
		(fp_line
			(start 0.4064 -0.7874)
			(end -0.4064 -0.7874)
			(stroke
				(width 0.0254)
				(type default)
			)
			(layer "B.Fab")
		)
		(fp_line
			(start -0.4064 0.8128)
			(end 0.4064 0.8128)
			(stroke
				(width 0.0254)
				(type default)
			)
			(layer "B.Fab")
		)
		(fp_line
			(start -0.4064 -0.7874)
			(end -0.4064 0.8128)
			(stroke
				(width 0.0254)
				(type default)
			)
			(layer "B.Fab")
		)
		(pad "1" smd rect
			(at 0 -0.8001)
			(size 0.8636 0.9652)
			(layers "B.Cu" "B.Mask" "B.Paste")
			(net "VDD_CORE")
		)
		(pad "2" smd rect
			(at 0 0.8001)
			(size 0.8636 0.9652)
			(layers "B.Cu" "B.Mask" "B.Paste")
			(net "GND")
		)
		(zone
			(layer "B.Cu")
			(hatch none 0.5)
			(connect_pads
				(clearance 0)
			)
			(min_thickness 0.25)
			(keepout
				(tracks not_allowed)
				(vias allowed)
				(pads allowed)
				(copperpour not_allowed)
				(footprints allowed)
			)
			(placement
				(enabled no)
				(sheetname "")
			)
			(fill
				(thermal_gap 0.5)
				(thermal_bridge_width 0.5)
				(island_removal_mode 0)
			)
			(polygon
				(pts
					(xy 54.6735 28.1432) (xy 54.8005 28.1432) (xy 54.8005 27.6352) (xy 54.6735 27.6352)
				)
			)
		)
	)
	(footprint ""
		(layer "B.Cu")
		(at 57.236995 13.54201)
		(property "Reference" "C161"
			(at -0.494665 2.96799 270)
			(unlocked yes)
			(layer "B.SilkS")
			(effects
				(font
					(size 0.7874 0.5842)
					(thickness 0.127)
				)
				(justify mirror)
			)
		)
		(property "Value" ""
			(at 0 0 0)
			(layer "B.Fab")
			(effects
				(font
					(size 1.27 1.27)
				)
				(justify mirror)
			)
		)
		(duplicate_pad_numbers_are_jumpers no)
		(fp_circle
			(center 0 0)
			(end 0.104648 0)
			(stroke
				(width 0.1016)
				(type default)
			)
			(fill no)
			(layer "B.SilkS")
		)
		(fp_poly
			(pts
				(xy 0.381 -0.889) (xy 0.381 0.889) (xy -0.381 0.889) (xy -0.381 -0.889)
			)
			(stroke
				(width 0)
				(type default)
			)
			(fill no)
			(layer "B.CrtYd")
		)
		(fp_line
			(start -0.508 -1.016)
			(end -0.508 1.016)
			(stroke
				(width 0.0254)
				(type default)
			)
			(layer "B.Fab")
		)
		(fp_line
			(start -0.508 1.016)
			(end 0.508 1.016)
			(stroke
				(width 0.0254)
				(type default)
			)
			(layer "B.Fab")
		)
		(fp_line
			(start 0.254 -1.016)
			(end -0.508 -1.016)
			(stroke
				(width 0.0254)
				(type default)
			)
			(layer "B.Fab")
		)
		(fp_line
			(start 0.508 -1.016)
			(end 0.254 -1.016)
			(stroke
				(width 0.0254)
				(type default)
			)
			(layer "B.Fab")
		)
		(fp_line
			(start 0.508 1.016)
			(end 0.508 -1.016)
			(stroke
				(width 0.0254)
				(type default)
			)
			(layer "B.Fab")
		)
		(pad "1" smd custom
			(at 0 -0.500126 180)
			(size 0.127 0.127)
			(layers "B.Cu" "B.Mask" "B.Paste")
			(net "VDD_CORE")
			(options
				(clearance outline)
				(anchor circle)
			)
			(primitives
				(gr_poly
					(pts
						(xy -0.1778 0.254) (xy 0.1778 0.254) (xy 0.254 0.1778) (xy 0.254 -0.1778) (xy 0.1778 -0.254) (xy -0.1778 -0.254)
						(xy -0.254 -0.1778) (xy -0.254 0.1778)
					)
					(width 0)
					(fill yes)
				)
			)
		)
		(pad "2" smd custom
			(at 0 0.500126 180)
			(size 0.127 0.127)
			(layers "B.Cu" "B.Mask" "B.Paste")
			(net "GND")
			(options
				(clearance outline)
				(anchor circle)
			)
			(primitives
				(gr_poly
					(pts
						(xy -0.1778 0.254) (xy 0.1778 0.254) (xy 0.254 0.1778) (xy 0.254 -0.1778) (xy 0.1778 -0.254) (xy -0.1778 -0.254)
						(xy -0.254 -0.1778) (xy -0.254 0.1778)
					)
					(width 0)
					(fill yes)
				)
			)
		)
	)
	(footprint ""
		(layer "B.Cu")
		(at 35.179 46.736)
		(property "Reference" "TP7"
			(at 0 0 0)
			(layer "B.SilkS")
			(hide yes)
			(effects
				(font
					(size 1.27 1.27)
				)
				(justify mirror)
			)
		)
		(property "Value" "*"
			(at 0.4826 -0.14732 0)
			(unlocked yes)
			(layer "B.Fab")
			(hide yes)
			(effects
				(font
					(size 1.27 0.9652)
					(thickness 0.000001)
				)
				(justify left mirror)
			)
		)
		(property "Device Type" "TP_SMALL"
			(at 0.4826 -0.14732 0)
			(unlocked yes)
			(layer "B.Fab")
			(hide yes)
			(effects
				(font
					(size 1.27 0.9652)
					(thickness 0.000001)
				)
				(justify left mirror)
			)
		)
		(duplicate_pad_numbers_are_jumpers no)
		(fp_line
			(start -0.8636 -0.8636)
			(end 0.8636 -0.8636)
			(stroke
				(width 0.1524)
				(type default)
			)
			(layer "B.SilkS")
		)
		(fp_line
			(start -0.8636 0.8636)
			(end -0.8636 -0.8636)
			(stroke
				(width 0.1524)
				(type default)
			)
			(layer "B.SilkS")
		)
		(fp_line
			(start 0.8636 -0.8636)
			(end 0.8636 0.8636)
			(stroke
				(width 0.1524)
				(type default)
			)
			(layer "B.SilkS")
		)
		(fp_line
			(start 0.8636 0.8636)
			(end -0.8636 0.8636)
			(stroke
				(width 0.1524)
				(type default)
			)
			(layer "B.SilkS")
		)
		(fp_poly
			(pts
				(xy 0.635 -0.635) (xy 0.635 0.635) (xy -0.635 0.635) (xy -0.635 -0.635)
			)
			(stroke
				(width 0)
				(type default)
			)
			(fill no)
			(layer "B.CrtYd")
		)
		(pad "1" smd rect
			(at 0 0 180)
			(size 1.27 1.27)
			(layers "B.Cu" "B.Mask" "B.Paste")
			(net "NFP_JTAG_ARM_TDI")
		)
	)
	(footprint ""
		(layer "B.Cu")
		(at 76.251003 13.456006)
		(property "Reference" "V_A-DQ17"
			(at 0 0 0)
			(layer "B.SilkS")
			(hide yes)
			(effects
				(font
					(size 1.27 1.27)
				)
				(justify mirror)
			)
		)
		(property "Value" ""
			(at 0 0 0)
			(layer "B.Fab")
			(effects
				(font
					(size 1.27 1.27)
				)
				(justify mirror)
			)
		)
		(duplicate_pad_numbers_are_jumpers no)
		(pad "1" thru_hole circle
			(at 0 0 180)
			(size 0.4572 0.4572)
			(drill 0.20574)
			(layers "*.Cu" "*.Mask")
			(remove_unused_layers no)
			(net "DDR0_32A_DQ17")
			(clearance 0.1143)
			(thermal_gap 0.1143)
		)
	)
	(footprint ""
		(layer "B.Cu")
		(at 43.18 46.101)
		(property "Reference" "TP19"
			(at 2.159 -1.49733 0)
			(unlocked yes)
			(layer "B.SilkS")
			(effects
				(font
					(size 0.7874 0.5842)
					(thickness 0.127)
				)
				(justify left mirror)
			)
		)
		(property "Value" "*"
			(at 0.4826 -0.14732 0)
			(unlocked yes)
			(layer "B.Fab")
			(hide yes)
			(effects
				(font
					(size 1.27 0.9652)
					(thickness 0.000001)
				)
				(justify left mirror)
			)
		)
		(property "Device Type" "TP_SMALL"
			(at 0.4826 -0.14732 0)
			(unlocked yes)
			(layer "B.Fab")
			(hide yes)
			(effects
				(font
					(size 1.27 0.9652)
					(thickness 0.000001)
				)
				(justify left mirror)
			)
		)
		(duplicate_pad_numbers_are_jumpers no)
		(fp_line
			(start -0.8636 -0.8636)
			(end 0.8636 -0.8636)
			(stroke
				(width 0.1524)
				(type default)
			)
			(layer "B.SilkS")
		)
		(fp_line
			(start -0.8636 0.8636)
			(end -0.8636 -0.8636)
			(stroke
				(width 0.1524)
				(type default)
			)
			(layer "B.SilkS")
		)
		(fp_line
			(start 0.8636 -0.8636)
			(end 0.8636 0.8636)
			(stroke
				(width 0.1524)
				(type default)
			)
			(layer "B.SilkS")
		)
		(fp_line
			(start 0.8636 0.8636)
			(end -0.8636 0.8636)
			(stroke
				(width 0.1524)
				(type default)
			)
			(layer "B.SilkS")
		)
		(fp_poly
			(pts
				(xy 0.635 -0.635) (xy 0.635 0.635) (xy -0.635 0.635) (xy -0.635 -0.635)
			)
			(stroke
				(width 0)
				(type default)
			)
			(fill no)
			(layer "B.CrtYd")
		)
		(pad "1" smd rect
			(at 0 0 180)
			(size 1.27 1.27)
			(layers "B.Cu" "B.Mask" "B.Paste")
			(net "NFP_UART_SR_TX")
		)
	)
	(footprint ""
		(layer "B.Cu")
		(at 54.737 24.9428 180)
		(property "Reference" "C7"
			(at -0.762 1.87833 0)
			(unlocked yes)
			(layer "B.SilkS")
			(effects
				(font
					(size 0.7874 0.5842)
					(thickness 0.127)
				)
				(justify left mirror)
			)
		)
		(property "Value" "22UF"
			(at 0.148158 1.7526 90)
			(unlocked yes)
			(layer "B.Fab")
			(hide yes)
			(effects
				(font
					(size 1.27 0.9652)
					(thickness 0.000001)
				)
				(justify left mirror)
			)
		)
		(property "Device Type" "CAPC0063"
			(at 0.148158 1.7526 90)
			(unlocked yes)
			(layer "B.Fab")
			(hide yes)
			(effects
				(font
					(size 1.27 0.9652)
					(thickness 0.000001)
				)
				(justify left mirror)
			)
		)
		(duplicate_pad_numbers_are_jumpers no)
		(fp_circle
			(center 0 0)
			(end -0.127 0)
			(stroke
				(width 0.2032)
				(type default)
			)
			(fill no)
			(layer "B.SilkS")
		)
		(fp_poly
			(pts
				(xy -0.7874 -1.6637) (xy 0.7874 -1.6637) (xy 0.7874 1.6637) (xy -0.7874 1.6637)
			)
			(stroke
				(width 0)
				(type default)
			)
			(fill no)
			(layer "B.CrtYd")
		)
		(fp_line
			(start 0.4064 0.8128)
			(end 0.4064 -0.7874)
			(stroke
				(width 0.0254)
				(type default)
			)
			(layer "B.Fab")
		)
		(fp_line
			(start 0.4064 -0.7874)
			(end -0.4064 -0.7874)
			(stroke
				(width 0.0254)
				(type default)
			)
			(layer "B.Fab")
		)
		(fp_line
			(start -0.4064 0.8128)
			(end 0.4064 0.8128)
			(stroke
				(width 0.0254)
				(type default)
			)
			(layer "B.Fab")
		)
		(fp_line
			(start -0.4064 -0.7874)
			(end -0.4064 0.8128)
			(stroke
				(width 0.0254)
				(type default)
			)
			(layer "B.Fab")
		)
		(pad "1" smd rect
			(at 0 -0.8001)
			(size 0.8636 0.9652)
			(layers "B.Cu" "B.Mask" "B.Paste")
			(net "VDD_CORE")
		)
		(pad "2" smd rect
			(at 0 0.8001)
			(size 0.8636 0.9652)
			(layers "B.Cu" "B.Mask" "B.Paste")
			(net "GND")
		)
		(zone
			(layer "B.Cu")
			(hatch none 0.5)
			(connect_pads
				(clearance 0)
			)
			(min_thickness 0.25)
			(keepout
				(tracks not_allowed)
				(vias allowed)
				(pads allowed)
				(copperpour not_allowed)
				(footprints allowed)
			)
			(placement
				(enabled no)
				(sheetname "")
			)
			(fill
				(thermal_gap 0.5)
				(thermal_bridge_width 0.5)
				(island_removal_mode 0)
			)
			(polygon
				(pts
					(xy 54.6735 25.1968) (xy 54.8005 25.1968) (xy 54.8005 24.6888) (xy 54.6735 24.6888)
				)
			)
		)
	)
	(footprint ""
		(layer "B.Cu")
		(at 81.850992 18.255996)
		(property "Reference" "V2_A-A12"
			(at 0 0 0)
			(layer "B.SilkS")
			(hide yes)
			(effects
				(font
					(size 1.27 1.27)
				)
				(justify mirror)
			)
		)
		(property "Value" ""
			(at 0 0 0)
			(layer "B.Fab")
			(effects
				(font
					(size 1.27 1.27)
				)
				(justify mirror)
			)
		)
		(duplicate_pad_numbers_are_jumpers no)
		(pad "1" thru_hole circle
			(at 0 0 180)
			(size 0.4572 0.4572)
			(drill 0.20574)
			(layers "*.Cu" "*.Mask")
			(remove_unused_layers no)
			(net "DDR0_32A_A12")
			(clearance 0.1143)
			(thermal_gap 0.1143)
		)
	)
	(footprint ""
		(layer "B.Cu")
		(at 57.236995 31.541974)
		(property "Reference" "C198"
			(at 0 0 0)
			(layer "B.SilkS")
			(hide yes)
			(effects
				(font
					(size 1.27 1.27)
				)
				(justify mirror)
			)
		)
		(property "Value" ""
			(at 0 0 0)
			(layer "B.Fab")
			(effects
				(font
					(size 1.27 1.27)
				)
				(justify mirror)
			)
		)
		(duplicate_pad_numbers_are_jumpers no)
		(fp_circle
			(center 0 0)
			(end 0.104648 0)
			(stroke
				(width 0.1016)
				(type default)
			)
			(fill no)
			(layer "B.SilkS")
		)
		(fp_poly
			(pts
				(xy 0.381 -0.889) (xy 0.381 0.889) (xy -0.381 0.889) (xy -0.381 -0.889)
			)
			(stroke
				(width 0)
				(type default)
			)
			(fill no)
			(layer "B.CrtYd")
		)
		(fp_line
			(start -0.508 -1.016)
			(end -0.508 1.016)
			(stroke
				(width 0.0254)
				(type default)
			)
			(layer "B.Fab")
		)
		(fp_line
			(start -0.508 1.016)
			(end 0.508 1.016)
			(stroke
				(width 0.0254)
				(type default)
			)
			(layer "B.Fab")
		)
		(fp_line
			(start 0.254 -1.016)
			(end -0.508 -1.016)
			(stroke
				(width 0.0254)
				(type default)
			)
			(layer "B.Fab")
		)
		(fp_line
			(start 0.508 -1.016)
			(end 0.254 -1.016)
			(stroke
				(width 0.0254)
				(type default)
			)
			(layer "B.Fab")
		)
		(fp_line
			(start 0.508 1.016)
			(end 0.508 -1.016)
			(stroke
				(width 0.0254)
				(type default)
			)
			(layer "B.Fab")
		)
		(pad "1" smd custom
			(at 0 -0.500126 180)
			(size 0.127 0.127)
			(layers "B.Cu" "B.Mask" "B.Paste")
			(net "VDD_CORE")
			(options
				(clearance outline)
				(anchor circle)
			)
			(primitives
				(gr_poly
					(pts
						(xy -0.1778 0.254) (xy 0.1778 0.254) (xy 0.254 0.1778) (xy 0.254 -0.1778) (xy 0.1778 -0.254) (xy -0.1778 -0.254)
						(xy -0.254 -0.1778) (xy -0.254 0.1778)
					)
					(width 0)
					(fill yes)
				)
			)
		)
		(pad "2" smd custom
			(at 0 0.500126 180)
			(size 0.127 0.127)
			(layers "B.Cu" "B.Mask" "B.Paste")
			(net "GND")
			(options
				(clearance outline)
				(anchor circle)
			)
			(primitives
				(gr_poly
					(pts
						(xy -0.1778 0.254) (xy 0.1778 0.254) (xy 0.254 0.1778) (xy 0.254 -0.1778) (xy 0.1778 -0.254) (xy -0.1778 -0.254)
						(xy -0.254 -0.1778) (xy -0.254 0.1778)
					)
					(width 0)
					(fill yes)
				)
			)
		)
	)
	(footprint ""
		(layer "B.Cu")
		(at 74.651006 6.698996)
		(property "Reference" "V_A-DM0"
			(at 0 0 0)
			(layer "B.SilkS")
			(hide yes)
			(effects
				(font
					(size 1.27 1.27)
				)
				(justify mirror)
			)
		)
		(property "Value" ""
			(at 0 0 0)
			(layer "B.Fab")
			(effects
				(font
					(size 1.27 1.27)
				)
				(justify mirror)
			)
		)
		(duplicate_pad_numbers_are_jumpers no)
		(pad "1" thru_hole circle
			(at 0 0 180)
			(size 0.4572 0.4572)
			(drill 0.20574)
			(layers "*.Cu" "*.Mask")
			(remove_unused_layers no)
			(net "DDR0_32A_DM0")
			(clearance 0.1143)
			(thermal_gap 0.1143)
		)
	)
	(footprint ""
		(layer "B.Cu")
		(at 41.237027 7.542022 180)
		(property "Reference" "C274"
			(at 1.512697 1.827022 270)
			(unlocked yes)
			(layer "B.SilkS")
			(effects
				(font
					(size 0.7874 0.5842)
					(thickness 0.127)
				)
				(justify mirror)
			)
		)
		(property "Value" ""
			(at 0 0 0)
			(layer "B.Fab")
			(effects
				(font
					(size 1.27 1.27)
				)
				(justify mirror)
			)
		)
		(duplicate_pad_numbers_are_jumpers no)
		(fp_circle
			(center 0 0)
			(end -0.104648 0)
			(stroke
				(width 0.1016)
				(type default)
			)
			(fill no)
			(layer "B.SilkS")
		)
		(fp_poly
			(pts
				(xy 0.381 -0.889) (xy 0.381 0.889) (xy -0.381 0.889) (xy -0.381 -0.889)
			)
			(stroke
				(width 0)
				(type default)
			)
			(fill no)
			(layer "B.CrtYd")
		)
		(fp_line
			(start 0.508 1.016)
			(end 0.508 -1.016)
			(stroke
				(width 0.0254)
				(type default)
			)
			(layer "B.Fab")
		)
		(fp_line
			(start 0.508 -1.016)
			(end 0.254 -1.016)
			(stroke
				(width 0.0254)
				(type default)
			)
			(layer "B.Fab")
		)
		(fp_line
			(start 0.254 -1.016)
			(end -0.508 -1.016)
			(stroke
				(width 0.0254)
				(type default)
			)
			(layer "B.Fab")
		)
		(fp_line
			(start -0.508 1.016)
			(end 0.508 1.016)
			(stroke
				(width 0.0254)
				(type default)
			)
			(layer "B.Fab")
		)
		(fp_line
			(start -0.508 -1.016)
			(end -0.508 1.016)
			(stroke
				(width 0.0254)
				(type default)
			)
			(layer "B.Fab")
		)
		(pad "1" smd custom
			(at 0 -0.500126)
			(size 0.127 0.127)
			(layers "B.Cu" "B.Mask" "B.Paste")
			(net "VDD_1.2V")
			(options
				(clearance outline)
				(anchor circle)
			)
			(primitives
				(gr_poly
					(pts
						(xy -0.1778 0.254) (xy 0.1778 0.254) (xy 0.254 0.1778) (xy 0.254 -0.1778) (xy 0.1778 -0.254) (xy -0.1778 -0.254)
						(xy -0.254 -0.1778) (xy -0.254 0.1778)
					)
					(width 0)
					(fill yes)
				)
			)
		)
		(pad "2" smd custom
			(at 0 0.500126)
			(size 0.127 0.127)
			(layers "B.Cu" "B.Mask" "B.Paste")
			(net "GND")
			(options
				(clearance outline)
				(anchor circle)
			)
			(primitives
				(gr_poly
					(pts
						(xy -0.1778 0.254) (xy 0.1778 0.254) (xy 0.254 0.1778) (xy 0.254 -0.1778) (xy 0.1778 -0.254) (xy -0.1778 -0.254)
						(xy -0.254 -0.1778) (xy -0.254 0.1778)
					)
					(width 0)
					(fill yes)
				)
			)
		)
	)
	(footprint ""
		(layer "B.Cu")
		(at 39.237031 24.541988)
		(property "Reference" "C74"
			(at 0 0 0)
			(layer "B.SilkS")
			(hide yes)
			(effects
				(font
					(size 1.27 1.27)
				)
				(justify mirror)
			)
		)
		(property "Value" ""
			(at 0 0 0)
			(layer "B.Fab")
			(effects
				(font
					(size 1.27 1.27)
				)
				(justify mirror)
			)
		)
		(duplicate_pad_numbers_are_jumpers no)
		(fp_circle
			(center 0 0)
			(end 0.104648 0)
			(stroke
				(width 0.1016)
				(type default)
			)
			(fill no)
			(layer "B.SilkS")
		)
		(fp_poly
			(pts
				(xy 0.381 -0.889) (xy 0.381 0.889) (xy -0.381 0.889) (xy -0.381 -0.889)
			)
			(stroke
				(width 0)
				(type default)
			)
			(fill no)
			(layer "B.CrtYd")
		)
		(fp_line
			(start -0.508 -1.016)
			(end -0.508 1.016)
			(stroke
				(width 0.0254)
				(type default)
			)
			(layer "B.Fab")
		)
		(fp_line
			(start -0.508 1.016)
			(end 0.508 1.016)
			(stroke
				(width 0.0254)
				(type default)
			)
			(layer "B.Fab")
		)
		(fp_line
			(start 0.254 -1.016)
			(end -0.508 -1.016)
			(stroke
				(width 0.0254)
				(type default)
			)
			(layer "B.Fab")
		)
		(fp_line
			(start 0.508 -1.016)
			(end 0.254 -1.016)
			(stroke
				(width 0.0254)
				(type default)
			)
			(layer "B.Fab")
		)
		(fp_line
			(start 0.508 1.016)
			(end 0.508 -1.016)
			(stroke
				(width 0.0254)
				(type default)
			)
			(layer "B.Fab")
		)
		(pad "1" smd custom
			(at 0 -0.500126 180)
			(size 0.127 0.127)
			(layers "B.Cu" "B.Mask" "B.Paste")
			(net "VDDA_TS0")
			(options
				(clearance outline)
				(anchor circle)
			)
			(primitives
				(gr_poly
					(pts
						(xy -0.1778 0.254) (xy 0.1778 0.254) (xy 0.254 0.1778) (xy 0.254 -0.1778) (xy 0.1778 -0.254) (xy -0.1778 -0.254)
						(xy -0.254 -0.1778) (xy -0.254 0.1778)
					)
					(width 0)
					(fill yes)
				)
			)
		)
		(pad "2" smd custom
			(at 0 0.500126 180)
			(size 0.127 0.127)
			(layers "B.Cu" "B.Mask" "B.Paste")
			(net "GND")
			(options
				(clearance outline)
				(anchor circle)
			)
			(primitives
				(gr_poly
					(pts
						(xy -0.1778 0.254) (xy 0.1778 0.254) (xy 0.254 0.1778) (xy 0.254 -0.1778) (xy 0.1778 -0.254) (xy -0.1778 -0.254)
						(xy -0.254 -0.1778) (xy -0.254 0.1778)
					)
					(width 0)
					(fill yes)
				)
			)
		)
	)
	(footprint ""
		(layer "B.Cu")
		(at 83.450989 6.698996)
		(property "Reference" "V1_A-A11"
			(at 0 0 0)
			(layer "B.SilkS")
			(hide yes)
			(effects
				(font
					(size 1.27 1.27)
				)
				(justify mirror)
			)
		)
		(property "Value" ""
			(at 0 0 0)
			(layer "B.Fab")
			(effects
				(font
					(size 1.27 1.27)
				)
				(justify mirror)
			)
		)
		(duplicate_pad_numbers_are_jumpers no)
		(pad "1" thru_hole circle
			(at 0 0 180)
			(size 0.4572 0.4572)
			(drill 0.20574)
			(layers "*.Cu" "*.Mask")
			(remove_unused_layers no)
			(net "DDR0_32A_A11")
			(clearance 0.1143)
			(thermal_gap 0.1143)
		)
	)
	(footprint ""
		(layer "B.Cu")
		(at 73.851008 5.898998)
		(property "Reference" "V_A-DQS1-P"
			(at 0 0 0)
			(layer "B.SilkS")
			(hide yes)
			(effects
				(font
					(size 1.27 1.27)
				)
				(justify mirror)
			)
		)
		(property "Value" ""
			(at 0 0 0)
			(layer "B.Fab")
			(effects
				(font
					(size 1.27 1.27)
				)
				(justify mirror)
			)
		)
		(duplicate_pad_numbers_are_jumpers no)
		(pad "1" thru_hole circle
			(at 0 0 180)
			(size 0.4572 0.4572)
			(drill 0.20574)
			(layers "*.Cu" "*.Mask")
			(remove_unused_layers no)
			(net "DDR0_32A_DQS1_P")
			(clearance 0.1143)
			(thermal_gap 0.1143)
		)
	)
	(footprint ""
		(layer "B.Cu")
		(at 31.877 32.639)
		(property "Reference" "R174"
			(at -0.02667 4.953 270)
			(unlocked yes)
			(layer "B.SilkS")
			(effects
				(font
					(size 0.7874 0.5842)
					(thickness 0.127)
				)
				(justify left mirror)
			)
		)
		(property "Value" "0"
			(at 0.148158 1.3462 270)
			(unlocked yes)
			(layer "B.Fab")
			(hide yes)
			(effects
				(font
					(size 1.27 0.9652)
					(thickness 0.000001)
				)
				(justify left mirror)
			)
		)
		(property "Device Type" "REST1111"
			(at 0.148158 1.3462 270)
			(unlocked yes)
			(layer "B.Fab")
			(hide yes)
			(effects
				(font
					(size 1.27 0.9652)
					(thickness 0.000001)
				)
				(justify left mirror)
			)
		)
		(duplicate_pad_numbers_are_jumpers no)
		(fp_poly
			(pts
				(xy -0.635 1.0668) (xy -0.635 -1.0668) (xy 0.635 -1.0668) (xy 0.635 1.0668)
			)
			(stroke
				(width 0)
				(type default)
			)
			(fill no)
			(layer "B.CrtYd")
		)
		(fp_line
			(start -0.254 -0.508)
			(end -0.254 0.508)
			(stroke
				(width 0.0254)
				(type default)
			)
			(layer "B.Fab")
		)
		(fp_line
			(start -0.254 0.508)
			(end 0.254 0.508)
			(stroke
				(width 0.0254)
				(type default)
			)
			(layer "B.Fab")
		)
		(fp_line
			(start 0.254 -0.508)
			(end -0.254 -0.508)
			(stroke
				(width 0.0254)
				(type default)
			)
			(layer "B.Fab")
		)
		(fp_line
			(start 0.254 0.508)
			(end 0.254 -0.508)
			(stroke
				(width 0.0254)
				(type default)
			)
			(layer "B.Fab")
		)
		(pad "1" smd rect
			(at 0 -0.4191 180)
			(size 0.508 0.5334)
			(layers "B.Cu" "B.Mask" "B.Paste")
			(net "NFP_CORE_VID4")
		)
		(pad "2" smd rect
			(at 0 0.4191 180)
			(size 0.508 0.5334)
			(layers "B.Cu" "B.Mask" "B.Paste")
			(net "_NFP_CORE_VID4")
		)
		(zone
			(layer "B.Cu")
			(hatch none 0.5)
			(connect_pads
				(clearance 0)
			)
			(min_thickness 0.25)
			(keepout
				(tracks not_allowed)
				(vias allowed)
				(pads allowed)
				(copperpour not_allowed)
				(footprints allowed)
			)
			(placement
				(enabled no)
				(sheetname "")
			)
			(fill
				(thermal_gap 0.5)
				(thermal_bridge_width 0.5)
				(island_removal_mode 0)
			)
			(polygon
				(pts
					(xy 31.8516 32.6136) (xy 31.8516 32.6644) (xy 31.9024 32.6644) (xy 31.9024 32.6136)
				)
			)
		)
	)
	(footprint ""
		(layer "B.Cu")
		(at 77.851 16.256 90)
		(property "Reference" "U18"
			(at 5.2705 6.858 0)
			(unlocked yes)
			(layer "B.SilkS")
			(effects
				(font
					(size 1.27 0.9652)
					(thickness 0.1524)
				)
				(justify left mirror)
			)
		)
		(property "Value" ""
			(at 0 0 90)
			(layer "B.Fab")
			(effects
				(font
					(size 1.27 1.27)
				)
				(justify mirror)
			)
		)
		(property "Component Value" "VALUE"
			(at 0.399999 -9.402597 90)
			(unlocked yes)
			(layer "User.4")
			(effects
				(font
					(size 0.254 0.254)
					(thickness 0.000001)
				)
				(justify mirror)
			)
		)
		(property "Device Type" "MEMC0051"
			(at 5.909996 -11.648211 90)
			(unlocked yes)
			(layer "B.Fab")
			(hide yes)
			(effects
				(font
					(size 1.27 0.9652)
					(thickness 0.000001)
				)
				(justify left mirror)
			)
		)
		(duplicate_pad_numbers_are_jumpers no)
		(fp_line
			(start 4.499991 -7.000011)
			(end 4.499991 7.000011)
			(stroke
				(width 0.1524)
				(type default)
			)
			(layer "B.SilkS")
		)
		(fp_line
			(start -4.499991 -7.000011)
			(end 4.499991 -7.000011)
			(stroke
				(width 0.1524)
				(type default)
			)
			(layer "B.SilkS")
		)
		(fp_line
			(start 4.499991 -5.999988)
			(end 3.499993 -7.000011)
			(stroke
				(width 0.1524)
				(type default)
			)
			(layer "B.SilkS")
		)
		(fp_line
			(start 4.499991 7.000011)
			(end -4.499991 7.000011)
			(stroke
				(width 0.1524)
				(type default)
			)
			(layer "B.SilkS")
		)
		(fp_line
			(start -4.499991 7.000011)
			(end -4.499991 -7.000011)
			(stroke
				(width 0.1524)
				(type default)
			)
			(layer "B.SilkS")
		)
		(fp_poly
			(pts
				(xy 7.50001 10.000005) (xy -7.50001 10.000005) (xy -7.50001 -10.000005) (xy 7.50001 -10.000005)
			)
			(stroke
				(width 0)
				(type default)
			)
			(fill no)
			(layer "B.CrtYd")
		)
		(fp_line
			(start 4.499991 -7.000011)
			(end 4.499991 7.000011)
			(stroke
				(width 0.1)
				(type default)
			)
			(layer "B.Fab")
		)
		(fp_line
			(start -4.499991 -7.000011)
			(end 4.499991 -7.000011)
			(stroke
				(width 0.1)
				(type default)
			)
			(layer "B.Fab")
		)
		(fp_line
			(start 4.499991 -5.999988)
			(end 3.499993 -7.000011)
			(stroke
				(width 0.1)
				(type default)
			)
			(layer "B.Fab")
		)
		(fp_line
			(start 4.499991 7.000011)
			(end -4.499991 7.000011)
			(stroke
				(width 0.1)
				(type default)
			)
			(layer "B.Fab")
		)
		(fp_line
			(start -4.499991 7.000011)
			(end -4.499991 -7.000011)
			(stroke
				(width 0.1)
				(type default)
			)
			(layer "B.Fab")
		)
		(fp_text user "1"
			(at 3.40233 -7.493 0)
			(unlocked yes)
			(layer "B.SilkS")
			(effects
				(font
					(size 0.7874 0.5842)
					(thickness 0.127)
				)
				(justify mirror)
			)
		)
		(fp_text user "A"
			(at 5.18033 -5.842 0)
			(unlocked yes)
			(layer "B.SilkS")
			(effects
				(font
					(size 0.7874 0.5842)
					(thickness 0.127)
				)
				(justify mirror)
			)
		)
		(pad "A1" smd circle
			(at 3.199994 -5.999988 270)
			(size 0.3556 0.3556)
			(layers "B.Cu" "B.Mask" "B.Paste")
			(net "DDR_VDDQ")
		)
		(pad "A2" smd circle
			(at 2.399995 -5.999988 270)
			(size 0.3556 0.3556)
			(layers "B.Cu" "B.Mask" "B.Paste")
			(net "DDR0_32A_DQ24")
		)
		(pad "A3" smd circle
			(at 1.599997 -5.999988 270)
			(size 0.3556 0.3556)
			(layers "B.Cu" "B.Mask" "B.Paste")
			(net "DDR0_32A_DQ29")
		)
		(pad "A7" smd circle
			(at -1.599997 -5.999988 270)
			(size 0.3556 0.3556)
			(layers "B.Cu" "B.Mask" "B.Paste")
			(net "DDR0_32A_DQ26")
		)
		(pad "A8" smd circle
			(at -2.399995 -5.999988 270)
			(size 0.3556 0.3556)
			(layers "B.Cu" "B.Mask" "B.Paste")
			(net "DDR_VDDQ")
		)
		(pad "A9" smd circle
			(at -3.199994 -5.999988 270)
			(size 0.3556 0.3556)
			(layers "B.Cu" "B.Mask" "B.Paste")
			(net "GND")
		)
		(pad "B1" smd circle
			(at 3.199994 -5.19999 270)
			(size 0.3556 0.3556)
			(layers "B.Cu" "B.Mask" "B.Paste")
			(net "GND")
		)
		(pad "B2" smd circle
			(at 2.399995 -5.19999 270)
			(size 0.3556 0.3556)
			(layers "B.Cu" "B.Mask" "B.Paste")
			(net "DDR_VDDQ")
		)
		(pad "B3" smd circle
			(at 1.599997 -5.19999 270)
			(size 0.3556 0.3556)
			(layers "B.Cu" "B.Mask" "B.Paste")
			(net "GND")
		)
		(pad "B7" smd circle
			(at -1.599997 -5.19999 270)
			(size 0.3556 0.3556)
			(layers "B.Cu" "B.Mask" "B.Paste")
			(net "DDR0_32A_DQS3_N")
		)
		(pad "B8" smd circle
			(at -2.399995 -5.19999 270)
			(size 0.3556 0.3556)
			(layers "B.Cu" "B.Mask" "B.Paste")
			(net "DDR0_32A_DQ28")
		)
		(pad "B9" smd circle
			(at -3.199994 -5.19999 270)
			(size 0.3556 0.3556)
			(layers "B.Cu" "B.Mask" "B.Paste")
			(net "GND")
		)
		(pad "C1" smd circle
			(at 3.199994 -4.399991 270)
			(size 0.3556 0.3556)
			(layers "B.Cu" "B.Mask" "B.Paste")
			(net "DDR_VDDQ")
		)
		(pad "C2" smd circle
			(at 2.399995 -4.399991 270)
			(size 0.3556 0.3556)
			(layers "B.Cu" "B.Mask" "B.Paste")
			(net "DDR0_32A_DQ31")
		)
		(pad "C3" smd circle
			(at 1.599997 -4.399991 270)
			(size 0.3556 0.3556)
			(layers "B.Cu" "B.Mask" "B.Paste")
			(net "DDR0_32A_DQ30")
		)
		(pad "C7" smd circle
			(at -1.599997 -4.399991 270)
			(size 0.3556 0.3556)
			(layers "B.Cu" "B.Mask" "B.Paste")
			(net "DDR0_32A_DQS3_P")
		)
		(pad "C8" smd circle
			(at -2.399995 -4.399991 270)
			(size 0.3556 0.3556)
			(layers "B.Cu" "B.Mask" "B.Paste")
			(net "DDR0_32A_DQ25")
		)
		(pad "C9" smd circle
			(at -3.199994 -4.399991 270)
			(size 0.3556 0.3556)
			(layers "B.Cu" "B.Mask" "B.Paste")
			(net "DDR_VDDQ")
		)
		(pad "D1" smd circle
			(at 3.199994 -3.599993 270)
			(size 0.3556 0.3556)
			(layers "B.Cu" "B.Mask" "B.Paste")
			(net "GND")
		)
		(pad "D2" smd circle
			(at 2.399995 -3.599993 270)
			(size 0.3556 0.3556)
			(layers "B.Cu" "B.Mask" "B.Paste")
			(net "DDR_VDDQ")
		)
		(pad "D3" smd circle
			(at 1.599997 -3.599993 270)
			(size 0.3556 0.3556)
			(layers "B.Cu" "B.Mask" "B.Paste")
			(net "DDR0_32A_DM3")
		)
		(pad "D7" smd circle
			(at -1.599997 -3.599993 270)
			(size 0.3556 0.3556)
			(layers "B.Cu" "B.Mask" "B.Paste")
			(net "DDR0_32A_DQ27")
		)
		(pad "D8" smd circle
			(at -2.399995 -3.599993 270)
			(size 0.3556 0.3556)
			(layers "B.Cu" "B.Mask" "B.Paste")
			(net "GND")
		)
		(pad "D9" smd circle
			(at -3.199994 -3.599993 270)
			(size 0.3556 0.3556)
			(layers "B.Cu" "B.Mask" "B.Paste")
			(net "DDR_VDDQ")
		)
		(pad "E1" smd circle
			(at 3.199994 -2.799994 270)
			(size 0.3556 0.3556)
			(layers "B.Cu" "B.Mask" "B.Paste")
			(net "GND")
		)
		(pad "E2" smd circle
			(at 2.399995 -2.799994 270)
			(size 0.3556 0.3556)
			(layers "B.Cu" "B.Mask" "B.Paste")
			(net "GND")
		)
		(pad "E3" smd circle
			(at 1.599997 -2.799994 270)
			(size 0.3556 0.3556)
			(layers "B.Cu" "B.Mask" "B.Paste")
			(net "DDR0_32A_DQ16")
		)
		(pad "E7" smd circle
			(at -1.599997 -2.799994 270)
			(size 0.3556 0.3556)
			(layers "B.Cu" "B.Mask" "B.Paste")
			(net "DDR0_32A_DM2")
		)
		(pad "E8" smd circle
			(at -2.399995 -2.799994 270)
			(size 0.3556 0.3556)
			(layers "B.Cu" "B.Mask" "B.Paste")
			(net "GND")
		)
		(pad "E9" smd circle
			(at -3.199994 -2.799994 270)
			(size 0.3556 0.3556)
			(layers "B.Cu" "B.Mask" "B.Paste")
			(net "DDR_VDDQ")
		)
		(pad "F1" smd circle
			(at 3.199994 -1.999996 270)
			(size 0.3556 0.3556)
			(layers "B.Cu" "B.Mask" "B.Paste")
			(net "DDR_VDDQ")
		)
		(pad "F2" smd circle
			(at 2.399995 -1.999996 270)
			(size 0.3556 0.3556)
			(layers "B.Cu" "B.Mask" "B.Paste")
			(net "DDR0_32A_DQ21")
		)
		(pad "F3" smd circle
			(at 1.599997 -1.999996 270)
			(size 0.3556 0.3556)
			(layers "B.Cu" "B.Mask" "B.Paste")
			(net "DDR0_32A_DQS2_P")
		)
		(pad "F7" smd circle
			(at -1.599997 -1.999996 270)
			(size 0.3556 0.3556)
			(layers "B.Cu" "B.Mask" "B.Paste")
			(net "DDR0_32A_DQ18")
		)
		(pad "F8" smd circle
			(at -2.399995 -1.999996 270)
			(size 0.3556 0.3556)
			(layers "B.Cu" "B.Mask" "B.Paste")
			(net "DDR0_32A_DQ20")
		)
		(pad "F9" smd circle
			(at -3.199994 -1.999996 270)
			(size 0.3556 0.3556)
			(layers "B.Cu" "B.Mask" "B.Paste")
			(net "GND")
		)
		(pad "G1" smd circle
			(at 3.199994 -1.199998 270)
			(size 0.3556 0.3556)
			(layers "B.Cu" "B.Mask" "B.Paste")
			(net "GND")
		)
		(pad "G2" smd circle
			(at 2.399995 -1.199998 270)
			(size 0.3556 0.3556)
			(layers "B.Cu" "B.Mask" "B.Paste")
			(net "DDR0_32A_DQ17")
		)
		(pad "G3" smd circle
			(at 1.599997 -1.199998 270)
			(size 0.3556 0.3556)
			(layers "B.Cu" "B.Mask" "B.Paste")
			(net "DDR0_32A_DQS2_N")
		)
		(pad "G7" smd circle
			(at -1.599997 -1.199998 270)
			(size 0.3556 0.3556)
			(layers "B.Cu" "B.Mask" "B.Paste")
			(net "DDR_VDDQ")
		)
		(pad "G8" smd circle
			(at -2.399995 -1.199998 270)
			(size 0.3556 0.3556)
			(layers "B.Cu" "B.Mask" "B.Paste")
			(net "GND")
		)
		(pad "G9" smd circle
			(at -3.199994 -1.199998 270)
			(size 0.3556 0.3556)
			(layers "B.Cu" "B.Mask" "B.Paste")
			(net "GND")
		)
		(pad "H1" smd circle
			(at 3.199994 -0.399999 270)
			(size 0.3556 0.3556)
			(layers "B.Cu" "B.Mask" "B.Paste")
			(net "DDR0_32A_VREF1B")
		)
		(pad "H2" smd circle
			(at 2.399995 -0.399999 270)
			(size 0.3556 0.3556)
			(layers "B.Cu" "B.Mask" "B.Paste")
			(net "DDR_VDDQ")
		)
		(pad "H3" smd circle
			(at 1.599997 -0.399999 270)
			(size 0.3556 0.3556)
			(layers "B.Cu" "B.Mask" "B.Paste")
			(net "DDR0_32A_DQ19")
		)
		(pad "H7" smd circle
			(at -1.599997 -0.399999 270)
			(size 0.3556 0.3556)
			(layers "B.Cu" "B.Mask" "B.Paste")
			(net "DDR0_32A_DQ23")
		)
		(pad "H8" smd circle
			(at -2.399995 -0.399999 270)
			(size 0.3556 0.3556)
			(layers "B.Cu" "B.Mask" "B.Paste")
			(net "DDR0_32A_DQ22")
		)
		(pad "H9" smd circle
			(at -3.199994 -0.399999 270)
			(size 0.3556 0.3556)
			(layers "B.Cu" "B.Mask" "B.Paste")
			(net "DDR_VDDQ")
		)
		(pad "J1" smd circle
			(at 3.199994 0.399999 270)
			(size 0.3556 0.3556)
			(layers "B.Cu" "B.Mask" "B.Paste")
			(net "Net_92")
		)
		(pad "J2" smd circle
			(at 2.399995 0.399999 270)
			(size 0.3556 0.3556)
			(layers "B.Cu" "B.Mask" "B.Paste")
			(net "GND")
		)
		(pad "J3" smd circle
			(at 1.599997 0.399999 270)
			(size 0.3556 0.3556)
			(layers "B.Cu" "B.Mask" "B.Paste")
			(net "DDR0_32A_RAS_L")
		)
		(pad "J7" smd circle
			(at -1.599997 0.399999 270)
			(size 0.3556 0.3556)
			(layers "B.Cu" "B.Mask" "B.Paste")
			(net "DDR0_32A_CK0_P")
		)
		(pad "J8" smd circle
			(at -2.399995 0.399999 270)
			(size 0.3556 0.3556)
			(layers "B.Cu" "B.Mask" "B.Paste")
			(net "GND")
		)
		(pad "J9" smd circle
			(at -3.199994 0.399999 270)
			(size 0.3556 0.3556)
			(layers "B.Cu" "B.Mask" "B.Paste")
			(net "Net_500")
		)
		(pad "K1" smd circle
			(at 3.199994 1.199998 270)
			(size 0.3556 0.3556)
			(layers "B.Cu" "B.Mask" "B.Paste")
			(net "DDR0_32A_ODT0")
		)
		(pad "K2" smd circle
			(at 2.399995 1.199998 270)
			(size 0.3556 0.3556)
			(layers "B.Cu" "B.Mask" "B.Paste")
			(net "DDR_VDDQ")
		)
		(pad "K3" smd circle
			(at 1.599997 1.199998 270)
			(size 0.3556 0.3556)
			(layers "B.Cu" "B.Mask" "B.Paste")
			(net "DDR0_32A_CAS_L")
		)
		(pad "K7" smd circle
			(at -1.599997 1.199998 270)
			(size 0.3556 0.3556)
			(layers "B.Cu" "B.Mask" "B.Paste")
			(net "DDR0_32A_CK0_N")
		)
		(pad "K8" smd circle
			(at -2.399995 1.199998 270)
			(size 0.3556 0.3556)
			(layers "B.Cu" "B.Mask" "B.Paste")
			(net "DDR_VDDQ")
		)
		(pad "K9" smd circle
			(at -3.199994 1.199998 270)
			(size 0.3556 0.3556)
			(layers "B.Cu" "B.Mask" "B.Paste")
			(net "DDR0_32A_CKE0")
		)
		(pad "L1" smd circle
			(at 3.199994 1.999996 270)
			(size 0.3556 0.3556)
			(layers "B.Cu" "B.Mask" "B.Paste")
			(net "Net_498")
		)
		(pad "L2" smd circle
			(at 2.399995 1.999996 270)
			(size 0.3556 0.3556)
			(layers "B.Cu" "B.Mask" "B.Paste")
			(net "DDR0_32A_CS0_L")
		)
		(pad "L3" smd circle
			(at 1.599997 1.999996 270)
			(size 0.3556 0.3556)
			(layers "B.Cu" "B.Mask" "B.Paste")
			(net "DDR0_32A_WE_L")
		)
		(pad "L7" smd circle
			(at -1.599997 1.999996 270)
			(size 0.3556 0.3556)
			(layers "B.Cu" "B.Mask" "B.Paste")
			(net "DDR0_32A_A10")
		)
		(pad "L8" smd circle
			(at -2.399995 1.999996 270)
			(size 0.3556 0.3556)
			(layers "B.Cu" "B.Mask" "B.Paste")
			(net "12N3057")
		)
		(pad "L9" smd circle
			(at -3.199994 1.999996 270)
			(size 0.3556 0.3556)
			(layers "B.Cu" "B.Mask" "B.Paste")
			(net "Net_501")
		)
		(pad "M1" smd circle
			(at 3.199994 2.799994 270)
			(size 0.3556 0.3556)
			(layers "B.Cu" "B.Mask" "B.Paste")
			(net "GND")
		)
		(pad "M2" smd circle
			(at 2.399995 2.799994 270)
			(size 0.3556 0.3556)
			(layers "B.Cu" "B.Mask" "B.Paste")
			(net "DDR0_32A_BA0")
		)
		(pad "M3" smd circle
			(at 1.599997 2.799994 270)
			(size 0.3556 0.3556)
			(layers "B.Cu" "B.Mask" "B.Paste")
			(net "DDR0_32A_BA2")
		)
		(pad "M7" smd circle
			(at -1.599997 2.799994 270)
			(size 0.3556 0.3556)
			(layers "B.Cu" "B.Mask" "B.Paste")
			(net "Net_499")
		)
		(pad "M8" smd circle
			(at -2.399995 2.799994 270)
			(size 0.3556 0.3556)
			(layers "B.Cu" "B.Mask" "B.Paste")
			(net "DDR0_32A_VREF1B")
		)
		(pad "M9" smd circle
			(at -3.199994 2.799994 270)
			(size 0.3556 0.3556)
			(layers "B.Cu" "B.Mask" "B.Paste")
			(net "GND")
		)
		(pad "N1" smd circle
			(at 3.199994 3.599993 270)
			(size 0.3556 0.3556)
			(layers "B.Cu" "B.Mask" "B.Paste")
			(net "DDR_VDDQ")
		)
		(pad "N2" smd circle
			(at 2.399995 3.599993 270)
			(size 0.3556 0.3556)
			(layers "B.Cu" "B.Mask" "B.Paste")
			(net "DDR0_32A_A3")
		)
		(pad "N3" smd circle
			(at 1.599997 3.599993 270)
			(size 0.3556 0.3556)
			(layers "B.Cu" "B.Mask" "B.Paste")
			(net "DDR0_32A_A0")
		)
		(pad "N7" smd circle
			(at -1.599997 3.599993 270)
			(size 0.3556 0.3556)
			(layers "B.Cu" "B.Mask" "B.Paste")
			(net "DDR0_32A_A12")
		)
		(pad "N8" smd circle
			(at -2.399995 3.599993 270)
			(size 0.3556 0.3556)
			(layers "B.Cu" "B.Mask" "B.Paste")
			(net "DDR0_32A_BA1")
		)
		(pad "N9" smd circle
			(at -3.199994 3.599993 270)
			(size 0.3556 0.3556)
			(layers "B.Cu" "B.Mask" "B.Paste")
			(net "DDR_VDDQ")
		)
		(pad "P1" smd circle
			(at 3.199994 4.399991 270)
			(size 0.3556 0.3556)
			(layers "B.Cu" "B.Mask" "B.Paste")
			(net "GND")
		)
		(pad "P2" smd circle
			(at 2.399995 4.399991 270)
			(size 0.3556 0.3556)
			(layers "B.Cu" "B.Mask" "B.Paste")
			(net "DDR0_32A_A5")
		)
		(pad "P3" smd circle
			(at 1.599997 4.399991 270)
			(size 0.3556 0.3556)
			(layers "B.Cu" "B.Mask" "B.Paste")
			(net "DDR0_32A_A2")
		)
		(pad "P7" smd circle
			(at -1.599997 4.399991 270)
			(size 0.3556 0.3556)
			(layers "B.Cu" "B.Mask" "B.Paste")
			(net "DDR0_32A_A1")
		)
		(pad "P8" smd circle
			(at -2.399995 4.399991 270)
			(size 0.3556 0.3556)
			(layers "B.Cu" "B.Mask" "B.Paste")
			(net "DDR0_32A_A4")
		)
		(pad "P9" smd circle
			(at -3.199994 4.399991 270)
			(size 0.3556 0.3556)
			(layers "B.Cu" "B.Mask" "B.Paste")
			(net "GND")
		)
		(pad "R1" smd circle
			(at 3.199994 5.19999 270)
			(size 0.3556 0.3556)
			(layers "B.Cu" "B.Mask" "B.Paste")
			(net "DDR_VDDQ")
		)
		(pad "R2" smd circle
			(at 2.399995 5.19999 270)
			(size 0.3556 0.3556)
			(layers "B.Cu" "B.Mask" "B.Paste")
			(net "DDR0_32A_A7")
		)
		(pad "R3" smd circle
			(at 1.599997 5.19999 270)
			(size 0.3556 0.3556)
			(layers "B.Cu" "B.Mask" "B.Paste")
			(net "DDR0_32A_A9")
		)
		(pad "R7" smd circle
			(at -1.599997 5.19999 270)
			(size 0.3556 0.3556)
			(layers "B.Cu" "B.Mask" "B.Paste")
			(net "DDR0_32A_A11")
		)
		(pad "R8" smd circle
			(at -2.399995 5.19999 270)
			(size 0.3556 0.3556)
			(layers "B.Cu" "B.Mask" "B.Paste")
			(net "DDR0_32A_A6")
		)
		(pad "R9" smd circle
			(at -3.199994 5.19999 270)
			(size 0.3556 0.3556)
			(layers "B.Cu" "B.Mask" "B.Paste")
			(net "DDR_VDDQ")
		)
		(pad "T1" smd circle
			(at 3.199994 5.999988 270)
			(size 0.3556 0.3556)
			(layers "B.Cu" "B.Mask" "B.Paste")
			(net "GND")
		)
		(pad "T2" smd circle
			(at 2.399995 5.999988 270)
			(size 0.3556 0.3556)
			(layers "B.Cu" "B.Mask" "B.Paste")
			(net "DDR0_32A_DRAMRST_L")
		)
		(pad "T3" smd circle
			(at 1.599997 5.999988 270)
			(size 0.3556 0.3556)
			(layers "B.Cu" "B.Mask" "B.Paste")
			(net "DDR0_32A_A13")
		)
		(pad "T7" smd circle
			(at -1.599997 5.999988 270)
			(size 0.3556 0.3556)
			(layers "B.Cu" "B.Mask" "B.Paste")
			(net "DDR0_32A_A14")
		)
		(pad "T8" smd circle
			(at -2.399995 5.999988 270)
			(size 0.3556 0.3556)
			(layers "B.Cu" "B.Mask" "B.Paste")
			(net "DDR0_32A_A8")
		)
		(pad "T9" smd circle
			(at -3.199994 5.999988 270)
			(size 0.3556 0.3556)
			(layers "B.Cu" "B.Mask" "B.Paste")
			(net "GND")
		)
	)
	(footprint ""
		(layer "B.Cu")
		(at 42.237152 21.542121 180)
		(property "Reference" "R409"
			(at 0 0 0)
			(layer "B.SilkS")
			(hide yes)
			(effects
				(font
					(size 1.27 1.27)
				)
				(justify mirror)
			)
		)
		(property "Value" ""
			(at 0 0 0)
			(layer "B.Fab")
			(effects
				(font
					(size 1.27 1.27)
				)
				(justify mirror)
			)
		)
		(duplicate_pad_numbers_are_jumpers no)
		(fp_circle
			(center 0 0)
			(end -0.104648 0)
			(stroke
				(width 0.1016)
				(type default)
			)
			(fill no)
			(layer "B.SilkS")
		)
		(fp_poly
			(pts
				(xy 0.381 -0.889) (xy 0.381 0.889) (xy -0.381 0.889) (xy -0.381 -0.889)
			)
			(stroke
				(width 0)
				(type default)
			)
			(fill no)
			(layer "B.CrtYd")
		)
		(fp_line
			(start 0.508 1.016)
			(end 0.508 -1.016)
			(stroke
				(width 0.0254)
				(type default)
			)
			(layer "B.Fab")
		)
		(fp_line
			(start 0.508 -1.016)
			(end 0.254 -1.016)
			(stroke
				(width 0.0254)
				(type default)
			)
			(layer "B.Fab")
		)
		(fp_line
			(start 0.254 -1.016)
			(end -0.508 -1.016)
			(stroke
				(width 0.0254)
				(type default)
			)
			(layer "B.Fab")
		)
		(fp_line
			(start -0.508 1.016)
			(end 0.508 1.016)
			(stroke
				(width 0.0254)
				(type default)
			)
			(layer "B.Fab")
		)
		(fp_line
			(start -0.508 -1.016)
			(end -0.508 1.016)
			(stroke
				(width 0.0254)
				(type default)
			)
			(layer "B.Fab")
		)
		(pad "1" smd custom
			(at 0 -0.500126)
			(size 0.127 0.127)
			(layers "B.Cu" "B.Mask" "B.Paste")
			(net "_NFP_PCIE0_RESET_OUT_L")
			(options
				(clearance outline)
				(anchor circle)
			)
			(primitives
				(gr_poly
					(pts
						(xy -0.1778 0.254) (xy 0.1778 0.254) (xy 0.254 0.1778) (xy 0.254 -0.1778) (xy 0.1778 -0.254) (xy -0.1778 -0.254)
						(xy -0.254 -0.1778) (xy -0.254 0.1778)
					)
					(width 0)
					(fill yes)
				)
			)
		)
		(pad "2" smd custom
			(at 0 0.500126)
			(size 0.127 0.127)
			(layers "B.Cu" "B.Mask" "B.Paste")
			(net "NFP_PCIE0_RESET_OUT_L")
			(options
				(clearance outline)
				(anchor circle)
			)
			(primitives
				(gr_poly
					(pts
						(xy -0.1778 0.254) (xy 0.1778 0.254) (xy 0.254 0.1778) (xy 0.254 -0.1778) (xy 0.1778 -0.254) (xy -0.1778 -0.254)
						(xy -0.254 -0.1778) (xy -0.254 0.1778)
					)
					(width 0)
					(fill yes)
				)
			)
		)
	)
	(footprint ""
		(layer "B.Cu")
		(at 43.737022 22.041993 90)
		(property "Reference" "C27"
			(at -0.463677 2.363978 0)
			(unlocked yes)
			(layer "B.SilkS")
			(effects
				(font
					(size 0.7874 0.5842)
					(thickness 0.127)
				)
				(justify mirror)
			)
		)
		(property "Value" ""
			(at 0 0 90)
			(layer "B.Fab")
			(effects
				(font
					(size 1.27 1.27)
				)
				(justify mirror)
			)
		)
		(duplicate_pad_numbers_are_jumpers no)
		(fp_circle
			(center 0 0)
			(end 0 0.104648)
			(stroke
				(width 0.1016)
				(type default)
			)
			(fill no)
			(layer "B.SilkS")
		)
		(fp_poly
			(pts
				(xy 0.381 -0.889) (xy 0.381 0.889) (xy -0.381 0.889) (xy -0.381 -0.889)
			)
			(stroke
				(width 0)
				(type default)
			)
			(fill no)
			(layer "B.CrtYd")
		)
		(fp_line
			(start 0.508 -1.016)
			(end 0.254 -1.016)
			(stroke
				(width 0.0254)
				(type default)
			)
			(layer "B.Fab")
		)
		(fp_line
			(start 0.254 -1.016)
			(end -0.508 -1.016)
			(stroke
				(width 0.0254)
				(type default)
			)
			(layer "B.Fab")
		)
		(fp_line
			(start -0.508 -1.016)
			(end -0.508 1.016)
			(stroke
				(width 0.0254)
				(type default)
			)
			(layer "B.Fab")
		)
		(fp_line
			(start 0.508 1.016)
			(end 0.508 -1.016)
			(stroke
				(width 0.0254)
				(type default)
			)
			(layer "B.Fab")
		)
		(fp_line
			(start -0.508 1.016)
			(end 0.508 1.016)
			(stroke
				(width 0.0254)
				(type default)
			)
			(layer "B.Fab")
		)
		(pad "1" smd custom
			(at 0 -0.500126 270)
			(size 0.127 0.127)
			(layers "B.Cu" "B.Mask" "B.Paste")
			(net "VDDA_PLL")
			(options
				(clearance outline)
				(anchor circle)
			)
			(primitives
				(gr_poly
					(pts
						(xy -0.1778 0.254) (xy 0.1778 0.254) (xy 0.254 0.1778) (xy 0.254 -0.1778) (xy 0.1778 -0.254) (xy -0.1778 -0.254)
						(xy -0.254 -0.1778) (xy -0.254 0.1778)
					)
					(width 0)
					(fill yes)
				)
			)
		)
		(pad "2" smd custom
			(at 0 0.500126 270)
			(size 0.127 0.127)
			(layers "B.Cu" "B.Mask" "B.Paste")
			(net "GND")
			(options
				(clearance outline)
				(anchor circle)
			)
			(primitives
				(gr_poly
					(pts
						(xy -0.1778 0.254) (xy 0.1778 0.254) (xy 0.254 0.1778) (xy 0.254 -0.1778) (xy 0.1778 -0.254) (xy -0.1778 -0.254)
						(xy -0.254 -0.1778) (xy -0.254 0.1778)
					)
					(width 0)
					(fill yes)
				)
			)
		)
	)
	(footprint ""
		(layer "B.Cu")
		(at 23.749 27.94 -90)
		(property "Reference" "R200"
			(at 1.04267 -1.016 0)
			(unlocked yes)
			(layer "B.SilkS")
			(effects
				(font
					(size 0.7874 0.5842)
					(thickness 0.127)
				)
				(justify left mirror)
			)
		)
		(property "Value" "39.0"
			(at 0.148158 1.3462 180)
			(unlocked yes)
			(layer "B.Fab")
			(hide yes)
			(effects
				(font
					(size 1.27 0.9652)
					(thickness 0.000001)
				)
				(justify left mirror)
			)
		)
		(property "Device Type" "REST0108"
			(at 0.148158 1.3462 180)
			(unlocked yes)
			(layer "B.Fab")
			(hide yes)
			(effects
				(font
					(size 1.27 0.9652)
					(thickness 0.000001)
				)
				(justify left mirror)
			)
		)
		(duplicate_pad_numbers_are_jumpers no)
		(fp_poly
			(pts
				(xy -0.635 1.0668) (xy -0.635 -1.0668) (xy 0.635 -1.0668) (xy 0.635 1.0668)
			)
			(stroke
				(width 0)
				(type default)
			)
			(fill no)
			(layer "B.CrtYd")
		)
		(fp_line
			(start -0.254 0.508)
			(end 0.254 0.508)
			(stroke
				(width 0.0254)
				(type default)
			)
			(layer "B.Fab")
		)
		(fp_line
			(start 0.254 0.508)
			(end 0.254 -0.508)
			(stroke
				(width 0.0254)
				(type default)
			)
			(layer "B.Fab")
		)
		(fp_line
			(start -0.254 -0.508)
			(end -0.254 0.508)
			(stroke
				(width 0.0254)
				(type default)
			)
			(layer "B.Fab")
		)
		(fp_line
			(start 0.254 -0.508)
			(end -0.254 -0.508)
			(stroke
				(width 0.0254)
				(type default)
			)
			(layer "B.Fab")
		)
		(pad "1" smd rect
			(at 0 -0.4191 90)
			(size 0.508 0.5334)
			(layers "B.Cu" "B.Mask" "B.Paste")
			(net "_NFP_UART_SR_TX")
		)
		(pad "2" smd rect
			(at 0 0.4191 90)
			(size 0.508 0.5334)
			(layers "B.Cu" "B.Mask" "B.Paste")
			(net "NFP_UART_SR_TX")
		)
		(zone
			(layer "B.Cu")
			(hatch none 0.5)
			(connect_pads
				(clearance 0)
			)
			(min_thickness 0.25)
			(keepout
				(tracks not_allowed)
				(vias allowed)
				(pads allowed)
				(copperpour not_allowed)
				(footprints allowed)
			)
			(placement
				(enabled no)
				(sheetname "")
			)
			(fill
				(thermal_gap 0.5)
				(thermal_bridge_width 0.5)
				(island_removal_mode 0)
			)
			(polygon
				(pts
					(xy 23.7744 27.9146) (xy 23.7236 27.9146) (xy 23.7236 27.9654) (xy 23.7744 27.9654)
				)
			)
		)
	)
	(footprint ""
		(layer "B.Cu")
		(at 41.783 35.306)
		(property "Reference" "R169"
			(at 0 0 0)
			(layer "B.SilkS")
			(hide yes)
			(effects
				(font
					(size 1.27 1.27)
				)
				(justify mirror)
			)
		)
		(property "Value" "0"
			(at 0.148158 1.3462 270)
			(unlocked yes)
			(layer "B.Fab")
			(hide yes)
			(effects
				(font
					(size 1.27 0.9652)
					(thickness 0.000001)
				)
				(justify left mirror)
			)
		)
		(property "Device Type" "REST1111"
			(at 0.148158 1.3462 270)
			(unlocked yes)
			(layer "B.Fab")
			(hide yes)
			(effects
				(font
					(size 1.27 0.9652)
					(thickness 0.000001)
				)
				(justify left mirror)
			)
		)
		(duplicate_pad_numbers_are_jumpers no)
		(fp_poly
			(pts
				(xy -0.635 1.0668) (xy -0.635 -1.0668) (xy 0.635 -1.0668) (xy 0.635 1.0668)
			)
			(stroke
				(width 0)
				(type default)
			)
			(fill no)
			(layer "B.CrtYd")
		)
		(fp_line
			(start -0.254 -0.508)
			(end -0.254 0.508)
			(stroke
				(width 0.0254)
				(type default)
			)
			(layer "B.Fab")
		)
		(fp_line
			(start -0.254 0.508)
			(end 0.254 0.508)
			(stroke
				(width 0.0254)
				(type default)
			)
			(layer "B.Fab")
		)
		(fp_line
			(start 0.254 -0.508)
			(end -0.254 -0.508)
			(stroke
				(width 0.0254)
				(type default)
			)
			(layer "B.Fab")
		)
		(fp_line
			(start 0.254 0.508)
			(end 0.254 -0.508)
			(stroke
				(width 0.0254)
				(type default)
			)
			(layer "B.Fab")
		)
		(pad "1" smd rect
			(at 0 -0.4191 180)
			(size 0.508 0.5334)
			(layers "B.Cu" "B.Mask" "B.Paste")
			(net "VR_ODN_L")
		)
		(pad "2" smd rect
			(at 0 0.4191 180)
			(size 0.508 0.5334)
			(layers "B.Cu" "B.Mask" "B.Paste")
			(net "10N2235")
		)
		(zone
			(layer "B.Cu")
			(hatch none 0.5)
			(connect_pads
				(clearance 0)
			)
			(min_thickness 0.25)
			(keepout
				(tracks not_allowed)
				(vias allowed)
				(pads allowed)
				(copperpour not_allowed)
				(footprints allowed)
			)
			(placement
				(enabled no)
				(sheetname "")
			)
			(fill
				(thermal_gap 0.5)
				(thermal_bridge_width 0.5)
				(island_removal_mode 0)
			)
			(polygon
				(pts
					(xy 41.7576 35.2806) (xy 41.7576 35.3314) (xy 41.8084 35.3314) (xy 41.8084 35.2806)
				)
			)
		)
	)
	(footprint ""
		(layer "B.Cu")
		(at 46.1899 35.6362 180)
		(property "Reference" "C203"
			(at 0 0 0)
			(layer "B.SilkS")
			(hide yes)
			(effects
				(font
					(size 1.27 1.27)
				)
				(justify mirror)
			)
		)
		(property "Value" "1UF"
			(at 0.091846 0.2921 90)
			(unlocked yes)
			(layer "B.Fab")
			(hide yes)
			(effects
				(font
					(size 0.7874 0.5842)
					(thickness 0.2032)
				)
				(justify left mirror)
			)
		)
		(property "Device Type" "CAPC0028"
			(at 0.091846 0.2921 90)
			(unlocked yes)
			(layer "B.Fab")
			(hide yes)
			(effects
				(font
					(size 0.7874 0.5842)
					(thickness 0.2032)
				)
				(justify left mirror)
			)
		)
		(duplicate_pad_numbers_are_jumpers no)
		(fp_poly
			(pts
				(xy -0.635 1.0668) (xy -0.635 -1.0668) (xy 0.635 -1.0668) (xy 0.635 1.0668)
			)
			(stroke
				(width 0)
				(type default)
			)
			(fill no)
			(layer "B.CrtYd")
		)
		(fp_line
			(start 0.254 0.508)
			(end 0.254 -0.508)
			(stroke
				(width 0.0254)
				(type default)
			)
			(layer "B.Fab")
		)
		(fp_line
			(start 0.254 -0.508)
			(end -0.254 -0.508)
			(stroke
				(width 0.0254)
				(type default)
			)
			(layer "B.Fab")
		)
		(fp_line
			(start -0.254 0.508)
			(end 0.254 0.508)
			(stroke
				(width 0.0254)
				(type default)
			)
			(layer "B.Fab")
		)
		(fp_line
			(start -0.254 -0.508)
			(end -0.254 0.508)
			(stroke
				(width 0.0254)
				(type default)
			)
			(layer "B.Fab")
		)
		(pad "1" smd rect
			(at 0 -0.4191)
			(size 0.508 0.5334)
			(layers "B.Cu" "B.Mask" "B.Paste")
			(net "VDD_5.0V")
		)
		(pad "2" smd rect
			(at 0 0.4191)
			(size 0.508 0.5334)
			(layers "B.Cu" "B.Mask" "B.Paste")
			(net "GND")
		)
		(zone
			(layer "B.Cu")
			(hatch none 0.5)
			(connect_pads
				(clearance 0)
			)
			(min_thickness 0.25)
			(keepout
				(tracks not_allowed)
				(vias allowed)
				(pads allowed)
				(copperpour not_allowed)
				(footprints allowed)
			)
			(placement
				(enabled no)
				(sheetname "")
			)
			(fill
				(thermal_gap 0.5)
				(thermal_bridge_width 0.5)
				(island_removal_mode 0)
			)
			(polygon
				(pts
					(xy 46.2153 35.6616) (xy 46.2153 35.6108) (xy 46.1645 35.6108) (xy 46.1645 35.6616)
				)
			)
		)
	)
	(footprint ""
		(layer "B.Cu")
		(at 35.306 29.083 90)
		(property "Reference" "C121"
			(at -0.78867 1.397 0)
			(unlocked yes)
			(layer "B.SilkS")
			(effects
				(font
					(size 0.7874 0.5842)
					(thickness 0.127)
				)
				(justify left mirror)
			)
		)
		(property "Value" "0.1UF"
			(at 0.091846 0.2921 0)
			(unlocked yes)
			(layer "B.Fab")
			(hide yes)
			(effects
				(font
					(size 0.7874 0.5842)
					(thickness 0.2032)
				)
				(justify left mirror)
			)
		)
		(property "Device Type" "CAPC0073"
			(at 0.091846 0.2921 0)
			(unlocked yes)
			(layer "B.Fab")
			(hide yes)
			(effects
				(font
					(size 0.7874 0.5842)
					(thickness 0.2032)
				)
				(justify left mirror)
			)
		)
		(duplicate_pad_numbers_are_jumpers no)
		(fp_poly
			(pts
				(xy -0.635 1.0668) (xy -0.635 -1.0668) (xy 0.635 -1.0668) (xy 0.635 1.0668)
			)
			(stroke
				(width 0)
				(type default)
			)
			(fill no)
			(layer "B.CrtYd")
		)
		(fp_line
			(start 0.254 -0.508)
			(end -0.254 -0.508)
			(stroke
				(width 0.0254)
				(type default)
			)
			(layer "B.Fab")
		)
		(fp_line
			(start -0.254 -0.508)
			(end -0.254 0.508)
			(stroke
				(width 0.0254)
				(type default)
			)
			(layer "B.Fab")
		)
		(fp_line
			(start 0.254 0.508)
			(end 0.254 -0.508)
			(stroke
				(width 0.0254)
				(type default)
			)
			(layer "B.Fab")
		)
		(fp_line
			(start -0.254 0.508)
			(end 0.254 0.508)
			(stroke
				(width 0.0254)
				(type default)
			)
			(layer "B.Fab")
		)
		(pad "1" smd rect
			(at 0 -0.4191 270)
			(size 0.508 0.5334)
			(layers "B.Cu" "B.Mask" "B.Paste")
			(net "EXT_3.3V")
		)
		(pad "2" smd rect
			(at 0 0.4191 270)
			(size 0.508 0.5334)
			(layers "B.Cu" "B.Mask" "B.Paste")
			(net "GND")
		)
		(zone
			(layer "B.Cu")
			(hatch none 0.5)
			(connect_pads
				(clearance 0)
			)
			(min_thickness 0.25)
			(keepout
				(tracks not_allowed)
				(vias allowed)
				(pads allowed)
				(copperpour not_allowed)
				(footprints allowed)
			)
			(placement
				(enabled no)
				(sheetname "")
			)
			(fill
				(thermal_gap 0.5)
				(thermal_bridge_width 0.5)
				(island_removal_mode 0)
			)
			(polygon
				(pts
					(xy 35.2806 29.1084) (xy 35.3314 29.1084) (xy 35.3314 29.0576) (xy 35.2806 29.0576)
				)
			)
		)
	)
	(footprint ""
		(layer "B.Cu")
		(at 83.450989 30.612994)
		(property "Reference" "V3_A-A06"
			(at 0 0 0)
			(layer "B.SilkS")
			(hide yes)
			(effects
				(font
					(size 1.27 1.27)
				)
				(justify mirror)
			)
		)
		(property "Value" ""
			(at 0 0 0)
			(layer "B.Fab")
			(effects
				(font
					(size 1.27 1.27)
				)
				(justify mirror)
			)
		)
		(duplicate_pad_numbers_are_jumpers no)
		(pad "1" thru_hole circle
			(at 0 0 180)
			(size 0.4572 0.4572)
			(drill 0.20574)
			(layers "*.Cu" "*.Mask")
			(remove_unused_layers no)
			(net "DDR0_32A_A6")
			(clearance 0.1143)
			(thermal_gap 0.1143)
		)
	)
	(footprint ""
		(layer "B.Cu")
		(at 77.851 27.813 90)
		(property "Reference" "U19"
			(at 5.3975 6.731 0)
			(unlocked yes)
			(layer "B.SilkS")
			(effects
				(font
					(size 1.27 0.9652)
					(thickness 0.1524)
				)
				(justify left mirror)
			)
		)
		(property "Value" ""
			(at 0 0 90)
			(layer "B.Fab")
			(effects
				(font
					(size 1.27 1.27)
				)
				(justify mirror)
			)
		)
		(property "Component Value" "VALUE"
			(at 0.399999 -9.402597 90)
			(unlocked yes)
			(layer "User.4")
			(effects
				(font
					(size 0.254 0.254)
					(thickness 0.000001)
				)
				(justify mirror)
			)
		)
		(property "Device Type" "MEMC0051"
			(at 5.909996 -11.648211 90)
			(unlocked yes)
			(layer "B.Fab")
			(hide yes)
			(effects
				(font
					(size 1.27 0.9652)
					(thickness 0.000001)
				)
				(justify left mirror)
			)
		)
		(duplicate_pad_numbers_are_jumpers no)
		(fp_line
			(start 4.499991 -7.000011)
			(end 4.499991 7.000011)
			(stroke
				(width 0.1524)
				(type default)
			)
			(layer "B.SilkS")
		)
		(fp_line
			(start -4.499991 -7.000011)
			(end 4.499991 -7.000011)
			(stroke
				(width 0.1524)
				(type default)
			)
			(layer "B.SilkS")
		)
		(fp_line
			(start 4.499991 -5.999988)
			(end 3.499993 -7.000011)
			(stroke
				(width 0.1524)
				(type default)
			)
			(layer "B.SilkS")
		)
		(fp_line
			(start 4.499991 7.000011)
			(end -4.499991 7.000011)
			(stroke
				(width 0.1524)
				(type default)
			)
			(layer "B.SilkS")
		)
		(fp_line
			(start -4.499991 7.000011)
			(end -4.499991 -7.000011)
			(stroke
				(width 0.1524)
				(type default)
			)
			(layer "B.SilkS")
		)
		(fp_poly
			(pts
				(xy 7.50001 10.000005) (xy -7.50001 10.000005) (xy -7.50001 -10.000005) (xy 7.50001 -10.000005)
			)
			(stroke
				(width 0)
				(type default)
			)
			(fill no)
			(layer "B.CrtYd")
		)
		(fp_line
			(start 4.499991 -7.000011)
			(end 4.499991 7.000011)
			(stroke
				(width 0.1)
				(type default)
			)
			(layer "B.Fab")
		)
		(fp_line
			(start -4.499991 -7.000011)
			(end 4.499991 -7.000011)
			(stroke
				(width 0.1)
				(type default)
			)
			(layer "B.Fab")
		)
		(fp_line
			(start 4.499991 -5.999988)
			(end 3.499993 -7.000011)
			(stroke
				(width 0.1)
				(type default)
			)
			(layer "B.Fab")
		)
		(fp_line
			(start 4.499991 7.000011)
			(end -4.499991 7.000011)
			(stroke
				(width 0.1)
				(type default)
			)
			(layer "B.Fab")
		)
		(fp_line
			(start -4.499991 7.000011)
			(end -4.499991 -7.000011)
			(stroke
				(width 0.1)
				(type default)
			)
			(layer "B.Fab")
		)
		(fp_text user "1"
			(at 3.14833 -7.366 0)
			(unlocked yes)
			(layer "B.SilkS")
			(effects
				(font
					(size 0.7874 0.5842)
					(thickness 0.127)
				)
				(justify mirror)
			)
		)
		(fp_text user "A"
			(at 5.05333 -5.588 0)
			(unlocked yes)
			(layer "B.SilkS")
			(effects
				(font
					(size 0.7874 0.5842)
					(thickness 0.127)
				)
				(justify mirror)
			)
		)
		(pad "A1" smd circle
			(at 3.199994 -5.999988 270)
			(size 0.3556 0.3556)
			(layers "B.Cu" "B.Mask" "B.Paste")
			(net "DDR_VDDQ")
		)
		(pad "A2" smd circle
			(at 2.399995 -5.999988 270)
			(size 0.3556 0.3556)
			(layers "B.Cu" "B.Mask" "B.Paste")
			(net "_NC_ECC_DQ13")
		)
		(pad "A3" smd circle
			(at 1.599997 -5.999988 270)
			(size 0.3556 0.3556)
			(layers "B.Cu" "B.Mask" "B.Paste")
			(net "_NC_ECC_DQ15")
		)
		(pad "A7" smd circle
			(at -1.599997 -5.999988 270)
			(size 0.3556 0.3556)
			(layers "B.Cu" "B.Mask" "B.Paste")
			(net "_NC_ECC_DQ12")
		)
		(pad "A8" smd circle
			(at -2.399995 -5.999988 270)
			(size 0.3556 0.3556)
			(layers "B.Cu" "B.Mask" "B.Paste")
			(net "DDR_VDDQ")
		)
		(pad "A9" smd circle
			(at -3.199994 -5.999988 270)
			(size 0.3556 0.3556)
			(layers "B.Cu" "B.Mask" "B.Paste")
			(net "GND")
		)
		(pad "B1" smd circle
			(at 3.199994 -5.19999 270)
			(size 0.3556 0.3556)
			(layers "B.Cu" "B.Mask" "B.Paste")
			(net "GND")
		)
		(pad "B2" smd circle
			(at 2.399995 -5.19999 270)
			(size 0.3556 0.3556)
			(layers "B.Cu" "B.Mask" "B.Paste")
			(net "DDR_VDDQ")
		)
		(pad "B3" smd circle
			(at 1.599997 -5.19999 270)
			(size 0.3556 0.3556)
			(layers "B.Cu" "B.Mask" "B.Paste")
			(net "GND")
		)
		(pad "B7" smd circle
			(at -1.599997 -5.19999 270)
			(size 0.3556 0.3556)
			(layers "B.Cu" "B.Mask" "B.Paste")
			(net "12N3293")
		)
		(pad "B8" smd circle
			(at -2.399995 -5.19999 270)
			(size 0.3556 0.3556)
			(layers "B.Cu" "B.Mask" "B.Paste")
			(net "_NC_ECC_DQ14")
		)
		(pad "B9" smd circle
			(at -3.199994 -5.19999 270)
			(size 0.3556 0.3556)
			(layers "B.Cu" "B.Mask" "B.Paste")
			(net "GND")
		)
		(pad "C1" smd circle
			(at 3.199994 -4.399991 270)
			(size 0.3556 0.3556)
			(layers "B.Cu" "B.Mask" "B.Paste")
			(net "DDR_VDDQ")
		)
		(pad "C2" smd circle
			(at 2.399995 -4.399991 270)
			(size 0.3556 0.3556)
			(layers "B.Cu" "B.Mask" "B.Paste")
			(net "_NC_ECC_DQ11")
		)
		(pad "C3" smd circle
			(at 1.599997 -4.399991 270)
			(size 0.3556 0.3556)
			(layers "B.Cu" "B.Mask" "B.Paste")
			(net "_NC_ECC_DQ9")
		)
		(pad "C7" smd circle
			(at -1.599997 -4.399991 270)
			(size 0.3556 0.3556)
			(layers "B.Cu" "B.Mask" "B.Paste")
			(net "12N3294")
		)
		(pad "C8" smd circle
			(at -2.399995 -4.399991 270)
			(size 0.3556 0.3556)
			(layers "B.Cu" "B.Mask" "B.Paste")
			(net "_NC_ECC_DQ10")
		)
		(pad "C9" smd circle
			(at -3.199994 -4.399991 270)
			(size 0.3556 0.3556)
			(layers "B.Cu" "B.Mask" "B.Paste")
			(net "DDR_VDDQ")
		)
		(pad "D1" smd circle
			(at 3.199994 -3.599993 270)
			(size 0.3556 0.3556)
			(layers "B.Cu" "B.Mask" "B.Paste")
			(net "GND")
		)
		(pad "D2" smd circle
			(at 2.399995 -3.599993 270)
			(size 0.3556 0.3556)
			(layers "B.Cu" "B.Mask" "B.Paste")
			(net "DDR_VDDQ")
		)
		(pad "D3" smd circle
			(at 1.599997 -3.599993 270)
			(size 0.3556 0.3556)
			(layers "B.Cu" "B.Mask" "B.Paste")
			(net "12N3291")
		)
		(pad "D7" smd circle
			(at -1.599997 -3.599993 270)
			(size 0.3556 0.3556)
			(layers "B.Cu" "B.Mask" "B.Paste")
			(net "_NC_ECC_DQ8")
		)
		(pad "D8" smd circle
			(at -2.399995 -3.599993 270)
			(size 0.3556 0.3556)
			(layers "B.Cu" "B.Mask" "B.Paste")
			(net "GND")
		)
		(pad "D9" smd circle
			(at -3.199994 -3.599993 270)
			(size 0.3556 0.3556)
			(layers "B.Cu" "B.Mask" "B.Paste")
			(net "DDR_VDDQ")
		)
		(pad "E1" smd circle
			(at 3.199994 -2.799994 270)
			(size 0.3556 0.3556)
			(layers "B.Cu" "B.Mask" "B.Paste")
			(net "GND")
		)
		(pad "E2" smd circle
			(at 2.399995 -2.799994 270)
			(size 0.3556 0.3556)
			(layers "B.Cu" "B.Mask" "B.Paste")
			(net "GND")
		)
		(pad "E3" smd circle
			(at 1.599997 -2.799994 270)
			(size 0.3556 0.3556)
			(layers "B.Cu" "B.Mask" "B.Paste")
			(net "DDR0_32A_CB2")
		)
		(pad "E7" smd circle
			(at -1.599997 -2.799994 270)
			(size 0.3556 0.3556)
			(layers "B.Cu" "B.Mask" "B.Paste")
			(net "DDR0_32A_DM4")
		)
		(pad "E8" smd circle
			(at -2.399995 -2.799994 270)
			(size 0.3556 0.3556)
			(layers "B.Cu" "B.Mask" "B.Paste")
			(net "GND")
		)
		(pad "E9" smd circle
			(at -3.199994 -2.799994 270)
			(size 0.3556 0.3556)
			(layers "B.Cu" "B.Mask" "B.Paste")
			(net "DDR_VDDQ")
		)
		(pad "F1" smd circle
			(at 3.199994 -1.999996 270)
			(size 0.3556 0.3556)
			(layers "B.Cu" "B.Mask" "B.Paste")
			(net "DDR_VDDQ")
		)
		(pad "F2" smd circle
			(at 2.399995 -1.999996 270)
			(size 0.3556 0.3556)
			(layers "B.Cu" "B.Mask" "B.Paste")
			(net "DDR0_32A_CB0")
		)
		(pad "F3" smd circle
			(at 1.599997 -1.999996 270)
			(size 0.3556 0.3556)
			(layers "B.Cu" "B.Mask" "B.Paste")
			(net "DDR0_32A_DQS4_P")
		)
		(pad "F7" smd circle
			(at -1.599997 -1.999996 270)
			(size 0.3556 0.3556)
			(layers "B.Cu" "B.Mask" "B.Paste")
			(net "DDR0_32A_CB5")
		)
		(pad "F8" smd circle
			(at -2.399995 -1.999996 270)
			(size 0.3556 0.3556)
			(layers "B.Cu" "B.Mask" "B.Paste")
			(net "DDR0_32A_CB4")
		)
		(pad "F9" smd circle
			(at -3.199994 -1.999996 270)
			(size 0.3556 0.3556)
			(layers "B.Cu" "B.Mask" "B.Paste")
			(net "GND")
		)
		(pad "G1" smd circle
			(at 3.199994 -1.199998 270)
			(size 0.3556 0.3556)
			(layers "B.Cu" "B.Mask" "B.Paste")
			(net "GND")
		)
		(pad "G2" smd circle
			(at 2.399995 -1.199998 270)
			(size 0.3556 0.3556)
			(layers "B.Cu" "B.Mask" "B.Paste")
			(net "DDR0_32A_CB6")
		)
		(pad "G3" smd circle
			(at 1.599997 -1.199998 270)
			(size 0.3556 0.3556)
			(layers "B.Cu" "B.Mask" "B.Paste")
			(net "DDR0_32A_DQS4_N")
		)
		(pad "G7" smd circle
			(at -1.599997 -1.199998 270)
			(size 0.3556 0.3556)
			(layers "B.Cu" "B.Mask" "B.Paste")
			(net "DDR_VDDQ")
		)
		(pad "G8" smd circle
			(at -2.399995 -1.199998 270)
			(size 0.3556 0.3556)
			(layers "B.Cu" "B.Mask" "B.Paste")
			(net "GND")
		)
		(pad "G9" smd circle
			(at -3.199994 -1.199998 270)
			(size 0.3556 0.3556)
			(layers "B.Cu" "B.Mask" "B.Paste")
			(net "GND")
		)
		(pad "H1" smd circle
			(at 3.199994 -0.399999 270)
			(size 0.3556 0.3556)
			(layers "B.Cu" "B.Mask" "B.Paste")
			(net "DDR0_32A_VREF1B")
		)
		(pad "H2" smd circle
			(at 2.399995 -0.399999 270)
			(size 0.3556 0.3556)
			(layers "B.Cu" "B.Mask" "B.Paste")
			(net "DDR_VDDQ")
		)
		(pad "H3" smd circle
			(at 1.599997 -0.399999 270)
			(size 0.3556 0.3556)
			(layers "B.Cu" "B.Mask" "B.Paste")
			(net "DDR0_32A_CB7")
		)
		(pad "H7" smd circle
			(at -1.599997 -0.399999 270)
			(size 0.3556 0.3556)
			(layers "B.Cu" "B.Mask" "B.Paste")
			(net "DDR0_32A_CB1")
		)
		(pad "H8" smd circle
			(at -2.399995 -0.399999 270)
			(size 0.3556 0.3556)
			(layers "B.Cu" "B.Mask" "B.Paste")
			(net "DDR0_32A_CB3")
		)
		(pad "H9" smd circle
			(at -3.199994 -0.399999 270)
			(size 0.3556 0.3556)
			(layers "B.Cu" "B.Mask" "B.Paste")
			(net "DDR_VDDQ")
		)
		(pad "J1" smd circle
			(at 3.199994 0.399999 270)
			(size 0.3556 0.3556)
			(layers "B.Cu" "B.Mask" "B.Paste")
			(net "Net_90")
		)
		(pad "J2" smd circle
			(at 2.399995 0.399999 270)
			(size 0.3556 0.3556)
			(layers "B.Cu" "B.Mask" "B.Paste")
			(net "GND")
		)
		(pad "J3" smd circle
			(at 1.599997 0.399999 270)
			(size 0.3556 0.3556)
			(layers "B.Cu" "B.Mask" "B.Paste")
			(net "DDR0_32A_RAS_L")
		)
		(pad "J7" smd circle
			(at -1.599997 0.399999 270)
			(size 0.3556 0.3556)
			(layers "B.Cu" "B.Mask" "B.Paste")
			(net "DDR0_32A_CK0_P")
		)
		(pad "J8" smd circle
			(at -2.399995 0.399999 270)
			(size 0.3556 0.3556)
			(layers "B.Cu" "B.Mask" "B.Paste")
			(net "GND")
		)
		(pad "J9" smd circle
			(at -3.199994 0.399999 270)
			(size 0.3556 0.3556)
			(layers "B.Cu" "B.Mask" "B.Paste")
			(net "Net_504")
		)
		(pad "K1" smd circle
			(at 3.199994 1.199998 270)
			(size 0.3556 0.3556)
			(layers "B.Cu" "B.Mask" "B.Paste")
			(net "DDR0_32A_ODT0")
		)
		(pad "K2" smd circle
			(at 2.399995 1.199998 270)
			(size 0.3556 0.3556)
			(layers "B.Cu" "B.Mask" "B.Paste")
			(net "DDR_VDDQ")
		)
		(pad "K3" smd circle
			(at 1.599997 1.199998 270)
			(size 0.3556 0.3556)
			(layers "B.Cu" "B.Mask" "B.Paste")
			(net "DDR0_32A_CAS_L")
		)
		(pad "K7" smd circle
			(at -1.599997 1.199998 270)
			(size 0.3556 0.3556)
			(layers "B.Cu" "B.Mask" "B.Paste")
			(net "DDR0_32A_CK0_N")
		)
		(pad "K8" smd circle
			(at -2.399995 1.199998 270)
			(size 0.3556 0.3556)
			(layers "B.Cu" "B.Mask" "B.Paste")
			(net "DDR_VDDQ")
		)
		(pad "K9" smd circle
			(at -3.199994 1.199998 270)
			(size 0.3556 0.3556)
			(layers "B.Cu" "B.Mask" "B.Paste")
			(net "DDR0_32A_CKE0")
		)
		(pad "L1" smd circle
			(at 3.199994 1.999996 270)
			(size 0.3556 0.3556)
			(layers "B.Cu" "B.Mask" "B.Paste")
			(net "Net_502")
		)
		(pad "L2" smd circle
			(at 2.399995 1.999996 270)
			(size 0.3556 0.3556)
			(layers "B.Cu" "B.Mask" "B.Paste")
			(net "DDR0_32A_CS0_L")
		)
		(pad "L3" smd circle
			(at 1.599997 1.999996 270)
			(size 0.3556 0.3556)
			(layers "B.Cu" "B.Mask" "B.Paste")
			(net "DDR0_32A_WE_L")
		)
		(pad "L7" smd circle
			(at -1.599997 1.999996 270)
			(size 0.3556 0.3556)
			(layers "B.Cu" "B.Mask" "B.Paste")
			(net "DDR0_32A_A10")
		)
		(pad "L8" smd circle
			(at -2.399995 1.999996 270)
			(size 0.3556 0.3556)
			(layers "B.Cu" "B.Mask" "B.Paste")
			(net "12N3220")
		)
		(pad "L9" smd circle
			(at -3.199994 1.999996 270)
			(size 0.3556 0.3556)
			(layers "B.Cu" "B.Mask" "B.Paste")
			(net "Net_505")
		)
		(pad "M1" smd circle
			(at 3.199994 2.799994 270)
			(size 0.3556 0.3556)
			(layers "B.Cu" "B.Mask" "B.Paste")
			(net "GND")
		)
		(pad "M2" smd circle
			(at 2.399995 2.799994 270)
			(size 0.3556 0.3556)
			(layers "B.Cu" "B.Mask" "B.Paste")
			(net "DDR0_32A_BA0")
		)
		(pad "M3" smd circle
			(at 1.599997 2.799994 270)
			(size 0.3556 0.3556)
			(layers "B.Cu" "B.Mask" "B.Paste")
			(net "DDR0_32A_BA2")
		)
		(pad "M7" smd circle
			(at -1.599997 2.799994 270)
			(size 0.3556 0.3556)
			(layers "B.Cu" "B.Mask" "B.Paste")
			(net "Net_503")
		)
		(pad "M8" smd circle
			(at -2.399995 2.799994 270)
			(size 0.3556 0.3556)
			(layers "B.Cu" "B.Mask" "B.Paste")
			(net "DDR0_32A_VREF1B")
		)
		(pad "M9" smd circle
			(at -3.199994 2.799994 270)
			(size 0.3556 0.3556)
			(layers "B.Cu" "B.Mask" "B.Paste")
			(net "GND")
		)
		(pad "N1" smd circle
			(at 3.199994 3.599993 270)
			(size 0.3556 0.3556)
			(layers "B.Cu" "B.Mask" "B.Paste")
			(net "DDR_VDDQ")
		)
		(pad "N2" smd circle
			(at 2.399995 3.599993 270)
			(size 0.3556 0.3556)
			(layers "B.Cu" "B.Mask" "B.Paste")
			(net "DDR0_32A_A3")
		)
		(pad "N3" smd circle
			(at 1.599997 3.599993 270)
			(size 0.3556 0.3556)
			(layers "B.Cu" "B.Mask" "B.Paste")
			(net "DDR0_32A_A0")
		)
		(pad "N7" smd circle
			(at -1.599997 3.599993 270)
			(size 0.3556 0.3556)
			(layers "B.Cu" "B.Mask" "B.Paste")
			(net "DDR0_32A_A12")
		)
		(pad "N8" smd circle
			(at -2.399995 3.599993 270)
			(size 0.3556 0.3556)
			(layers "B.Cu" "B.Mask" "B.Paste")
			(net "DDR0_32A_BA1")
		)
		(pad "N9" smd circle
			(at -3.199994 3.599993 270)
			(size 0.3556 0.3556)
			(layers "B.Cu" "B.Mask" "B.Paste")
			(net "DDR_VDDQ")
		)
		(pad "P1" smd circle
			(at 3.199994 4.399991 270)
			(size 0.3556 0.3556)
			(layers "B.Cu" "B.Mask" "B.Paste")
			(net "GND")
		)
		(pad "P2" smd circle
			(at 2.399995 4.399991 270)
			(size 0.3556 0.3556)
			(layers "B.Cu" "B.Mask" "B.Paste")
			(net "DDR0_32A_A5")
		)
		(pad "P3" smd circle
			(at 1.599997 4.399991 270)
			(size 0.3556 0.3556)
			(layers "B.Cu" "B.Mask" "B.Paste")
			(net "DDR0_32A_A2")
		)
		(pad "P7" smd circle
			(at -1.599997 4.399991 270)
			(size 0.3556 0.3556)
			(layers "B.Cu" "B.Mask" "B.Paste")
			(net "DDR0_32A_A1")
		)
		(pad "P8" smd circle
			(at -2.399995 4.399991 270)
			(size 0.3556 0.3556)
			(layers "B.Cu" "B.Mask" "B.Paste")
			(net "DDR0_32A_A4")
		)
		(pad "P9" smd circle
			(at -3.199994 4.399991 270)
			(size 0.3556 0.3556)
			(layers "B.Cu" "B.Mask" "B.Paste")
			(net "GND")
		)
		(pad "R1" smd circle
			(at 3.199994 5.19999 270)
			(size 0.3556 0.3556)
			(layers "B.Cu" "B.Mask" "B.Paste")
			(net "DDR_VDDQ")
		)
		(pad "R2" smd circle
			(at 2.399995 5.19999 270)
			(size 0.3556 0.3556)
			(layers "B.Cu" "B.Mask" "B.Paste")
			(net "DDR0_32A_A7")
		)
		(pad "R3" smd circle
			(at 1.599997 5.19999 270)
			(size 0.3556 0.3556)
			(layers "B.Cu" "B.Mask" "B.Paste")
			(net "DDR0_32A_A9")
		)
		(pad "R7" smd circle
			(at -1.599997 5.19999 270)
			(size 0.3556 0.3556)
			(layers "B.Cu" "B.Mask" "B.Paste")
			(net "DDR0_32A_A11")
		)
		(pad "R8" smd circle
			(at -2.399995 5.19999 270)
			(size 0.3556 0.3556)
			(layers "B.Cu" "B.Mask" "B.Paste")
			(net "DDR0_32A_A6")
		)
		(pad "R9" smd circle
			(at -3.199994 5.19999 270)
			(size 0.3556 0.3556)
			(layers "B.Cu" "B.Mask" "B.Paste")
			(net "DDR_VDDQ")
		)
		(pad "T1" smd circle
			(at 3.199994 5.999988 270)
			(size 0.3556 0.3556)
			(layers "B.Cu" "B.Mask" "B.Paste")
			(net "GND")
		)
		(pad "T2" smd circle
			(at 2.399995 5.999988 270)
			(size 0.3556 0.3556)
			(layers "B.Cu" "B.Mask" "B.Paste")
			(net "DDR0_32A_DRAMRST_L")
		)
		(pad "T3" smd circle
			(at 1.599997 5.999988 270)
			(size 0.3556 0.3556)
			(layers "B.Cu" "B.Mask" "B.Paste")
			(net "DDR0_32A_A13")
		)
		(pad "T7" smd circle
			(at -1.599997 5.999988 270)
			(size 0.3556 0.3556)
			(layers "B.Cu" "B.Mask" "B.Paste")
			(net "DDR0_32A_A14")
		)
		(pad "T8" smd circle
			(at -2.399995 5.999988 270)
			(size 0.3556 0.3556)
			(layers "B.Cu" "B.Mask" "B.Paste")
			(net "DDR0_32A_A8")
		)
		(pad "T9" smd circle
			(at -3.199994 5.999988 270)
			(size 0.3556 0.3556)
			(layers "B.Cu" "B.Mask" "B.Paste")
			(net "GND")
		)
	)
	(footprint ""
		(layer "B.Cu")
		(at 35.8902 20.447 -90)
		(property "Reference" "C119"
			(at 0 0 90)
			(layer "B.SilkS")
			(hide yes)
			(effects
				(font
					(size 1.27 1.27)
				)
				(justify mirror)
			)
		)
		(property "Value" "0.1UF"
			(at 0.091846 0.2921 180)
			(unlocked yes)
			(layer "B.Fab")
			(hide yes)
			(effects
				(font
					(size 0.7874 0.5842)
					(thickness 0.2032)
				)
				(justify left mirror)
			)
		)
		(property "Device Type" "CAPC0073"
			(at 0.091846 0.2921 180)
			(unlocked yes)
			(layer "B.Fab")
			(hide yes)
			(effects
				(font
					(size 0.7874 0.5842)
					(thickness 0.2032)
				)
				(justify left mirror)
			)
		)
		(duplicate_pad_numbers_are_jumpers no)
		(fp_poly
			(pts
				(xy -0.635 1.0668) (xy -0.635 -1.0668) (xy 0.635 -1.0668) (xy 0.635 1.0668)
			)
			(stroke
				(width 0)
				(type default)
			)
			(fill no)
			(layer "B.CrtYd")
		)
		(fp_line
			(start -0.254 0.508)
			(end 0.254 0.508)
			(stroke
				(width 0.0254)
				(type default)
			)
			(layer "B.Fab")
		)
		(fp_line
			(start 0.254 0.508)
			(end 0.254 -0.508)
			(stroke
				(width 0.0254)
				(type default)
			)
			(layer "B.Fab")
		)
		(fp_line
			(start -0.254 -0.508)
			(end -0.254 0.508)
			(stroke
				(width 0.0254)
				(type default)
			)
			(layer "B.Fab")
		)
		(fp_line
			(start 0.254 -0.508)
			(end -0.254 -0.508)
			(stroke
				(width 0.0254)
				(type default)
			)
			(layer "B.Fab")
		)
		(pad "1" smd rect
			(at 0 -0.4191 90)
			(size 0.508 0.5334)
			(layers "B.Cu" "B.Mask" "B.Paste")
			(net "EXT_3.3V")
		)
		(pad "2" smd rect
			(at 0 0.4191 90)
			(size 0.508 0.5334)
			(layers "B.Cu" "B.Mask" "B.Paste")
			(net "GND")
		)
		(zone
			(layer "B.Cu")
			(hatch none 0.5)
			(connect_pads
				(clearance 0)
			)
			(min_thickness 0.25)
			(keepout
				(tracks not_allowed)
				(vias allowed)
				(pads allowed)
				(copperpour not_allowed)
				(footprints allowed)
			)
			(placement
				(enabled no)
				(sheetname "")
			)
			(fill
				(thermal_gap 0.5)
				(thermal_bridge_width 0.5)
				(island_removal_mode 0)
			)
			(polygon
				(pts
					(xy 35.9156 20.4216) (xy 35.8648 20.4216) (xy 35.8648 20.4724) (xy 35.9156 20.4724)
				)
			)
		)
	)
	(footprint ""
		(layer "B.Cu")
		(at 16.764 32.131)
		(property "Reference" "TP69"
			(at 1.87833 2.667 270)
			(unlocked yes)
			(layer "B.SilkS")
			(effects
				(font
					(size 0.7874 0.5842)
					(thickness 0.127)
				)
				(justify left mirror)
			)
		)
		(property "Value" "*"
			(at 0.4826 -0.14732 0)
			(unlocked yes)
			(layer "B.Fab")
			(hide yes)
			(effects
				(font
					(size 1.27 0.9652)
					(thickness 0.000001)
				)
				(justify left mirror)
			)
		)
		(property "Device Type" "TP_SMALL"
			(at 0.4826 -0.14732 0)
			(unlocked yes)
			(layer "B.Fab")
			(hide yes)
			(effects
				(font
					(size 1.27 0.9652)
					(thickness 0.000001)
				)
				(justify left mirror)
			)
		)
		(duplicate_pad_numbers_are_jumpers no)
		(fp_line
			(start -0.8636 -0.8636)
			(end 0.8636 -0.8636)
			(stroke
				(width 0.1524)
				(type default)
			)
			(layer "B.SilkS")
		)
		(fp_line
			(start -0.8636 0.8636)
			(end -0.8636 -0.8636)
			(stroke
				(width 0.1524)
				(type default)
			)
			(layer "B.SilkS")
		)
		(fp_line
			(start 0.8636 -0.8636)
			(end 0.8636 0.8636)
			(stroke
				(width 0.1524)
				(type default)
			)
			(layer "B.SilkS")
		)
		(fp_line
			(start 0.8636 0.8636)
			(end -0.8636 0.8636)
			(stroke
				(width 0.1524)
				(type default)
			)
			(layer "B.SilkS")
		)
		(fp_poly
			(pts
				(xy 0.635 -0.635) (xy 0.635 0.635) (xy -0.635 0.635) (xy -0.635 -0.635)
			)
			(stroke
				(width 0)
				(type default)
			)
			(fill no)
			(layer "B.CrtYd")
		)
		(pad "1" smd rect
			(at 0 0 180)
			(size 1.27 1.27)
			(layers "B.Cu" "B.Mask" "B.Paste")
			(net "GND")
		)
	)
	(footprint ""
		(layer "B.Cu")
		(at 83.450989 29.812996)
		(property "Reference" "V3_A-A11"
			(at 0 0 0)
			(layer "B.SilkS")
			(hide yes)
			(effects
				(font
					(size 1.27 1.27)
				)
				(justify mirror)
			)
		)
		(property "Value" ""
			(at 0 0 0)
			(layer "B.Fab")
			(effects
				(font
					(size 1.27 1.27)
				)
				(justify mirror)
			)
		)
		(duplicate_pad_numbers_are_jumpers no)
		(pad "1" thru_hole circle
			(at 0 0 180)
			(size 0.4572 0.4572)
			(drill 0.20574)
			(layers "*.Cu" "*.Mask")
			(remove_unused_layers no)
			(net "DDR0_32A_A11")
			(clearance 0.1143)
			(thermal_gap 0.1143)
		)
	)
	(footprint ""
		(layer "B.Cu")
		(at 61.736986 16.042005 -90)
		(property "Reference" "C196"
			(at 0 0 90)
			(layer "B.SilkS")
			(hide yes)
			(effects
				(font
					(size 1.27 1.27)
				)
				(justify mirror)
			)
		)
		(property "Value" ""
			(at 0 0 90)
			(layer "B.Fab")
			(effects
				(font
					(size 1.27 1.27)
				)
				(justify mirror)
			)
		)
		(duplicate_pad_numbers_are_jumpers no)
		(fp_circle
			(center 0 0)
			(end 0 -0.104648)
			(stroke
				(width 0.1016)
				(type default)
			)
			(fill no)
			(layer "B.SilkS")
		)
		(fp_poly
			(pts
				(xy 0.381 -0.889) (xy 0.381 0.889) (xy -0.381 0.889) (xy -0.381 -0.889)
			)
			(stroke
				(width 0)
				(type default)
			)
			(fill no)
			(layer "B.CrtYd")
		)
		(fp_line
			(start -0.508 1.016)
			(end 0.508 1.016)
			(stroke
				(width 0.0254)
				(type default)
			)
			(layer "B.Fab")
		)
		(fp_line
			(start 0.508 1.016)
			(end 0.508 -1.016)
			(stroke
				(width 0.0254)
				(type default)
			)
			(layer "B.Fab")
		)
		(fp_line
			(start -0.508 -1.016)
			(end -0.508 1.016)
			(stroke
				(width 0.0254)
				(type default)
			)
			(layer "B.Fab")
		)
		(fp_line
			(start 0.254 -1.016)
			(end -0.508 -1.016)
			(stroke
				(width 0.0254)
				(type default)
			)
			(layer "B.Fab")
		)
		(fp_line
			(start 0.508 -1.016)
			(end 0.254 -1.016)
			(stroke
				(width 0.0254)
				(type default)
			)
			(layer "B.Fab")
		)
		(pad "1" smd custom
			(at 0 -0.500126 90)
			(size 0.127 0.127)
			(layers "B.Cu" "B.Mask" "B.Paste")
			(net "DDR0_32A_VREF")
			(options
				(clearance outline)
				(anchor circle)
			)
			(primitives
				(gr_poly
					(pts
						(xy -0.1778 0.254) (xy 0.1778 0.254) (xy 0.254 0.1778) (xy 0.254 -0.1778) (xy 0.1778 -0.254) (xy -0.1778 -0.254)
						(xy -0.254 -0.1778) (xy -0.254 0.1778)
					)
					(width 0)
					(fill yes)
				)
			)
		)
		(pad "2" smd custom
			(at 0 0.500126 90)
			(size 0.127 0.127)
			(layers "B.Cu" "B.Mask" "B.Paste")
			(net "GND")
			(options
				(clearance outline)
				(anchor circle)
			)
			(primitives
				(gr_poly
					(pts
						(xy -0.1778 0.254) (xy 0.1778 0.254) (xy 0.254 0.1778) (xy 0.254 -0.1778) (xy 0.1778 -0.254) (xy -0.1778 -0.254)
						(xy -0.254 -0.1778) (xy -0.254 0.1778)
					)
					(width 0)
					(fill yes)
				)
			)
		)
	)
	(footprint ""
		(layer "B.Cu")
		(at 40.894 44.831)
		(property "Reference" "TP24"
			(at 3.302 -1.75133 0)
			(unlocked yes)
			(layer "B.SilkS")
			(effects
				(font
					(size 0.7874 0.5842)
					(thickness 0.127)
				)
				(justify left mirror)
			)
		)
		(property "Value" "*"
			(at 0.4826 -0.14732 0)
			(unlocked yes)
			(layer "B.Fab")
			(hide yes)
			(effects
				(font
					(size 1.27 0.9652)
					(thickness 0.000001)
				)
				(justify left mirror)
			)
		)
		(property "Device Type" "TP_SMALL"
			(at 0.4826 -0.14732 0)
			(unlocked yes)
			(layer "B.Fab")
			(hide yes)
			(effects
				(font
					(size 1.27 0.9652)
					(thickness 0.000001)
				)
				(justify left mirror)
			)
		)
		(duplicate_pad_numbers_are_jumpers no)
		(fp_line
			(start -0.8636 -0.8636)
			(end 0.8636 -0.8636)
			(stroke
				(width 0.1524)
				(type default)
			)
			(layer "B.SilkS")
		)
		(fp_line
			(start -0.8636 0.8636)
			(end -0.8636 -0.8636)
			(stroke
				(width 0.1524)
				(type default)
			)
			(layer "B.SilkS")
		)
		(fp_line
			(start 0.8636 -0.8636)
			(end 0.8636 0.8636)
			(stroke
				(width 0.1524)
				(type default)
			)
			(layer "B.SilkS")
		)
		(fp_line
			(start 0.8636 0.8636)
			(end -0.8636 0.8636)
			(stroke
				(width 0.1524)
				(type default)
			)
			(layer "B.SilkS")
		)
		(fp_poly
			(pts
				(xy 0.635 -0.635) (xy 0.635 0.635) (xy -0.635 0.635) (xy -0.635 -0.635)
			)
			(stroke
				(width 0)
				(type default)
			)
			(fill no)
			(layer "B.CrtYd")
		)
		(pad "1" smd rect
			(at 0 0 180)
			(size 1.27 1.27)
			(layers "B.Cu" "B.Mask" "B.Paste")
			(net "NFP_CFG_SPI_FLASH_HOLD_L")
		)
	)
	(footprint ""
		(layer "B.Cu")
		(at 56.007 41.91)
		(property "Reference" "C17"
			(at 1.143 -1.87833 0)
			(unlocked yes)
			(layer "B.SilkS")
			(effects
				(font
					(size 0.7874 0.5842)
					(thickness 0.127)
				)
				(justify left mirror)
			)
		)
		(property "Value" "22UF"
			(at 0.148158 1.7526 270)
			(unlocked yes)
			(layer "B.Fab")
			(hide yes)
			(effects
				(font
					(size 1.27 0.9652)
					(thickness 0.000001)
				)
				(justify left mirror)
			)
		)
		(property "Device Type" "CAPC0063"
			(at 0.148158 1.7526 270)
			(unlocked yes)
			(layer "B.Fab")
			(hide yes)
			(effects
				(font
					(size 1.27 0.9652)
					(thickness 0.000001)
				)
				(justify left mirror)
			)
		)
		(duplicate_pad_numbers_are_jumpers no)
		(fp_circle
			(center 0 0)
			(end 0.127 0)
			(stroke
				(width 0.2032)
				(type default)
			)
			(fill no)
			(layer "B.SilkS")
		)
		(fp_poly
			(pts
				(xy -0.7874 -1.6637) (xy 0.7874 -1.6637) (xy 0.7874 1.6637) (xy -0.7874 1.6637)
			)
			(stroke
				(width 0)
				(type default)
			)
			(fill no)
			(layer "B.CrtYd")
		)
		(fp_line
			(start -0.4064 -0.7874)
			(end -0.4064 0.8128)
			(stroke
				(width 0.0254)
				(type default)
			)
			(layer "B.Fab")
		)
		(fp_line
			(start -0.4064 0.8128)
			(end 0.4064 0.8128)
			(stroke
				(width 0.0254)
				(type default)
			)
			(layer "B.Fab")
		)
		(fp_line
			(start 0.4064 -0.7874)
			(end -0.4064 -0.7874)
			(stroke
				(width 0.0254)
				(type default)
			)
			(layer "B.Fab")
		)
		(fp_line
			(start 0.4064 0.8128)
			(end 0.4064 -0.7874)
			(stroke
				(width 0.0254)
				(type default)
			)
			(layer "B.Fab")
		)
		(pad "1" smd rect
			(at 0 -0.8001 180)
			(size 0.8636 0.9652)
			(layers "B.Cu" "B.Mask" "B.Paste")
			(net "VDD_CORE")
		)
		(pad "2" smd rect
			(at 0 0.8001 180)
			(size 0.8636 0.9652)
			(layers "B.Cu" "B.Mask" "B.Paste")
			(net "GND")
		)
		(zone
			(layer "B.Cu")
			(hatch none 0.5)
			(connect_pads
				(clearance 0)
			)
			(min_thickness 0.25)
			(keepout
				(tracks not_allowed)
				(vias allowed)
				(pads allowed)
				(copperpour not_allowed)
				(footprints allowed)
			)
			(placement
				(enabled no)
				(sheetname "")
			)
			(fill
				(thermal_gap 0.5)
				(thermal_bridge_width 0.5)
				(island_removal_mode 0)
			)
			(polygon
				(pts
					(xy 56.0705 41.656) (xy 55.9435 41.656) (xy 55.9435 42.164) (xy 56.0705 42.164)
				)
			)
		)
	)
	(footprint ""
		(layer "B.Cu")
		(at 81.850992 2.699004)
		(property "Reference" "V1_A-A00"
			(at 0 0 0)
			(layer "B.SilkS")
			(hide yes)
			(effects
				(font
					(size 1.27 1.27)
				)
				(justify mirror)
			)
		)
		(property "Value" ""
			(at 0 0 0)
			(layer "B.Fab")
			(effects
				(font
					(size 1.27 1.27)
				)
				(justify mirror)
			)
		)
		(duplicate_pad_numbers_are_jumpers no)
		(pad "1" thru_hole circle
			(at 0 0 180)
			(size 0.4572 0.4572)
			(drill 0.20574)
			(layers "*.Cu" "*.Mask")
			(remove_unused_layers no)
			(net "DDR0_32A_A0")
			(clearance 0.1143)
			(thermal_gap 0.1143)
		)
	)
	(footprint ""
		(layer "B.Cu")
		(at 60.236989 9.542018)
		(property "Reference" "C37"
			(at 0 0 0)
			(layer "B.SilkS")
			(hide yes)
			(effects
				(font
					(size 1.27 1.27)
				)
				(justify mirror)
			)
		)
		(property "Value" ""
			(at 0 0 0)
			(layer "B.Fab")
			(effects
				(font
					(size 1.27 1.27)
				)
				(justify mirror)
			)
		)
		(duplicate_pad_numbers_are_jumpers no)
		(fp_circle
			(center 0 0)
			(end 0.104648 0)
			(stroke
				(width 0.1016)
				(type default)
			)
			(fill no)
			(layer "B.SilkS")
		)
		(fp_poly
			(pts
				(xy 0.381 -0.889) (xy 0.381 0.889) (xy -0.381 0.889) (xy -0.381 -0.889)
			)
			(stroke
				(width 0)
				(type default)
			)
			(fill no)
			(layer "B.CrtYd")
		)
		(fp_line
			(start -0.508 -1.016)
			(end -0.508 1.016)
			(stroke
				(width 0.0254)
				(type default)
			)
			(layer "B.Fab")
		)
		(fp_line
			(start -0.508 1.016)
			(end 0.508 1.016)
			(stroke
				(width 0.0254)
				(type default)
			)
			(layer "B.Fab")
		)
		(fp_line
			(start 0.254 -1.016)
			(end -0.508 -1.016)
			(stroke
				(width 0.0254)
				(type default)
			)
			(layer "B.Fab")
		)
		(fp_line
			(start 0.508 -1.016)
			(end 0.254 -1.016)
			(stroke
				(width 0.0254)
				(type default)
			)
			(layer "B.Fab")
		)
		(fp_line
			(start 0.508 1.016)
			(end 0.508 -1.016)
			(stroke
				(width 0.0254)
				(type default)
			)
			(layer "B.Fab")
		)
		(pad "1" smd custom
			(at 0 -0.500126 180)
			(size 0.127 0.127)
			(layers "B.Cu" "B.Mask" "B.Paste")
			(net "VDDA_PCIE0")
			(options
				(clearance outline)
				(anchor circle)
			)
			(primitives
				(gr_poly
					(pts
						(xy -0.1778 0.254) (xy 0.1778 0.254) (xy 0.254 0.1778) (xy 0.254 -0.1778) (xy 0.1778 -0.254) (xy -0.1778 -0.254)
						(xy -0.254 -0.1778) (xy -0.254 0.1778)
					)
					(width 0)
					(fill yes)
				)
			)
		)
		(pad "2" smd custom
			(at 0 0.500126 180)
			(size 0.127 0.127)
			(layers "B.Cu" "B.Mask" "B.Paste")
			(net "GND")
			(options
				(clearance outline)
				(anchor circle)
			)
			(primitives
				(gr_poly
					(pts
						(xy -0.1778 0.254) (xy 0.1778 0.254) (xy 0.254 0.1778) (xy 0.254 -0.1778) (xy 0.1778 -0.254) (xy -0.1778 -0.254)
						(xy -0.254 -0.1778) (xy -0.254 0.1778)
					)
					(width 0)
					(fill yes)
				)
			)
		)
	)
	(footprint ""
		(layer "B.Cu")
		(at 27.305 19.2024 -90)
		(property "Reference" "C120"
			(at -1.31953 -0.762 0)
			(unlocked yes)
			(layer "B.SilkS")
			(effects
				(font
					(size 0.7874 0.5842)
					(thickness 0.127)
				)
				(justify left mirror)
			)
		)
		(property "Value" "0.1UF"
			(at 0.091846 0.2921 180)
			(unlocked yes)
			(layer "B.Fab")
			(hide yes)
			(effects
				(font
					(size 0.7874 0.5842)
					(thickness 0.2032)
				)
				(justify left mirror)
			)
		)
		(property "Device Type" "CAPC0073"
			(at 0.091846 0.2921 180)
			(unlocked yes)
			(layer "B.Fab")
			(hide yes)
			(effects
				(font
					(size 0.7874 0.5842)
					(thickness 0.2032)
				)
				(justify left mirror)
			)
		)
		(duplicate_pad_numbers_are_jumpers no)
		(fp_poly
			(pts
				(xy -0.635 1.0668) (xy -0.635 -1.0668) (xy 0.635 -1.0668) (xy 0.635 1.0668)
			)
			(stroke
				(width 0)
				(type default)
			)
			(fill no)
			(layer "B.CrtYd")
		)
		(fp_line
			(start -0.254 0.508)
			(end 0.254 0.508)
			(stroke
				(width 0.0254)
				(type default)
			)
			(layer "B.Fab")
		)
		(fp_line
			(start 0.254 0.508)
			(end 0.254 -0.508)
			(stroke
				(width 0.0254)
				(type default)
			)
			(layer "B.Fab")
		)
		(fp_line
			(start -0.254 -0.508)
			(end -0.254 0.508)
			(stroke
				(width 0.0254)
				(type default)
			)
			(layer "B.Fab")
		)
		(fp_line
			(start 0.254 -0.508)
			(end -0.254 -0.508)
			(stroke
				(width 0.0254)
				(type default)
			)
			(layer "B.Fab")
		)
		(pad "1" smd rect
			(at 0 -0.4191 90)
			(size 0.508 0.5334)
			(layers "B.Cu" "B.Mask" "B.Paste")
			(net "EXT_3.3V")
		)
		(pad "2" smd rect
			(at 0 0.4191 90)
			(size 0.508 0.5334)
			(layers "B.Cu" "B.Mask" "B.Paste")
			(net "GND")
		)
		(zone
			(layer "B.Cu")
			(hatch none 0.5)
			(connect_pads
				(clearance 0)
			)
			(min_thickness 0.25)
			(keepout
				(tracks not_allowed)
				(vias allowed)
				(pads allowed)
				(copperpour not_allowed)
				(footprints allowed)
			)
			(placement
				(enabled no)
				(sheetname "")
			)
			(fill
				(thermal_gap 0.5)
				(thermal_bridge_width 0.5)
				(island_removal_mode 0)
			)
			(polygon
				(pts
					(xy 27.3304 19.177) (xy 27.2796 19.177) (xy 27.2796 19.2278) (xy 27.3304 19.2278)
				)
			)
		)
	)
	(footprint ""
		(layer "B.Cu")
		(at 77.343 43.688)
		(property "Reference" "C137"
			(at 0.311988 4.4958 270)
			(unlocked yes)
			(layer "B.SilkS")
			(effects
				(font
					(size 0.7874 0.5842)
					(thickness 0.127)
				)
				(justify left mirror)
			)
		)
		(property "Value" "10UF"
			(at 0.148158 1.7526 270)
			(unlocked yes)
			(layer "B.Fab")
			(hide yes)
			(effects
				(font
					(size 1.27 0.9652)
					(thickness 0.000001)
				)
				(justify left mirror)
			)
		)
		(property "Device Type" "CAPC0058"
			(at 0.148158 1.7526 270)
			(unlocked yes)
			(layer "B.Fab")
			(hide yes)
			(effects
				(font
					(size 1.27 0.9652)
					(thickness 0.000001)
				)
				(justify left mirror)
			)
		)
		(duplicate_pad_numbers_are_jumpers no)
		(fp_circle
			(center 0 0)
			(end 0.127 0)
			(stroke
				(width 0.2032)
				(type default)
			)
			(fill no)
			(layer "B.SilkS")
		)
		(fp_poly
			(pts
				(xy -0.7874 -1.6637) (xy 0.7874 -1.6637) (xy 0.7874 1.6637) (xy -0.7874 1.6637)
			)
			(stroke
				(width 0)
				(type default)
			)
			(fill no)
			(layer "B.CrtYd")
		)
		(fp_line
			(start -0.4064 -0.7874)
			(end -0.4064 0.8128)
			(stroke
				(width 0.0254)
				(type default)
			)
			(layer "B.Fab")
		)
		(fp_line
			(start -0.4064 0.8128)
			(end 0.4064 0.8128)
			(stroke
				(width 0.0254)
				(type default)
			)
			(layer "B.Fab")
		)
		(fp_line
			(start 0.4064 -0.7874)
			(end -0.4064 -0.7874)
			(stroke
				(width 0.0254)
				(type default)
			)
			(layer "B.Fab")
		)
		(fp_line
			(start 0.4064 0.8128)
			(end 0.4064 -0.7874)
			(stroke
				(width 0.0254)
				(type default)
			)
			(layer "B.Fab")
		)
		(pad "1" smd rect
			(at 0 -0.8001 180)
			(size 0.8636 0.9652)
			(layers "B.Cu" "B.Mask" "B.Paste")
			(net "DDR_VTT")
		)
		(pad "2" smd rect
			(at 0 0.8001 180)
			(size 0.8636 0.9652)
			(layers "B.Cu" "B.Mask" "B.Paste")
			(net "GND")
		)
		(zone
			(layer "B.Cu")
			(hatch none 0.5)
			(connect_pads
				(clearance 0)
			)
			(min_thickness 0.25)
			(keepout
				(tracks not_allowed)
				(vias allowed)
				(pads allowed)
				(copperpour not_allowed)
				(footprints allowed)
			)
			(placement
				(enabled no)
				(sheetname "")
			)
			(fill
				(thermal_gap 0.5)
				(thermal_bridge_width 0.5)
				(island_removal_mode 0)
			)
			(polygon
				(pts
					(xy 77.4065 43.434) (xy 77.2795 43.434) (xy 77.2795 43.942) (xy 77.4065 43.942)
				)
			)
		)
	)
	(footprint ""
		(layer "B.Cu")
		(at 48.768 4.445 180)
		(property "Reference" "C280"
			(at -0.98933 -0.508 270)
			(unlocked yes)
			(layer "B.SilkS")
			(effects
				(font
					(size 0.7874 0.5842)
					(thickness 0.127)
				)
				(justify left mirror)
			)
		)
		(property "Value" "22UF"
			(at 0.148158 1.7526 90)
			(unlocked yes)
			(layer "B.Fab")
			(hide yes)
			(effects
				(font
					(size 1.27 0.9652)
					(thickness 0.000001)
				)
				(justify left mirror)
			)
		)
		(property "Device Type" "CAPC0063"
			(at 0.148158 1.7526 90)
			(unlocked yes)
			(layer "B.Fab")
			(hide yes)
			(effects
				(font
					(size 1.27 0.9652)
					(thickness 0.000001)
				)
				(justify left mirror)
			)
		)
		(duplicate_pad_numbers_are_jumpers no)
		(fp_circle
			(center 0 0)
			(end -0.127 0)
			(stroke
				(width 0.2032)
				(type default)
			)
			(fill no)
			(layer "B.SilkS")
		)
		(fp_poly
			(pts
				(xy -0.7874 -1.6637) (xy 0.7874 -1.6637) (xy 0.7874 1.6637) (xy -0.7874 1.6637)
			)
			(stroke
				(width 0)
				(type default)
			)
			(fill no)
			(layer "B.CrtYd")
		)
		(fp_line
			(start 0.4064 0.8128)
			(end 0.4064 -0.7874)
			(stroke
				(width 0.0254)
				(type default)
			)
			(layer "B.Fab")
		)
		(fp_line
			(start 0.4064 -0.7874)
			(end -0.4064 -0.7874)
			(stroke
				(width 0.0254)
				(type default)
			)
			(layer "B.Fab")
		)
		(fp_line
			(start -0.4064 0.8128)
			(end 0.4064 0.8128)
			(stroke
				(width 0.0254)
				(type default)
			)
			(layer "B.Fab")
		)
		(fp_line
			(start -0.4064 -0.7874)
			(end -0.4064 0.8128)
			(stroke
				(width 0.0254)
				(type default)
			)
			(layer "B.Fab")
		)
		(pad "1" smd rect
			(at 0 -0.8001)
			(size 0.8636 0.9652)
			(layers "B.Cu" "B.Mask" "B.Paste")
			(net "VDDA_SERDES")
		)
		(pad "2" smd rect
			(at 0 0.8001)
			(size 0.8636 0.9652)
			(layers "B.Cu" "B.Mask" "B.Paste")
			(net "GND")
		)
		(zone
			(layer "B.Cu")
			(hatch none 0.5)
			(connect_pads
				(clearance 0)
			)
			(min_thickness 0.25)
			(keepout
				(tracks not_allowed)
				(vias allowed)
				(pads allowed)
				(copperpour not_allowed)
				(footprints allowed)
			)
			(placement
				(enabled no)
				(sheetname "")
			)
			(fill
				(thermal_gap 0.5)
				(thermal_bridge_width 0.5)
				(island_removal_mode 0)
			)
			(polygon
				(pts
					(xy 48.7045 4.699) (xy 48.8315 4.699) (xy 48.8315 4.191) (xy 48.7045 4.191)
				)
			)
		)
	)
	(footprint ""
		(layer "B.Cu")
		(at 57.023 47.244)
		(property "Reference" "TP32"
			(at 0.10033 4.064 270)
			(unlocked yes)
			(layer "B.SilkS")
			(effects
				(font
					(size 0.7874 0.5842)
					(thickness 0.127)
				)
				(justify left mirror)
			)
		)
		(property "Value" "*"
			(at 0.4826 -0.14732 0)
			(unlocked yes)
			(layer "B.Fab")
			(hide yes)
			(effects
				(font
					(size 1.27 0.9652)
					(thickness 0.000001)
				)
				(justify left mirror)
			)
		)
		(property "Device Type" "TP_SMALL"
			(at 0.4826 -0.14732 0)
			(unlocked yes)
			(layer "B.Fab")
			(hide yes)
			(effects
				(font
					(size 1.27 0.9652)
					(thickness 0.000001)
				)
				(justify left mirror)
			)
		)
		(duplicate_pad_numbers_are_jumpers no)
		(fp_line
			(start -0.8636 -0.8636)
			(end 0.8636 -0.8636)
			(stroke
				(width 0.1524)
				(type default)
			)
			(layer "B.SilkS")
		)
		(fp_line
			(start -0.8636 0.8636)
			(end -0.8636 -0.8636)
			(stroke
				(width 0.1524)
				(type default)
			)
			(layer "B.SilkS")
		)
		(fp_line
			(start 0.8636 -0.8636)
			(end 0.8636 0.8636)
			(stroke
				(width 0.1524)
				(type default)
			)
			(layer "B.SilkS")
		)
		(fp_line
			(start 0.8636 0.8636)
			(end -0.8636 0.8636)
			(stroke
				(width 0.1524)
				(type default)
			)
			(layer "B.SilkS")
		)
		(fp_poly
			(pts
				(xy 0.635 -0.635) (xy 0.635 0.635) (xy -0.635 0.635) (xy -0.635 -0.635)
			)
			(stroke
				(width 0)
				(type default)
			)
			(fill no)
			(layer "B.CrtYd")
		)
		(pad "1" smd rect
			(at 0 0 180)
			(size 1.27 1.27)
			(layers "B.Cu" "B.Mask" "B.Paste")
			(net "GH_PHASE1")
		)
	)
	(footprint ""
		(layer "B.Cu")
		(at 75.451005 6.698996)
		(property "Reference" "V_A-DQ06"
			(at 0 0 0)
			(layer "B.SilkS")
			(hide yes)
			(effects
				(font
					(size 1.27 1.27)
				)
				(justify mirror)
			)
		)
		(property "Value" ""
			(at 0 0 0)
			(layer "B.Fab")
			(effects
				(font
					(size 1.27 1.27)
				)
				(justify mirror)
			)
		)
		(duplicate_pad_numbers_are_jumpers no)
		(pad "1" thru_hole circle
			(at 0 0 180)
			(size 0.4572 0.4572)
			(drill 0.20574)
			(layers "*.Cu" "*.Mask")
			(remove_unused_layers no)
			(net "DDR0_32A_DQ6")
			(clearance 0.1143)
			(thermal_gap 0.1143)
		)
	)
	(footprint ""
		(layer "B.Cu")
		(at 28.448 25.781)
		(property "Reference" "TP17"
			(at 0.762 1.42367 0)
			(unlocked yes)
			(layer "B.SilkS")
			(effects
				(font
					(size 0.7874 0.5842)
					(thickness 0.127)
				)
				(justify left mirror)
			)
		)
		(property "Value" "*"
			(at 0.4826 -0.14732 0)
			(unlocked yes)
			(layer "B.Fab")
			(hide yes)
			(effects
				(font
					(size 1.27 0.9652)
					(thickness 0.000001)
				)
				(justify left mirror)
			)
		)
		(property "Device Type" "TP_SMALL"
			(at 0.4826 -0.14732 0)
			(unlocked yes)
			(layer "B.Fab")
			(hide yes)
			(effects
				(font
					(size 1.27 0.9652)
					(thickness 0.000001)
				)
				(justify left mirror)
			)
		)
		(duplicate_pad_numbers_are_jumpers no)
		(fp_line
			(start -0.8636 -0.8636)
			(end 0.8636 -0.8636)
			(stroke
				(width 0.1524)
				(type default)
			)
			(layer "B.SilkS")
		)
		(fp_line
			(start -0.8636 0.8636)
			(end -0.8636 -0.8636)
			(stroke
				(width 0.1524)
				(type default)
			)
			(layer "B.SilkS")
		)
		(fp_line
			(start 0.8636 -0.8636)
			(end 0.8636 0.8636)
			(stroke
				(width 0.1524)
				(type default)
			)
			(layer "B.SilkS")
		)
		(fp_line
			(start 0.8636 0.8636)
			(end -0.8636 0.8636)
			(stroke
				(width 0.1524)
				(type default)
			)
			(layer "B.SilkS")
		)
		(fp_poly
			(pts
				(xy 0.635 -0.635) (xy 0.635 0.635) (xy -0.635 0.635) (xy -0.635 -0.635)
			)
			(stroke
				(width 0)
				(type default)
			)
			(fill no)
			(layer "B.CrtYd")
		)
		(pad "1" smd rect
			(at 0 0 180)
			(size 1.27 1.27)
			(layers "B.Cu" "B.Mask" "B.Paste")
			(net "NFP_FAIL_SAFE_BOOT_L")
		)
	)
	(footprint ""
		(layer "B.Cu")
		(at 58.928 37.465 90)
		(property "Reference" "C58"
			(at -1.016 -3.20167 270)
			(unlocked yes)
			(layer "B.SilkS")
			(effects
				(font
					(size 0.7874 0.5842)
					(thickness 0.127)
				)
				(justify left mirror)
			)
		)
		(property "Value" "100UF"
			(at 0.78232 0.4826 0)
			(unlocked yes)
			(layer "B.Fab")
			(hide yes)
			(effects
				(font
					(size 1.27 0.9652)
					(thickness 0.000001)
				)
				(justify left mirror)
			)
		)
		(property "Device Type" "CAPC0087"
			(at 0.78232 0.4826 0)
			(unlocked yes)
			(layer "B.Fab")
			(hide yes)
			(effects
				(font
					(size 1.27 0.9652)
					(thickness 0.000001)
				)
				(justify left mirror)
			)
		)
		(duplicate_pad_numbers_are_jumpers no)
		(fp_circle
			(center 0 0)
			(end 0 0.508)
			(stroke
				(width 0.2032)
				(type default)
			)
			(fill no)
			(layer "B.SilkS")
		)
		(fp_poly
			(pts
				(xy 1.27 2.9464) (xy -1.27 2.9464) (xy -1.27 -2.9464) (xy 1.27 -2.9464)
			)
			(stroke
				(width 0)
				(type default)
			)
			(fill no)
			(layer "B.CrtYd")
		)
		(fp_line
			(start 1.016 -2.794)
			(end -1.016 -2.794)
			(stroke
				(width 0.0254)
				(type default)
			)
			(layer "B.Fab")
		)
		(fp_line
			(start -1.016 -2.794)
			(end -1.016 2.794)
			(stroke
				(width 0.0254)
				(type default)
			)
			(layer "B.Fab")
		)
		(fp_line
			(start 1.016 2.794)
			(end 1.016 -2.794)
			(stroke
				(width 0.0254)
				(type default)
			)
			(layer "B.Fab")
		)
		(fp_line
			(start -1.016 2.794)
			(end 1.016 2.794)
			(stroke
				(width 0.0254)
				(type default)
			)
			(layer "B.Fab")
		)
		(pad "1" smd rect
			(at 0 -1.6764 270)
			(size 1.524 1.524)
			(layers "B.Cu" "B.Mask" "B.Paste")
			(net "VDD_CORE")
		)
		(pad "2" smd rect
			(at 0 1.6764 270)
			(size 1.524 1.524)
			(layers "B.Cu" "B.Mask" "B.Paste")
			(net "GND")
		)
		(zone
			(layer "B.Cu")
			(hatch none 0.5)
			(connect_pads
				(clearance 0)
			)
			(min_thickness 0.25)
			(keepout
				(tracks not_allowed)
				(vias allowed)
				(pads allowed)
				(copperpour not_allowed)
				(footprints allowed)
			)
			(placement
				(enabled no)
				(sheetname "")
			)
			(fill
				(thermal_gap 0.5)
				(thermal_bridge_width 0.5)
				(island_removal_mode 0)
			)
			(polygon
				(pts
					(xy 58.039 36.6776) (xy 58.039 38.2524) (xy 58.1914 38.2524) (xy 58.1914 36.6776)
				)
			)
		)
		(zone
			(layer "B.Cu")
			(hatch none 0.5)
			(connect_pads
				(clearance 0)
			)
			(min_thickness 0.25)
			(keepout
				(tracks not_allowed)
				(vias allowed)
				(pads allowed)
				(copperpour not_allowed)
				(footprints allowed)
			)
			(placement
				(enabled no)
				(sheetname "")
			)
			(fill
				(thermal_gap 0.5)
				(thermal_bridge_width 0.5)
				(island_removal_mode 0)
			)
			(polygon
				(pts
					(xy 59.6646 36.6776) (xy 59.6646 38.2524) (xy 59.817 38.2524) (xy 59.817 36.6776)
				)
			)
		)
		(zone
			(layer "B.Cu")
			(hatch none 0.5)
			(connect_pads
				(clearance 0)
			)
			(min_thickness 0.25)
			(keepout
				(tracks allowed)
				(vias not_allowed)
				(pads allowed)
				(copperpour not_allowed)
				(footprints allowed)
			)
			(placement
				(enabled no)
				(sheetname "")
			)
			(fill
				(thermal_gap 0.5)
				(thermal_bridge_width 0.5)
				(island_removal_mode 0)
			)
			(polygon
				(pts
					(xy 60.5282 36.6776) (xy 60.5282 38.2524) (xy 57.3278 38.2524) (xy 57.3278 36.6776)
				)
			)
		)
	)
	(footprint ""
		(layer "B.Cu")
		(at 77.851 4.699 90)
		(property "Reference" "U17"
			(at 5.3975 6.35 0)
			(unlocked yes)
			(layer "B.SilkS")
			(effects
				(font
					(size 1.27 0.9652)
					(thickness 0.1524)
				)
				(justify left mirror)
			)
		)
		(property "Value" ""
			(at 0 0 90)
			(layer "B.Fab")
			(effects
				(font
					(size 1.27 1.27)
				)
				(justify mirror)
			)
		)
		(property "Component Value" "VALUE"
			(at 0.399999 -9.402597 90)
			(unlocked yes)
			(layer "User.4")
			(effects
				(font
					(size 0.254 0.254)
					(thickness 0.000001)
				)
				(justify mirror)
			)
		)
		(property "Device Type" "MEMC0051"
			(at 5.909996 -11.648211 90)
			(unlocked yes)
			(layer "B.Fab")
			(hide yes)
			(effects
				(font
					(size 1.27 0.9652)
					(thickness 0.000001)
				)
				(justify left mirror)
			)
		)
		(duplicate_pad_numbers_are_jumpers no)
		(fp_line
			(start 4.499991 -7.000011)
			(end 4.499991 7.000011)
			(stroke
				(width 0.1524)
				(type default)
			)
			(layer "B.SilkS")
		)
		(fp_line
			(start -4.499991 -7.000011)
			(end 4.499991 -7.000011)
			(stroke
				(width 0.1524)
				(type default)
			)
			(layer "B.SilkS")
		)
		(fp_line
			(start 4.499991 -5.999988)
			(end 3.499993 -7.000011)
			(stroke
				(width 0.1524)
				(type default)
			)
			(layer "B.SilkS")
		)
		(fp_line
			(start 4.499991 7.000011)
			(end -4.499991 7.000011)
			(stroke
				(width 0.1524)
				(type default)
			)
			(layer "B.SilkS")
		)
		(fp_line
			(start -4.499991 7.000011)
			(end -4.499991 -7.000011)
			(stroke
				(width 0.1524)
				(type default)
			)
			(layer "B.SilkS")
		)
		(fp_poly
			(pts
				(xy 7.50001 10.000005) (xy -7.50001 10.000005) (xy -7.50001 -10.000005) (xy 7.50001 -10.000005)
			)
			(stroke
				(width 0)
				(type default)
			)
			(fill no)
			(layer "B.CrtYd")
		)
		(fp_line
			(start 4.499991 -7.000011)
			(end 4.499991 7.000011)
			(stroke
				(width 0.1)
				(type default)
			)
			(layer "B.Fab")
		)
		(fp_line
			(start -4.499991 -7.000011)
			(end 4.499991 -7.000011)
			(stroke
				(width 0.1)
				(type default)
			)
			(layer "B.Fab")
		)
		(fp_line
			(start 4.499991 -5.999988)
			(end 3.499993 -7.000011)
			(stroke
				(width 0.1)
				(type default)
			)
			(layer "B.Fab")
		)
		(fp_line
			(start 4.499991 7.000011)
			(end -4.499991 7.000011)
			(stroke
				(width 0.1)
				(type default)
			)
			(layer "B.Fab")
		)
		(fp_line
			(start -4.499991 7.000011)
			(end -4.499991 -7.000011)
			(stroke
				(width 0.1)
				(type default)
			)
			(layer "B.Fab")
		)
		(fp_text user "1"
			(at 4.16433 -7.366 0)
			(unlocked yes)
			(layer "B.SilkS")
			(effects
				(font
					(size 0.7874 0.5842)
					(thickness 0.127)
				)
				(justify mirror)
			)
		)
		(fp_text user "A"
			(at 5.18033 -6.223 0)
			(unlocked yes)
			(layer "B.SilkS")
			(effects
				(font
					(size 0.7874 0.5842)
					(thickness 0.127)
				)
				(justify mirror)
			)
		)
		(pad "A1" smd circle
			(at 3.199994 -5.999988 270)
			(size 0.3556 0.3556)
			(layers "B.Cu" "B.Mask" "B.Paste")
			(net "DDR_VDDQ")
		)
		(pad "A2" smd circle
			(at 2.399995 -5.999988 270)
			(size 0.3556 0.3556)
			(layers "B.Cu" "B.Mask" "B.Paste")
			(net "DDR0_32A_DQ12")
		)
		(pad "A3" smd circle
			(at 1.599997 -5.999988 270)
			(size 0.3556 0.3556)
			(layers "B.Cu" "B.Mask" "B.Paste")
			(net "DDR0_32A_DQ14")
		)
		(pad "A7" smd circle
			(at -1.599997 -5.999988 270)
			(size 0.3556 0.3556)
			(layers "B.Cu" "B.Mask" "B.Paste")
			(net "DDR0_32A_DQ13")
		)
		(pad "A8" smd circle
			(at -2.399995 -5.999988 270)
			(size 0.3556 0.3556)
			(layers "B.Cu" "B.Mask" "B.Paste")
			(net "DDR_VDDQ")
		)
		(pad "A9" smd circle
			(at -3.199994 -5.999988 270)
			(size 0.3556 0.3556)
			(layers "B.Cu" "B.Mask" "B.Paste")
			(net "GND")
		)
		(pad "B1" smd circle
			(at 3.199994 -5.19999 270)
			(size 0.3556 0.3556)
			(layers "B.Cu" "B.Mask" "B.Paste")
			(net "GND")
		)
		(pad "B2" smd circle
			(at 2.399995 -5.19999 270)
			(size 0.3556 0.3556)
			(layers "B.Cu" "B.Mask" "B.Paste")
			(net "DDR_VDDQ")
		)
		(pad "B3" smd circle
			(at 1.599997 -5.19999 270)
			(size 0.3556 0.3556)
			(layers "B.Cu" "B.Mask" "B.Paste")
			(net "GND")
		)
		(pad "B7" smd circle
			(at -1.599997 -5.19999 270)
			(size 0.3556 0.3556)
			(layers "B.Cu" "B.Mask" "B.Paste")
			(net "DDR0_32A_DQS1_N")
		)
		(pad "B8" smd circle
			(at -2.399995 -5.19999 270)
			(size 0.3556 0.3556)
			(layers "B.Cu" "B.Mask" "B.Paste")
			(net "DDR0_32A_DQ11")
		)
		(pad "B9" smd circle
			(at -3.199994 -5.19999 270)
			(size 0.3556 0.3556)
			(layers "B.Cu" "B.Mask" "B.Paste")
			(net "GND")
		)
		(pad "C1" smd circle
			(at 3.199994 -4.399991 270)
			(size 0.3556 0.3556)
			(layers "B.Cu" "B.Mask" "B.Paste")
			(net "DDR_VDDQ")
		)
		(pad "C2" smd circle
			(at 2.399995 -4.399991 270)
			(size 0.3556 0.3556)
			(layers "B.Cu" "B.Mask" "B.Paste")
			(net "DDR0_32A_DQ15")
		)
		(pad "C3" smd circle
			(at 1.599997 -4.399991 270)
			(size 0.3556 0.3556)
			(layers "B.Cu" "B.Mask" "B.Paste")
			(net "DDR0_32A_DQ9")
		)
		(pad "C7" smd circle
			(at -1.599997 -4.399991 270)
			(size 0.3556 0.3556)
			(layers "B.Cu" "B.Mask" "B.Paste")
			(net "DDR0_32A_DQS1_P")
		)
		(pad "C8" smd circle
			(at -2.399995 -4.399991 270)
			(size 0.3556 0.3556)
			(layers "B.Cu" "B.Mask" "B.Paste")
			(net "DDR0_32A_DQ10")
		)
		(pad "C9" smd circle
			(at -3.199994 -4.399991 270)
			(size 0.3556 0.3556)
			(layers "B.Cu" "B.Mask" "B.Paste")
			(net "DDR_VDDQ")
		)
		(pad "D1" smd circle
			(at 3.199994 -3.599993 270)
			(size 0.3556 0.3556)
			(layers "B.Cu" "B.Mask" "B.Paste")
			(net "GND")
		)
		(pad "D2" smd circle
			(at 2.399995 -3.599993 270)
			(size 0.3556 0.3556)
			(layers "B.Cu" "B.Mask" "B.Paste")
			(net "DDR_VDDQ")
		)
		(pad "D3" smd circle
			(at 1.599997 -3.599993 270)
			(size 0.3556 0.3556)
			(layers "B.Cu" "B.Mask" "B.Paste")
			(net "DDR0_32A_DM1")
		)
		(pad "D7" smd circle
			(at -1.599997 -3.599993 270)
			(size 0.3556 0.3556)
			(layers "B.Cu" "B.Mask" "B.Paste")
			(net "DDR0_32A_DQ8")
		)
		(pad "D8" smd circle
			(at -2.399995 -3.599993 270)
			(size 0.3556 0.3556)
			(layers "B.Cu" "B.Mask" "B.Paste")
			(net "GND")
		)
		(pad "D9" smd circle
			(at -3.199994 -3.599993 270)
			(size 0.3556 0.3556)
			(layers "B.Cu" "B.Mask" "B.Paste")
			(net "DDR_VDDQ")
		)
		(pad "E1" smd circle
			(at 3.199994 -2.799994 270)
			(size 0.3556 0.3556)
			(layers "B.Cu" "B.Mask" "B.Paste")
			(net "GND")
		)
		(pad "E2" smd circle
			(at 2.399995 -2.799994 270)
			(size 0.3556 0.3556)
			(layers "B.Cu" "B.Mask" "B.Paste")
			(net "GND")
		)
		(pad "E3" smd circle
			(at 1.599997 -2.799994 270)
			(size 0.3556 0.3556)
			(layers "B.Cu" "B.Mask" "B.Paste")
			(net "DDR0_32A_DQ5")
		)
		(pad "E7" smd circle
			(at -1.599997 -2.799994 270)
			(size 0.3556 0.3556)
			(layers "B.Cu" "B.Mask" "B.Paste")
			(net "DDR0_32A_DM0")
		)
		(pad "E8" smd circle
			(at -2.399995 -2.799994 270)
			(size 0.3556 0.3556)
			(layers "B.Cu" "B.Mask" "B.Paste")
			(net "GND")
		)
		(pad "E9" smd circle
			(at -3.199994 -2.799994 270)
			(size 0.3556 0.3556)
			(layers "B.Cu" "B.Mask" "B.Paste")
			(net "DDR_VDDQ")
		)
		(pad "F1" smd circle
			(at 3.199994 -1.999996 270)
			(size 0.3556 0.3556)
			(layers "B.Cu" "B.Mask" "B.Paste")
			(net "DDR_VDDQ")
		)
		(pad "F2" smd circle
			(at 2.399995 -1.999996 270)
			(size 0.3556 0.3556)
			(layers "B.Cu" "B.Mask" "B.Paste")
			(net "DDR0_32A_DQ0")
		)
		(pad "F3" smd circle
			(at 1.599997 -1.999996 270)
			(size 0.3556 0.3556)
			(layers "B.Cu" "B.Mask" "B.Paste")
			(net "DDR0_32A_DQS0_P")
		)
		(pad "F7" smd circle
			(at -1.599997 -1.999996 270)
			(size 0.3556 0.3556)
			(layers "B.Cu" "B.Mask" "B.Paste")
			(net "DDR0_32A_DQ6")
		)
		(pad "F8" smd circle
			(at -2.399995 -1.999996 270)
			(size 0.3556 0.3556)
			(layers "B.Cu" "B.Mask" "B.Paste")
			(net "DDR0_32A_DQ7")
		)
		(pad "F9" smd circle
			(at -3.199994 -1.999996 270)
			(size 0.3556 0.3556)
			(layers "B.Cu" "B.Mask" "B.Paste")
			(net "GND")
		)
		(pad "G1" smd circle
			(at 3.199994 -1.199998 270)
			(size 0.3556 0.3556)
			(layers "B.Cu" "B.Mask" "B.Paste")
			(net "GND")
		)
		(pad "G2" smd circle
			(at 2.399995 -1.199998 270)
			(size 0.3556 0.3556)
			(layers "B.Cu" "B.Mask" "B.Paste")
			(net "DDR0_32A_DQ1")
		)
		(pad "G3" smd circle
			(at 1.599997 -1.199998 270)
			(size 0.3556 0.3556)
			(layers "B.Cu" "B.Mask" "B.Paste")
			(net "DDR0_32A_DQS0_N")
		)
		(pad "G7" smd circle
			(at -1.599997 -1.199998 270)
			(size 0.3556 0.3556)
			(layers "B.Cu" "B.Mask" "B.Paste")
			(net "DDR_VDDQ")
		)
		(pad "G8" smd circle
			(at -2.399995 -1.199998 270)
			(size 0.3556 0.3556)
			(layers "B.Cu" "B.Mask" "B.Paste")
			(net "GND")
		)
		(pad "G9" smd circle
			(at -3.199994 -1.199998 270)
			(size 0.3556 0.3556)
			(layers "B.Cu" "B.Mask" "B.Paste")
			(net "GND")
		)
		(pad "H1" smd circle
			(at 3.199994 -0.399999 270)
			(size 0.3556 0.3556)
			(layers "B.Cu" "B.Mask" "B.Paste")
			(net "DDR0_32A_VREF0B")
		)
		(pad "H2" smd circle
			(at 2.399995 -0.399999 270)
			(size 0.3556 0.3556)
			(layers "B.Cu" "B.Mask" "B.Paste")
			(net "DDR_VDDQ")
		)
		(pad "H3" smd circle
			(at 1.599997 -0.399999 270)
			(size 0.3556 0.3556)
			(layers "B.Cu" "B.Mask" "B.Paste")
			(net "DDR0_32A_DQ4")
		)
		(pad "H7" smd circle
			(at -1.599997 -0.399999 270)
			(size 0.3556 0.3556)
			(layers "B.Cu" "B.Mask" "B.Paste")
			(net "DDR0_32A_DQ3")
		)
		(pad "H8" smd circle
			(at -2.399995 -0.399999 270)
			(size 0.3556 0.3556)
			(layers "B.Cu" "B.Mask" "B.Paste")
			(net "DDR0_32A_DQ2")
		)
		(pad "H9" smd circle
			(at -3.199994 -0.399999 270)
			(size 0.3556 0.3556)
			(layers "B.Cu" "B.Mask" "B.Paste")
			(net "DDR_VDDQ")
		)
		(pad "J1" smd circle
			(at 3.199994 0.399999 270)
			(size 0.3556 0.3556)
			(layers "B.Cu" "B.Mask" "B.Paste")
			(net "Net_91")
		)
		(pad "J2" smd circle
			(at 2.399995 0.399999 270)
			(size 0.3556 0.3556)
			(layers "B.Cu" "B.Mask" "B.Paste")
			(net "GND")
		)
		(pad "J3" smd circle
			(at 1.599997 0.399999 270)
			(size 0.3556 0.3556)
			(layers "B.Cu" "B.Mask" "B.Paste")
			(net "DDR0_32A_RAS_L")
		)
		(pad "J7" smd circle
			(at -1.599997 0.399999 270)
			(size 0.3556 0.3556)
			(layers "B.Cu" "B.Mask" "B.Paste")
			(net "DDR0_32A_CK0_P")
		)
		(pad "J8" smd circle
			(at -2.399995 0.399999 270)
			(size 0.3556 0.3556)
			(layers "B.Cu" "B.Mask" "B.Paste")
			(net "GND")
		)
		(pad "J9" smd circle
			(at -3.199994 0.399999 270)
			(size 0.3556 0.3556)
			(layers "B.Cu" "B.Mask" "B.Paste")
			(net "Net_496")
		)
		(pad "K1" smd circle
			(at 3.199994 1.199998 270)
			(size 0.3556 0.3556)
			(layers "B.Cu" "B.Mask" "B.Paste")
			(net "DDR0_32A_ODT0")
		)
		(pad "K2" smd circle
			(at 2.399995 1.199998 270)
			(size 0.3556 0.3556)
			(layers "B.Cu" "B.Mask" "B.Paste")
			(net "DDR_VDDQ")
		)
		(pad "K3" smd circle
			(at 1.599997 1.199998 270)
			(size 0.3556 0.3556)
			(layers "B.Cu" "B.Mask" "B.Paste")
			(net "DDR0_32A_CAS_L")
		)
		(pad "K7" smd circle
			(at -1.599997 1.199998 270)
			(size 0.3556 0.3556)
			(layers "B.Cu" "B.Mask" "B.Paste")
			(net "DDR0_32A_CK0_N")
		)
		(pad "K8" smd circle
			(at -2.399995 1.199998 270)
			(size 0.3556 0.3556)
			(layers "B.Cu" "B.Mask" "B.Paste")
			(net "DDR_VDDQ")
		)
		(pad "K9" smd circle
			(at -3.199994 1.199998 270)
			(size 0.3556 0.3556)
			(layers "B.Cu" "B.Mask" "B.Paste")
			(net "DDR0_32A_CKE0")
		)
		(pad "L1" smd circle
			(at 3.199994 1.999996 270)
			(size 0.3556 0.3556)
			(layers "B.Cu" "B.Mask" "B.Paste")
			(net "Net_494")
		)
		(pad "L2" smd circle
			(at 2.399995 1.999996 270)
			(size 0.3556 0.3556)
			(layers "B.Cu" "B.Mask" "B.Paste")
			(net "DDR0_32A_CS0_L")
		)
		(pad "L3" smd circle
			(at 1.599997 1.999996 270)
			(size 0.3556 0.3556)
			(layers "B.Cu" "B.Mask" "B.Paste")
			(net "DDR0_32A_WE_L")
		)
		(pad "L7" smd circle
			(at -1.599997 1.999996 270)
			(size 0.3556 0.3556)
			(layers "B.Cu" "B.Mask" "B.Paste")
			(net "DDR0_32A_A10")
		)
		(pad "L8" smd circle
			(at -2.399995 1.999996 270)
			(size 0.3556 0.3556)
			(layers "B.Cu" "B.Mask" "B.Paste")
			(net "12N2312")
		)
		(pad "L9" smd circle
			(at -3.199994 1.999996 270)
			(size 0.3556 0.3556)
			(layers "B.Cu" "B.Mask" "B.Paste")
			(net "Net_497")
		)
		(pad "M1" smd circle
			(at 3.199994 2.799994 270)
			(size 0.3556 0.3556)
			(layers "B.Cu" "B.Mask" "B.Paste")
			(net "GND")
		)
		(pad "M2" smd circle
			(at 2.399995 2.799994 270)
			(size 0.3556 0.3556)
			(layers "B.Cu" "B.Mask" "B.Paste")
			(net "DDR0_32A_BA0")
		)
		(pad "M3" smd circle
			(at 1.599997 2.799994 270)
			(size 0.3556 0.3556)
			(layers "B.Cu" "B.Mask" "B.Paste")
			(net "DDR0_32A_BA2")
		)
		(pad "M7" smd circle
			(at -1.599997 2.799994 270)
			(size 0.3556 0.3556)
			(layers "B.Cu" "B.Mask" "B.Paste")
			(net "Net_495")
		)
		(pad "M8" smd circle
			(at -2.399995 2.799994 270)
			(size 0.3556 0.3556)
			(layers "B.Cu" "B.Mask" "B.Paste")
			(net "DDR0_32A_VREF0B")
		)
		(pad "M9" smd circle
			(at -3.199994 2.799994 270)
			(size 0.3556 0.3556)
			(layers "B.Cu" "B.Mask" "B.Paste")
			(net "GND")
		)
		(pad "N1" smd circle
			(at 3.199994 3.599993 270)
			(size 0.3556 0.3556)
			(layers "B.Cu" "B.Mask" "B.Paste")
			(net "DDR_VDDQ")
		)
		(pad "N2" smd circle
			(at 2.399995 3.599993 270)
			(size 0.3556 0.3556)
			(layers "B.Cu" "B.Mask" "B.Paste")
			(net "DDR0_32A_A3")
		)
		(pad "N3" smd circle
			(at 1.599997 3.599993 270)
			(size 0.3556 0.3556)
			(layers "B.Cu" "B.Mask" "B.Paste")
			(net "DDR0_32A_A0")
		)
		(pad "N7" smd circle
			(at -1.599997 3.599993 270)
			(size 0.3556 0.3556)
			(layers "B.Cu" "B.Mask" "B.Paste")
			(net "DDR0_32A_A12")
		)
		(pad "N8" smd circle
			(at -2.399995 3.599993 270)
			(size 0.3556 0.3556)
			(layers "B.Cu" "B.Mask" "B.Paste")
			(net "DDR0_32A_BA1")
		)
		(pad "N9" smd circle
			(at -3.199994 3.599993 270)
			(size 0.3556 0.3556)
			(layers "B.Cu" "B.Mask" "B.Paste")
			(net "DDR_VDDQ")
		)
		(pad "P1" smd circle
			(at 3.199994 4.399991 270)
			(size 0.3556 0.3556)
			(layers "B.Cu" "B.Mask" "B.Paste")
			(net "GND")
		)
		(pad "P2" smd circle
			(at 2.399995 4.399991 270)
			(size 0.3556 0.3556)
			(layers "B.Cu" "B.Mask" "B.Paste")
			(net "DDR0_32A_A5")
		)
		(pad "P3" smd circle
			(at 1.599997 4.399991 270)
			(size 0.3556 0.3556)
			(layers "B.Cu" "B.Mask" "B.Paste")
			(net "DDR0_32A_A2")
		)
		(pad "P7" smd circle
			(at -1.599997 4.399991 270)
			(size 0.3556 0.3556)
			(layers "B.Cu" "B.Mask" "B.Paste")
			(net "DDR0_32A_A1")
		)
		(pad "P8" smd circle
			(at -2.399995 4.399991 270)
			(size 0.3556 0.3556)
			(layers "B.Cu" "B.Mask" "B.Paste")
			(net "DDR0_32A_A4")
		)
		(pad "P9" smd circle
			(at -3.199994 4.399991 270)
			(size 0.3556 0.3556)
			(layers "B.Cu" "B.Mask" "B.Paste")
			(net "GND")
		)
		(pad "R1" smd circle
			(at 3.199994 5.19999 270)
			(size 0.3556 0.3556)
			(layers "B.Cu" "B.Mask" "B.Paste")
			(net "DDR_VDDQ")
		)
		(pad "R2" smd circle
			(at 2.399995 5.19999 270)
			(size 0.3556 0.3556)
			(layers "B.Cu" "B.Mask" "B.Paste")
			(net "DDR0_32A_A7")
		)
		(pad "R3" smd circle
			(at 1.599997 5.19999 270)
			(size 0.3556 0.3556)
			(layers "B.Cu" "B.Mask" "B.Paste")
			(net "DDR0_32A_A9")
		)
		(pad "R7" smd circle
			(at -1.599997 5.19999 270)
			(size 0.3556 0.3556)
			(layers "B.Cu" "B.Mask" "B.Paste")
			(net "DDR0_32A_A11")
		)
		(pad "R8" smd circle
			(at -2.399995 5.19999 270)
			(size 0.3556 0.3556)
			(layers "B.Cu" "B.Mask" "B.Paste")
			(net "DDR0_32A_A6")
		)
		(pad "R9" smd circle
			(at -3.199994 5.19999 270)
			(size 0.3556 0.3556)
			(layers "B.Cu" "B.Mask" "B.Paste")
			(net "DDR_VDDQ")
		)
		(pad "T1" smd circle
			(at 3.199994 5.999988 270)
			(size 0.3556 0.3556)
			(layers "B.Cu" "B.Mask" "B.Paste")
			(net "GND")
		)
		(pad "T2" smd circle
			(at 2.399995 5.999988 270)
			(size 0.3556 0.3556)
			(layers "B.Cu" "B.Mask" "B.Paste")
			(net "DDR0_32A_DRAMRST_L")
		)
		(pad "T3" smd circle
			(at 1.599997 5.999988 270)
			(size 0.3556 0.3556)
			(layers "B.Cu" "B.Mask" "B.Paste")
			(net "DDR0_32A_A13")
		)
		(pad "T7" smd circle
			(at -1.599997 5.999988 270)
			(size 0.3556 0.3556)
			(layers "B.Cu" "B.Mask" "B.Paste")
			(net "DDR0_32A_A14")
		)
		(pad "T8" smd circle
			(at -2.399995 5.999988 270)
			(size 0.3556 0.3556)
			(layers "B.Cu" "B.Mask" "B.Paste")
			(net "DDR0_32A_A8")
		)
		(pad "T9" smd circle
			(at -3.199994 5.999988 270)
			(size 0.3556 0.3556)
			(layers "B.Cu" "B.Mask" "B.Paste")
			(net "GND")
		)
	)
	(footprint ""
		(layer "B.Cu")
		(at 81.850992 25.013006)
		(property "Reference" "V3_A-A03"
			(at 0 0 0)
			(layer "B.SilkS")
			(hide yes)
			(effects
				(font
					(size 1.27 1.27)
				)
				(justify mirror)
			)
		)
		(property "Value" ""
			(at 0 0 0)
			(layer "B.Fab")
			(effects
				(font
					(size 1.27 1.27)
				)
				(justify mirror)
			)
		)
		(duplicate_pad_numbers_are_jumpers no)
		(pad "1" thru_hole circle
			(at 0 0 180)
			(size 0.4572 0.4572)
			(drill 0.20574)
			(layers "*.Cu" "*.Mask")
			(remove_unused_layers no)
			(net "DDR0_32A_A3")
			(clearance 0.1143)
			(thermal_gap 0.1143)
		)
	)
	(footprint ""
		(layer "B.Cu")
		(at 30.988 32.639)
		(property "Reference" "R175"
			(at -0.02667 4.953 270)
			(unlocked yes)
			(layer "B.SilkS")
			(effects
				(font
					(size 0.7874 0.5842)
					(thickness 0.127)
				)
				(justify left mirror)
			)
		)
		(property "Value" "0"
			(at 0.148158 1.3462 270)
			(unlocked yes)
			(layer "B.Fab")
			(hide yes)
			(effects
				(font
					(size 1.27 0.9652)
					(thickness 0.000001)
				)
				(justify left mirror)
			)
		)
		(property "Device Type" "REST1111"
			(at 0.148158 1.3462 270)
			(unlocked yes)
			(layer "B.Fab")
			(hide yes)
			(effects
				(font
					(size 1.27 0.9652)
					(thickness 0.000001)
				)
				(justify left mirror)
			)
		)
		(duplicate_pad_numbers_are_jumpers no)
		(fp_poly
			(pts
				(xy -0.635 1.0668) (xy -0.635 -1.0668) (xy 0.635 -1.0668) (xy 0.635 1.0668)
			)
			(stroke
				(width 0)
				(type default)
			)
			(fill no)
			(layer "B.CrtYd")
		)
		(fp_line
			(start -0.254 -0.508)
			(end -0.254 0.508)
			(stroke
				(width 0.0254)
				(type default)
			)
			(layer "B.Fab")
		)
		(fp_line
			(start -0.254 0.508)
			(end 0.254 0.508)
			(stroke
				(width 0.0254)
				(type default)
			)
			(layer "B.Fab")
		)
		(fp_line
			(start 0.254 -0.508)
			(end -0.254 -0.508)
			(stroke
				(width 0.0254)
				(type default)
			)
			(layer "B.Fab")
		)
		(fp_line
			(start 0.254 0.508)
			(end 0.254 -0.508)
			(stroke
				(width 0.0254)
				(type default)
			)
			(layer "B.Fab")
		)
		(pad "1" smd rect
			(at 0 -0.4191 180)
			(size 0.508 0.5334)
			(layers "B.Cu" "B.Mask" "B.Paste")
			(net "NFP_CORE_VID3")
		)
		(pad "2" smd rect
			(at 0 0.4191 180)
			(size 0.508 0.5334)
			(layers "B.Cu" "B.Mask" "B.Paste")
			(net "_NFP_CORE_VID3")
		)
		(zone
			(layer "B.Cu")
			(hatch none 0.5)
			(connect_pads
				(clearance 0)
			)
			(min_thickness 0.25)
			(keepout
				(tracks not_allowed)
				(vias allowed)
				(pads allowed)
				(copperpour not_allowed)
				(footprints allowed)
			)
			(placement
				(enabled no)
				(sheetname "")
			)
			(fill
				(thermal_gap 0.5)
				(thermal_bridge_width 0.5)
				(island_removal_mode 0)
			)
			(polygon
				(pts
					(xy 30.9626 32.6136) (xy 30.9626 32.6644) (xy 31.0134 32.6644) (xy 31.0134 32.6136)
				)
			)
		)
	)
	(footprint ""
		(layer "B.Cu")
		(at 82.65099 18.255996)
		(property "Reference" "V2_A-A01"
			(at 0 0 0)
			(layer "B.SilkS")
			(hide yes)
			(effects
				(font
					(size 1.27 1.27)
				)
				(justify mirror)
			)
		)
		(property "Value" ""
			(at 0 0 0)
			(layer "B.Fab")
			(effects
				(font
					(size 1.27 1.27)
				)
				(justify mirror)
			)
		)
		(duplicate_pad_numbers_are_jumpers no)
		(pad "1" thru_hole circle
			(at 0 0 180)
			(size 0.4572 0.4572)
			(drill 0.20574)
			(layers "*.Cu" "*.Mask")
			(remove_unused_layers no)
			(net "DDR0_32A_A1")
			(clearance 0.1143)
			(thermal_gap 0.1143)
		)
	)
	(footprint ""
		(layer "B.Cu")
		(at 69.236971 6.542024 180)
		(property "Reference" "C191"
			(at 0 0 0)
			(layer "B.SilkS")
			(hide yes)
			(effects
				(font
					(size 1.27 1.27)
				)
				(justify mirror)
			)
		)
		(property "Value" ""
			(at 0 0 0)
			(layer "B.Fab")
			(effects
				(font
					(size 1.27 1.27)
				)
				(justify mirror)
			)
		)
		(duplicate_pad_numbers_are_jumpers no)
		(fp_circle
			(center 0 0)
			(end -0.104648 0)
			(stroke
				(width 0.1016)
				(type default)
			)
			(fill no)
			(layer "B.SilkS")
		)
		(fp_poly
			(pts
				(xy 0.381 -0.889) (xy 0.381 0.889) (xy -0.381 0.889) (xy -0.381 -0.889)
			)
			(stroke
				(width 0)
				(type default)
			)
			(fill no)
			(layer "B.CrtYd")
		)
		(fp_line
			(start 0.508 1.016)
			(end 0.508 -1.016)
			(stroke
				(width 0.0254)
				(type default)
			)
			(layer "B.Fab")
		)
		(fp_line
			(start 0.508 -1.016)
			(end 0.254 -1.016)
			(stroke
				(width 0.0254)
				(type default)
			)
			(layer "B.Fab")
		)
		(fp_line
			(start 0.254 -1.016)
			(end -0.508 -1.016)
			(stroke
				(width 0.0254)
				(type default)
			)
			(layer "B.Fab")
		)
		(fp_line
			(start -0.508 1.016)
			(end 0.508 1.016)
			(stroke
				(width 0.0254)
				(type default)
			)
			(layer "B.Fab")
		)
		(fp_line
			(start -0.508 -1.016)
			(end -0.508 1.016)
			(stroke
				(width 0.0254)
				(type default)
			)
			(layer "B.Fab")
		)
		(pad "1" smd custom
			(at 0 -0.500126)
			(size 0.127 0.127)
			(layers "B.Cu" "B.Mask" "B.Paste")
			(net "DDR_VDDQ")
			(options
				(clearance outline)
				(anchor circle)
			)
			(primitives
				(gr_poly
					(pts
						(xy -0.1778 0.254) (xy 0.1778 0.254) (xy 0.254 0.1778) (xy 0.254 -0.1778) (xy 0.1778 -0.254) (xy -0.1778 -0.254)
						(xy -0.254 -0.1778) (xy -0.254 0.1778)
					)
					(width 0)
					(fill yes)
				)
			)
		)
		(pad "2" smd custom
			(at 0 0.500126)
			(size 0.127 0.127)
			(layers "B.Cu" "B.Mask" "B.Paste")
			(net "GND")
			(options
				(clearance outline)
				(anchor circle)
			)
			(primitives
				(gr_poly
					(pts
						(xy -0.1778 0.254) (xy 0.1778 0.254) (xy 0.254 0.1778) (xy 0.254 -0.1778) (xy 0.1778 -0.254) (xy -0.1778 -0.254)
						(xy -0.254 -0.1778) (xy -0.254 0.1778)
					)
					(width 0)
					(fill yes)
				)
			)
		)
	)
	(footprint ""
		(layer "B.Cu")
		(at 57.404 0.762 180)
		(property "Reference" "C159"
			(at 0.145212 0.8763 270)
			(unlocked yes)
			(layer "B.SilkS")
			(effects
				(font
					(size 0.7874 0.5842)
					(thickness 0.127)
				)
				(justify left mirror)
			)
		)
		(property "Value" "0.22UF"
			(at 0.091846 0.2921 90)
			(unlocked yes)
			(layer "B.Fab")
			(hide yes)
			(effects
				(font
					(size 0.7874 0.5842)
					(thickness 0.2032)
				)
				(justify left mirror)
			)
		)
		(property "Device Type" "CAPC0062"
			(at 0.091846 0.2921 90)
			(unlocked yes)
			(layer "B.Fab")
			(hide yes)
			(effects
				(font
					(size 0.7874 0.5842)
					(thickness 0.2032)
				)
				(justify left mirror)
			)
		)
		(duplicate_pad_numbers_are_jumpers no)
		(fp_poly
			(pts
				(xy -0.635 1.0668) (xy -0.635 -1.0668) (xy 0.635 -1.0668) (xy 0.635 1.0668)
			)
			(stroke
				(width 0)
				(type default)
			)
			(fill no)
			(layer "B.CrtYd")
		)
		(fp_line
			(start 0.254 0.508)
			(end 0.254 -0.508)
			(stroke
				(width 0.0254)
				(type default)
			)
			(layer "B.Fab")
		)
		(fp_line
			(start 0.254 -0.508)
			(end -0.254 -0.508)
			(stroke
				(width 0.0254)
				(type default)
			)
			(layer "B.Fab")
		)
		(fp_line
			(start -0.254 0.508)
			(end 0.254 0.508)
			(stroke
				(width 0.0254)
				(type default)
			)
			(layer "B.Fab")
		)
		(fp_line
			(start -0.254 -0.508)
			(end -0.254 0.508)
			(stroke
				(width 0.0254)
				(type default)
			)
			(layer "B.Fab")
		)
		(pad "1" smd rect
			(at 0 -0.4191)
			(size 0.508 0.5334)
			(layers "B.Cu" "B.Mask" "B.Paste")
			(net "_NFP_PCIE0_PER3_P")
		)
		(pad "2" smd rect
			(at 0 0.4191)
			(size 0.508 0.5334)
			(layers "B.Cu" "B.Mask" "B.Paste")
			(net "NFP_PCIE0_PER3_P")
		)
		(zone
			(layer "B.Cu")
			(hatch none 0.5)
			(connect_pads
				(clearance 0)
			)
			(min_thickness 0.25)
			(keepout
				(tracks not_allowed)
				(vias allowed)
				(pads allowed)
				(copperpour not_allowed)
				(footprints allowed)
			)
			(placement
				(enabled no)
				(sheetname "")
			)
			(fill
				(thermal_gap 0.5)
				(thermal_bridge_width 0.5)
				(island_removal_mode 0)
			)
			(polygon
				(pts
					(xy 57.4294 0.7874) (xy 57.4294 0.7366) (xy 57.3786 0.7366) (xy 57.3786 0.7874)
				)
			)
		)
	)
	(footprint ""
		(layer "B.Cu")
		(at 81.850992 30.612994)
		(property "Reference" "V3_A-BA1"
			(at 0 0 0)
			(layer "B.SilkS")
			(hide yes)
			(effects
				(font
					(size 1.27 1.27)
				)
				(justify mirror)
			)
		)
		(property "Value" ""
			(at 0 0 0)
			(layer "B.Fab")
			(effects
				(font
					(size 1.27 1.27)
				)
				(justify mirror)
			)
		)
		(duplicate_pad_numbers_are_jumpers no)
		(pad "1" thru_hole circle
			(at 0 0 180)
			(size 0.4572 0.4572)
			(drill 0.20574)
			(layers "*.Cu" "*.Mask")
			(remove_unused_layers no)
			(net "DDR0_32A_BA1")
			(clearance 0.1143)
			(thermal_gap 0.1143)
		)
	)
	(footprint ""
		(layer "B.Cu")
		(at 51.469036 0.762 180)
		(property "Reference" "C149"
			(at 0.145212 0.8763 270)
			(unlocked yes)
			(layer "B.SilkS")
			(effects
				(font
					(size 0.7874 0.5842)
					(thickness 0.127)
				)
				(justify left mirror)
			)
		)
		(property "Value" "0.22UF"
			(at 0.091846 0.2921 90)
			(unlocked yes)
			(layer "B.Fab")
			(hide yes)
			(effects
				(font
					(size 0.7874 0.5842)
					(thickness 0.2032)
				)
				(justify left mirror)
			)
		)
		(property "Device Type" "CAPC0062"
			(at 0.091846 0.2921 90)
			(unlocked yes)
			(layer "B.Fab")
			(hide yes)
			(effects
				(font
					(size 0.7874 0.5842)
					(thickness 0.2032)
				)
				(justify left mirror)
			)
		)
		(duplicate_pad_numbers_are_jumpers no)
		(fp_poly
			(pts
				(xy -0.635 1.0668) (xy -0.635 -1.0668) (xy 0.635 -1.0668) (xy 0.635 1.0668)
			)
			(stroke
				(width 0)
				(type default)
			)
			(fill no)
			(layer "B.CrtYd")
		)
		(fp_line
			(start 0.254 0.508)
			(end 0.254 -0.508)
			(stroke
				(width 0.0254)
				(type default)
			)
			(layer "B.Fab")
		)
		(fp_line
			(start 0.254 -0.508)
			(end -0.254 -0.508)
			(stroke
				(width 0.0254)
				(type default)
			)
			(layer "B.Fab")
		)
		(fp_line
			(start -0.254 0.508)
			(end 0.254 0.508)
			(stroke
				(width 0.0254)
				(type default)
			)
			(layer "B.Fab")
		)
		(fp_line
			(start -0.254 -0.508)
			(end -0.254 0.508)
			(stroke
				(width 0.0254)
				(type default)
			)
			(layer "B.Fab")
		)
		(pad "1" smd rect
			(at 0 -0.4191)
			(size 0.508 0.5334)
			(layers "B.Cu" "B.Mask" "B.Paste")
			(net "_NFP_PCIE0_PER6_P")
		)
		(pad "2" smd rect
			(at 0 0.4191)
			(size 0.508 0.5334)
			(layers "B.Cu" "B.Mask" "B.Paste")
			(net "NFP_PCIE0_PER6_P")
		)
		(zone
			(layer "B.Cu")
			(hatch none 0.5)
			(connect_pads
				(clearance 0)
			)
			(min_thickness 0.25)
			(keepout
				(tracks not_allowed)
				(vias allowed)
				(pads allowed)
				(copperpour not_allowed)
				(footprints allowed)
			)
			(placement
				(enabled no)
				(sheetname "")
			)
			(fill
				(thermal_gap 0.5)
				(thermal_bridge_width 0.5)
				(island_removal_mode 0)
			)
			(polygon
				(pts
					(xy 51.494436 0.7874) (xy 51.494436 0.7366) (xy 51.443636 0.7366) (xy 51.443636 0.7874)
				)
			)
		)
	)
	(footprint ""
		(layer "B.Cu")
		(at 50.1015 18.542 90)
		(property "Reference" "C10"
			(at 0.22733 3.683 0)
			(unlocked yes)
			(layer "B.SilkS")
			(effects
				(font
					(size 0.7874 0.5842)
					(thickness 0.127)
				)
				(justify left mirror)
			)
		)
		(property "Value" "22UF"
			(at 0.148158 1.7526 0)
			(unlocked yes)
			(layer "B.Fab")
			(hide yes)
			(effects
				(font
					(size 1.27 0.9652)
					(thickness 0.000001)
				)
				(justify left mirror)
			)
		)
		(property "Device Type" "CAPC0063"
			(at 0.148158 1.7526 0)
			(unlocked yes)
			(layer "B.Fab")
			(hide yes)
			(effects
				(font
					(size 1.27 0.9652)
					(thickness 0.000001)
				)
				(justify left mirror)
			)
		)
		(duplicate_pad_numbers_are_jumpers no)
		(fp_circle
			(center 0 0)
			(end 0 0.127)
			(stroke
				(width 0.2032)
				(type default)
			)
			(fill no)
			(layer "B.SilkS")
		)
		(fp_poly
			(pts
				(xy -0.7874 -1.6637) (xy 0.7874 -1.6637) (xy 0.7874 1.6637) (xy -0.7874 1.6637)
			)
			(stroke
				(width 0)
				(type default)
			)
			(fill no)
			(layer "B.CrtYd")
		)
		(fp_line
			(start 0.4064 -0.7874)
			(end -0.4064 -0.7874)
			(stroke
				(width 0.0254)
				(type default)
			)
			(layer "B.Fab")
		)
		(fp_line
			(start -0.4064 -0.7874)
			(end -0.4064 0.8128)
			(stroke
				(width 0.0254)
				(type default)
			)
			(layer "B.Fab")
		)
		(fp_line
			(start 0.4064 0.8128)
			(end 0.4064 -0.7874)
			(stroke
				(width 0.0254)
				(type default)
			)
			(layer "B.Fab")
		)
		(fp_line
			(start -0.4064 0.8128)
			(end 0.4064 0.8128)
			(stroke
				(width 0.0254)
				(type default)
			)
			(layer "B.Fab")
		)
		(pad "1" smd rect
			(at 0 -0.8001 270)
			(size 0.8636 0.9652)
			(layers "B.Cu" "B.Mask" "B.Paste")
			(net "VDD_CORE")
		)
		(pad "2" smd rect
			(at 0 0.8001 270)
			(size 0.8636 0.9652)
			(layers "B.Cu" "B.Mask" "B.Paste")
			(net "GND")
		)
		(zone
			(layer "B.Cu")
			(hatch none 0.5)
			(connect_pads
				(clearance 0)
			)
			(min_thickness 0.25)
			(keepout
				(tracks not_allowed)
				(vias allowed)
				(pads allowed)
				(copperpour not_allowed)
				(footprints allowed)
			)
			(placement
				(enabled no)
				(sheetname "")
			)
			(fill
				(thermal_gap 0.5)
				(thermal_bridge_width 0.5)
				(island_removal_mode 0)
			)
			(polygon
				(pts
					(xy 49.8475 18.4785) (xy 49.8475 18.6055) (xy 50.3555 18.6055) (xy 50.3555 18.4785)
				)
			)
		)
	)
	(footprint ""
		(layer "B.Cu")
		(at 28.321 30.48 -90)
		(property "Reference" "C118"
			(at 0.02667 0.762 0)
			(unlocked yes)
			(layer "B.SilkS")
			(effects
				(font
					(size 0.7874 0.5842)
					(thickness 0.127)
				)
				(justify left mirror)
			)
		)
		(property "Value" "0.1UF"
			(at 0.091846 0.2921 180)
			(unlocked yes)
			(layer "B.Fab")
			(hide yes)
			(effects
				(font
					(size 0.7874 0.5842)
					(thickness 0.2032)
				)
				(justify left mirror)
			)
		)
		(property "Device Type" "CAPC0073"
			(at 0.091846 0.2921 180)
			(unlocked yes)
			(layer "B.Fab")
			(hide yes)
			(effects
				(font
					(size 0.7874 0.5842)
					(thickness 0.2032)
				)
				(justify left mirror)
			)
		)
		(duplicate_pad_numbers_are_jumpers no)
		(fp_poly
			(pts
				(xy -0.635 1.0668) (xy -0.635 -1.0668) (xy 0.635 -1.0668) (xy 0.635 1.0668)
			)
			(stroke
				(width 0)
				(type default)
			)
			(fill no)
			(layer "B.CrtYd")
		)
		(fp_line
			(start -0.254 0.508)
			(end 0.254 0.508)
			(stroke
				(width 0.0254)
				(type default)
			)
			(layer "B.Fab")
		)
		(fp_line
			(start 0.254 0.508)
			(end 0.254 -0.508)
			(stroke
				(width 0.0254)
				(type default)
			)
			(layer "B.Fab")
		)
		(fp_line
			(start -0.254 -0.508)
			(end -0.254 0.508)
			(stroke
				(width 0.0254)
				(type default)
			)
			(layer "B.Fab")
		)
		(fp_line
			(start 0.254 -0.508)
			(end -0.254 -0.508)
			(stroke
				(width 0.0254)
				(type default)
			)
			(layer "B.Fab")
		)
		(pad "1" smd rect
			(at 0 -0.4191 90)
			(size 0.508 0.5334)
			(layers "B.Cu" "B.Mask" "B.Paste")
			(net "EXT_3.3V")
		)
		(pad "2" smd rect
			(at 0 0.4191 90)
			(size 0.508 0.5334)
			(layers "B.Cu" "B.Mask" "B.Paste")
			(net "GND")
		)
		(zone
			(layer "B.Cu")
			(hatch none 0.5)
			(connect_pads
				(clearance 0)
			)
			(min_thickness 0.25)
			(keepout
				(tracks not_allowed)
				(vias allowed)
				(pads allowed)
				(copperpour not_allowed)
				(footprints allowed)
			)
			(placement
				(enabled no)
				(sheetname "")
			)
			(fill
				(thermal_gap 0.5)
				(thermal_bridge_width 0.5)
				(island_removal_mode 0)
			)
			(polygon
				(pts
					(xy 28.3464 30.4546) (xy 28.2956 30.4546) (xy 28.2956 30.5054) (xy 28.3464 30.5054)
				)
			)
		)
	)
	(footprint ""
		(layer "B.Cu")
		(at 66.802 25.4 180)
		(property "Reference" "R124"
			(at -0.86233 -0.381 270)
			(unlocked yes)
			(layer "B.SilkS")
			(effects
				(font
					(size 0.7874 0.5842)
					(thickness 0.127)
				)
				(justify mirror)
			)
		)
		(property "Value" ""
			(at 0 0 0)
			(layer "B.Fab")
			(effects
				(font
					(size 1.27 1.27)
				)
				(justify mirror)
			)
		)
		(duplicate_pad_numbers_are_jumpers no)
		(fp_circle
			(center 0 0)
			(end -0.104648 0)
			(stroke
				(width 0.1016)
				(type default)
			)
			(fill no)
			(layer "B.SilkS")
		)
		(fp_poly
			(pts
				(xy 0.381 -0.889) (xy 0.381 0.889) (xy -0.381 0.889) (xy -0.381 -0.889)
			)
			(stroke
				(width 0)
				(type default)
			)
			(fill no)
			(layer "B.CrtYd")
		)
		(fp_line
			(start 0.508 1.016)
			(end 0.508 -1.016)
			(stroke
				(width 0.0254)
				(type default)
			)
			(layer "B.Fab")
		)
		(fp_line
			(start 0.508 -1.016)
			(end 0.254 -1.016)
			(stroke
				(width 0.0254)
				(type default)
			)
			(layer "B.Fab")
		)
		(fp_line
			(start 0.254 -1.016)
			(end -0.508 -1.016)
			(stroke
				(width 0.0254)
				(type default)
			)
			(layer "B.Fab")
		)
		(fp_line
			(start -0.508 1.016)
			(end 0.508 1.016)
			(stroke
				(width 0.0254)
				(type default)
			)
			(layer "B.Fab")
		)
		(fp_line
			(start -0.508 -1.016)
			(end -0.508 1.016)
			(stroke
				(width 0.0254)
				(type default)
			)
			(layer "B.Fab")
		)
		(pad "1" smd custom
			(at 0 -0.500126)
			(size 0.127 0.127)
			(layers "B.Cu" "B.Mask" "B.Paste")
			(net "GND")
			(options
				(clearance outline)
				(anchor circle)
			)
			(primitives
				(gr_poly
					(pts
						(xy -0.1778 0.254) (xy 0.1778 0.254) (xy 0.254 0.1778) (xy 0.254 -0.1778) (xy 0.1778 -0.254) (xy -0.1778 -0.254)
						(xy -0.254 -0.1778) (xy -0.254 0.1778)
					)
					(width 0)
					(fill yes)
				)
			)
		)
		(pad "2" smd custom
			(at 0 0.500126)
			(size 0.127 0.127)
			(layers "B.Cu" "B.Mask" "B.Paste")
			(net "6N3961")
			(options
				(clearance outline)
				(anchor circle)
			)
			(primitives
				(gr_poly
					(pts
						(xy -0.1778 0.254) (xy 0.1778 0.254) (xy 0.254 0.1778) (xy 0.254 -0.1778) (xy 0.1778 -0.254) (xy -0.1778 -0.254)
						(xy -0.254 -0.1778) (xy -0.254 0.1778)
					)
					(width 0)
					(fill yes)
				)
			)
		)
	)
	(footprint ""
		(layer "B.Cu")
		(at 77.051002 25.813004)
		(property "Reference" "V_A-CB7"
			(at 0 0 0)
			(layer "B.SilkS")
			(hide yes)
			(effects
				(font
					(size 1.27 1.27)
				)
				(justify mirror)
			)
		)
		(property "Value" ""
			(at 0 0 0)
			(layer "B.Fab")
			(effects
				(font
					(size 1.27 1.27)
				)
				(justify mirror)
			)
		)
		(duplicate_pad_numbers_are_jumpers no)
		(pad "1" thru_hole circle
			(at 0 0 180)
			(size 0.4572 0.4572)
			(drill 0.20574)
			(layers "*.Cu" "*.Mask")
			(remove_unused_layers no)
			(net "DDR0_32A_CB7")
			(clearance 0.1143)
			(thermal_gap 0.1143)
		)
	)
	(footprint ""
		(layer "B.Cu")
		(at 50.477039 0.762 180)
		(property "Reference" "C150"
			(at 0.145212 0.8763 270)
			(unlocked yes)
			(layer "B.SilkS")
			(effects
				(font
					(size 0.7874 0.5842)
					(thickness 0.127)
				)
				(justify left mirror)
			)
		)
		(property "Value" "0.22UF"
			(at 0.091846 0.2921 90)
			(unlocked yes)
			(layer "B.Fab")
			(hide yes)
			(effects
				(font
					(size 0.7874 0.5842)
					(thickness 0.2032)
				)
				(justify left mirror)
			)
		)
		(property "Device Type" "CAPC0062"
			(at 0.091846 0.2921 90)
			(unlocked yes)
			(layer "B.Fab")
			(hide yes)
			(effects
				(font
					(size 0.7874 0.5842)
					(thickness 0.2032)
				)
				(justify left mirror)
			)
		)
		(duplicate_pad_numbers_are_jumpers no)
		(fp_poly
			(pts
				(xy -0.635 1.0668) (xy -0.635 -1.0668) (xy 0.635 -1.0668) (xy 0.635 1.0668)
			)
			(stroke
				(width 0)
				(type default)
			)
			(fill no)
			(layer "B.CrtYd")
		)
		(fp_line
			(start 0.254 0.508)
			(end 0.254 -0.508)
			(stroke
				(width 0.0254)
				(type default)
			)
			(layer "B.Fab")
		)
		(fp_line
			(start 0.254 -0.508)
			(end -0.254 -0.508)
			(stroke
				(width 0.0254)
				(type default)
			)
			(layer "B.Fab")
		)
		(fp_line
			(start -0.254 0.508)
			(end 0.254 0.508)
			(stroke
				(width 0.0254)
				(type default)
			)
			(layer "B.Fab")
		)
		(fp_line
			(start -0.254 -0.508)
			(end -0.254 0.508)
			(stroke
				(width 0.0254)
				(type default)
			)
			(layer "B.Fab")
		)
		(pad "1" smd rect
			(at 0 -0.4191)
			(size 0.508 0.5334)
			(layers "B.Cu" "B.Mask" "B.Paste")
			(net "_NFP_PCIE0_PER6_N")
		)
		(pad "2" smd rect
			(at 0 0.4191)
			(size 0.508 0.5334)
			(layers "B.Cu" "B.Mask" "B.Paste")
			(net "NFP_PCIE0_PER6_N")
		)
		(zone
			(layer "B.Cu")
			(hatch none 0.5)
			(connect_pads
				(clearance 0)
			)
			(min_thickness 0.25)
			(keepout
				(tracks not_allowed)
				(vias allowed)
				(pads allowed)
				(copperpour not_allowed)
				(footprints allowed)
			)
			(placement
				(enabled no)
				(sheetname "")
			)
			(fill
				(thermal_gap 0.5)
				(thermal_bridge_width 0.5)
				(island_removal_mode 0)
			)
			(polygon
				(pts
					(xy 50.502439 0.7874) (xy 50.502439 0.7366) (xy 50.451639 0.7366) (xy 50.451639 0.7874)
				)
			)
		)
	)
	(footprint ""
		(layer "B.Cu")
		(at 28.702 18.923 180)
		(property "Reference" "R54"
			(at 0 0 0)
			(layer "B.SilkS")
			(hide yes)
			(effects
				(font
					(size 1.27 1.27)
				)
				(justify mirror)
			)
		)
		(property "Value" "4.75K"
			(at 0.148158 1.3462 90)
			(unlocked yes)
			(layer "B.Fab")
			(hide yes)
			(effects
				(font
					(size 1.27 0.9652)
					(thickness 0.000001)
				)
				(justify left mirror)
			)
		)
		(property "Device Type" "REST4024"
			(at 0.148158 1.3462 90)
			(unlocked yes)
			(layer "B.Fab")
			(hide yes)
			(effects
				(font
					(size 1.27 0.9652)
					(thickness 0.000001)
				)
				(justify left mirror)
			)
		)
		(duplicate_pad_numbers_are_jumpers no)
		(fp_poly
			(pts
				(xy -0.635 1.0668) (xy -0.635 -1.0668) (xy 0.635 -1.0668) (xy 0.635 1.0668)
			)
			(stroke
				(width 0)
				(type default)
			)
			(fill no)
			(layer "B.CrtYd")
		)
		(fp_line
			(start 0.254 0.508)
			(end 0.254 -0.508)
			(stroke
				(width 0.0254)
				(type default)
			)
			(layer "B.Fab")
		)
		(fp_line
			(start 0.254 -0.508)
			(end -0.254 -0.508)
			(stroke
				(width 0.0254)
				(type default)
			)
			(layer "B.Fab")
		)
		(fp_line
			(start -0.254 0.508)
			(end 0.254 0.508)
			(stroke
				(width 0.0254)
				(type default)
			)
			(layer "B.Fab")
		)
		(fp_line
			(start -0.254 -0.508)
			(end -0.254 0.508)
			(stroke
				(width 0.0254)
				(type default)
			)
			(layer "B.Fab")
		)
		(pad "1" smd rect
			(at 0 -0.4191)
			(size 0.508 0.5334)
			(layers "B.Cu" "B.Mask" "B.Paste")
			(net "CPLD_VERSION_2")
		)
		(pad "2" smd rect
			(at 0 0.4191)
			(size 0.508 0.5334)
			(layers "B.Cu" "B.Mask" "B.Paste")
			(net "GND")
		)
		(zone
			(layer "B.Cu")
			(hatch none 0.5)
			(connect_pads
				(clearance 0)
			)
			(min_thickness 0.25)
			(keepout
				(tracks not_allowed)
				(vias allowed)
				(pads allowed)
				(copperpour not_allowed)
				(footprints allowed)
			)
			(placement
				(enabled no)
				(sheetname "")
			)
			(fill
				(thermal_gap 0.5)
				(thermal_bridge_width 0.5)
				(island_removal_mode 0)
			)
			(polygon
				(pts
					(xy 28.7274 18.9484) (xy 28.7274 18.8976) (xy 28.6766 18.8976) (xy 28.6766 18.9484)
				)
			)
		)
	)
	(footprint ""
		(layer "B.Cu")
		(at 2.032 9.8552 180)
		(property "Reference" "R378"
			(at 0 0 0)
			(layer "B.SilkS")
			(hide yes)
			(effects
				(font
					(size 1.27 1.27)
				)
				(justify mirror)
			)
		)
		(property "Value" "4.75K"
			(at 0.148158 1.3462 90)
			(unlocked yes)
			(layer "B.Fab")
			(hide yes)
			(effects
				(font
					(size 1.27 0.9652)
					(thickness 0.000001)
				)
				(justify left mirror)
			)
		)
		(property "Device Type" "REST4024"
			(at 0.148158 1.3462 90)
			(unlocked yes)
			(layer "B.Fab")
			(hide yes)
			(effects
				(font
					(size 1.27 0.9652)
					(thickness 0.000001)
				)
				(justify left mirror)
			)
		)
		(duplicate_pad_numbers_are_jumpers no)
		(fp_poly
			(pts
				(xy -0.635 1.0668) (xy -0.635 -1.0668) (xy 0.635 -1.0668) (xy 0.635 1.0668)
			)
			(stroke
				(width 0)
				(type default)
			)
			(fill no)
			(layer "B.CrtYd")
		)
		(fp_line
			(start 0.254 0.508)
			(end 0.254 -0.508)
			(stroke
				(width 0.0254)
				(type default)
			)
			(layer "B.Fab")
		)
		(fp_line
			(start 0.254 -0.508)
			(end -0.254 -0.508)
			(stroke
				(width 0.0254)
				(type default)
			)
			(layer "B.Fab")
		)
		(fp_line
			(start -0.254 0.508)
			(end 0.254 0.508)
			(stroke
				(width 0.0254)
				(type default)
			)
			(layer "B.Fab")
		)
		(fp_line
			(start -0.254 -0.508)
			(end -0.254 0.508)
			(stroke
				(width 0.0254)
				(type default)
			)
			(layer "B.Fab")
		)
		(pad "1" smd rect
			(at 0 -0.4191)
			(size 0.508 0.5334)
			(layers "B.Cu" "B.Mask" "B.Paste")
			(net "NWK1_I2C_SDA")
		)
		(pad "2" smd rect
			(at 0 0.4191)
			(size 0.508 0.5334)
			(layers "B.Cu" "B.Mask" "B.Paste")
			(net "EXT_3.3V")
		)
		(zone
			(layer "B.Cu")
			(hatch none 0.5)
			(connect_pads
				(clearance 0)
			)
			(min_thickness 0.25)
			(keepout
				(tracks not_allowed)
				(vias allowed)
				(pads allowed)
				(copperpour not_allowed)
				(footprints allowed)
			)
			(placement
				(enabled no)
				(sheetname "")
			)
			(fill
				(thermal_gap 0.5)
				(thermal_bridge_width 0.5)
				(island_removal_mode 0)
			)
			(polygon
				(pts
					(xy 2.0574 9.8806) (xy 2.0574 9.8298) (xy 2.0066 9.8298) (xy 2.0066 9.8806)
				)
			)
		)
	)
	(footprint ""
		(layer "B.Cu")
		(at 5.334 14.5796)
		(property "Reference" "C283"
			(at 0.86233 3.2004 270)
			(unlocked yes)
			(layer "B.SilkS")
			(effects
				(font
					(size 0.7874 0.5842)
					(thickness 0.127)
				)
				(justify left mirror)
			)
		)
		(property "Value" "4.7UF"
			(at 0.091846 0.2921 270)
			(unlocked yes)
			(layer "B.Fab")
			(hide yes)
			(effects
				(font
					(size 0.7874 0.5842)
					(thickness 0.2032)
				)
				(justify left mirror)
			)
		)
		(property "Device Type" "CAPC0065"
			(at 0.091846 0.2921 270)
			(unlocked yes)
			(layer "B.Fab")
			(hide yes)
			(effects
				(font
					(size 0.7874 0.5842)
					(thickness 0.2032)
				)
				(justify left mirror)
			)
		)
		(duplicate_pad_numbers_are_jumpers no)
		(fp_poly
			(pts
				(xy -0.635 1.0668) (xy -0.635 -1.0668) (xy 0.635 -1.0668) (xy 0.635 1.0668)
			)
			(stroke
				(width 0)
				(type default)
			)
			(fill no)
			(layer "B.CrtYd")
		)
		(fp_line
			(start -0.254 -0.508)
			(end -0.254 0.508)
			(stroke
				(width 0.0254)
				(type default)
			)
			(layer "B.Fab")
		)
		(fp_line
			(start -0.254 0.508)
			(end 0.254 0.508)
			(stroke
				(width 0.0254)
				(type default)
			)
			(layer "B.Fab")
		)
		(fp_line
			(start 0.254 -0.508)
			(end -0.254 -0.508)
			(stroke
				(width 0.0254)
				(type default)
			)
			(layer "B.Fab")
		)
		(fp_line
			(start 0.254 0.508)
			(end 0.254 -0.508)
			(stroke
				(width 0.0254)
				(type default)
			)
			(layer "B.Fab")
		)
		(pad "1" smd rect
			(at 0 -0.4191 180)
			(size 0.508 0.5334)
			(layers "B.Cu" "B.Mask" "B.Paste")
			(net "13N4351")
		)
		(pad "2" smd rect
			(at 0 0.4191 180)
			(size 0.508 0.5334)
			(layers "B.Cu" "B.Mask" "B.Paste")
			(net "GND")
		)
		(zone
			(layer "B.Cu")
			(hatch none 0.5)
			(connect_pads
				(clearance 0)
			)
			(min_thickness 0.25)
			(keepout
				(tracks not_allowed)
				(vias allowed)
				(pads allowed)
				(copperpour not_allowed)
				(footprints allowed)
			)
			(placement
				(enabled no)
				(sheetname "")
			)
			(fill
				(thermal_gap 0.5)
				(thermal_bridge_width 0.5)
				(island_removal_mode 0)
			)
			(polygon
				(pts
					(xy 5.3086 14.5542) (xy 5.3086 14.605) (xy 5.3594 14.605) (xy 5.3594 14.5542)
				)
			)
		)
	)
	(footprint ""
		(layer "B.Cu")
		(at 40.237029 11.542014)
		(property "Reference" "R41"
			(at 0 0 0)
			(layer "B.SilkS")
			(hide yes)
			(effects
				(font
					(size 1.27 1.27)
				)
				(justify mirror)
			)
		)
		(property "Value" ""
			(at 0 0 0)
			(layer "B.Fab")
			(effects
				(font
					(size 1.27 1.27)
				)
				(justify mirror)
			)
		)
		(duplicate_pad_numbers_are_jumpers no)
		(fp_circle
			(center 0 0)
			(end 0.104648 0)
			(stroke
				(width 0.1016)
				(type default)
			)
			(fill no)
			(layer "B.SilkS")
		)
		(fp_poly
			(pts
				(xy 0.381 -0.889) (xy 0.381 0.889) (xy -0.381 0.889) (xy -0.381 -0.889)
			)
			(stroke
				(width 0)
				(type default)
			)
			(fill no)
			(layer "B.CrtYd")
		)
		(fp_line
			(start -0.508 -1.016)
			(end -0.508 1.016)
			(stroke
				(width 0.0254)
				(type default)
			)
			(layer "B.Fab")
		)
		(fp_line
			(start -0.508 1.016)
			(end 0.508 1.016)
			(stroke
				(width 0.0254)
				(type default)
			)
			(layer "B.Fab")
		)
		(fp_line
			(start 0.254 -1.016)
			(end -0.508 -1.016)
			(stroke
				(width 0.0254)
				(type default)
			)
			(layer "B.Fab")
		)
		(fp_line
			(start 0.508 -1.016)
			(end 0.254 -1.016)
			(stroke
				(width 0.0254)
				(type default)
			)
			(layer "B.Fab")
		)
		(fp_line
			(start 0.508 1.016)
			(end 0.508 -1.016)
			(stroke
				(width 0.0254)
				(type default)
			)
			(layer "B.Fab")
		)
		(pad "1" smd custom
			(at 0 -0.500126 180)
			(size 0.127 0.127)
			(layers "B.Cu" "B.Mask" "B.Paste")
			(net "VDD_3.3V")
			(options
				(clearance outline)
				(anchor circle)
			)
			(primitives
				(gr_poly
					(pts
						(xy -0.1778 0.254) (xy 0.1778 0.254) (xy 0.254 0.1778) (xy 0.254 -0.1778) (xy 0.1778 -0.254) (xy -0.1778 -0.254)
						(xy -0.254 -0.1778) (xy -0.254 0.1778)
					)
					(width 0)
					(fill yes)
				)
			)
		)
		(pad "2" smd custom
			(at 0 0.500126 180)
			(size 0.127 0.127)
			(layers "B.Cu" "B.Mask" "B.Paste")
			(net "PGRM_JTAG_TRST_L")
			(options
				(clearance outline)
				(anchor circle)
			)
			(primitives
				(gr_poly
					(pts
						(xy -0.1778 0.254) (xy 0.1778 0.254) (xy 0.254 0.1778) (xy 0.254 -0.1778) (xy 0.1778 -0.254) (xy -0.1778 -0.254)
						(xy -0.254 -0.1778) (xy -0.254 0.1778)
					)
					(width 0)
					(fill yes)
				)
			)
		)
	)
	(footprint ""
		(layer "B.Cu")
		(at 2.032 8.128)
		(property "Reference" "TP30"
			(at -1.524 -0.48133 0)
			(unlocked yes)
			(layer "B.SilkS")
			(effects
				(font
					(size 0.7874 0.5842)
					(thickness 0.127)
				)
				(justify left mirror)
			)
		)
		(property "Value" "*"
			(at 0.4826 -0.14732 0)
			(unlocked yes)
			(layer "B.Fab")
			(hide yes)
			(effects
				(font
					(size 1.27 0.9652)
					(thickness 0.000001)
				)
				(justify left mirror)
			)
		)
		(property "Device Type" "TP_SMALL"
			(at 0.4826 -0.14732 0)
			(unlocked yes)
			(layer "B.Fab")
			(hide yes)
			(effects
				(font
					(size 1.27 0.9652)
					(thickness 0.000001)
				)
				(justify left mirror)
			)
		)
		(duplicate_pad_numbers_are_jumpers no)
		(fp_line
			(start -0.8636 -0.8636)
			(end 0.8636 -0.8636)
			(stroke
				(width 0.1524)
				(type default)
			)
			(layer "B.SilkS")
		)
		(fp_line
			(start -0.8636 0.8636)
			(end -0.8636 -0.8636)
			(stroke
				(width 0.1524)
				(type default)
			)
			(layer "B.SilkS")
		)
		(fp_line
			(start 0.8636 -0.8636)
			(end 0.8636 0.8636)
			(stroke
				(width 0.1524)
				(type default)
			)
			(layer "B.SilkS")
		)
		(fp_line
			(start 0.8636 0.8636)
			(end -0.8636 0.8636)
			(stroke
				(width 0.1524)
				(type default)
			)
			(layer "B.SilkS")
		)
		(fp_poly
			(pts
				(xy 0.635 -0.635) (xy 0.635 0.635) (xy -0.635 0.635) (xy -0.635 -0.635)
			)
			(stroke
				(width 0)
				(type default)
			)
			(fill no)
			(layer "B.CrtYd")
		)
		(pad "1" smd rect
			(at 0 0 180)
			(size 1.27 1.27)
			(layers "B.Cu" "B.Mask" "B.Paste")
			(net "PGRM_JTAG_TMS")
		)
	)
	(footprint ""
		(layer "B.Cu")
		(at 45.737018 11.042015 -90)
		(property "Reference" "R286"
			(at 0 0 90)
			(layer "B.SilkS")
			(hide yes)
			(effects
				(font
					(size 1.27 1.27)
				)
				(justify mirror)
			)
		)
		(property "Value" ""
			(at 0 0 90)
			(layer "B.Fab")
			(effects
				(font
					(size 1.27 1.27)
				)
				(justify mirror)
			)
		)
		(duplicate_pad_numbers_are_jumpers no)
		(fp_circle
			(center 0 0)
			(end 0 -0.104648)
			(stroke
				(width 0.1016)
				(type default)
			)
			(fill no)
			(layer "B.SilkS")
		)
		(fp_poly
			(pts
				(xy 0.381 -0.889) (xy 0.381 0.889) (xy -0.381 0.889) (xy -0.381 -0.889)
			)
			(stroke
				(width 0)
				(type default)
			)
			(fill no)
			(layer "B.CrtYd")
		)
		(fp_line
			(start -0.508 1.016)
			(end 0.508 1.016)
			(stroke
				(width 0.0254)
				(type default)
			)
			(layer "B.Fab")
		)
		(fp_line
			(start 0.508 1.016)
			(end 0.508 -1.016)
			(stroke
				(width 0.0254)
				(type default)
			)
			(layer "B.Fab")
		)
		(fp_line
			(start -0.508 -1.016)
			(end -0.508 1.016)
			(stroke
				(width 0.0254)
				(type default)
			)
			(layer "B.Fab")
		)
		(fp_line
			(start 0.254 -1.016)
			(end -0.508 -1.016)
			(stroke
				(width 0.0254)
				(type default)
			)
			(layer "B.Fab")
		)
		(fp_line
			(start 0.508 -1.016)
			(end 0.254 -1.016)
			(stroke
				(width 0.0254)
				(type default)
			)
			(layer "B.Fab")
		)
		(pad "1" smd custom
			(at 0 -0.500126 90)
			(size 0.127 0.127)
			(layers "B.Cu" "B.Mask" "B.Paste")
			(net "NFP_VDD_CORE_SENSE_VDD")
			(options
				(clearance outline)
				(anchor circle)
			)
			(primitives
				(gr_poly
					(pts
						(xy -0.1778 0.254) (xy 0.1778 0.254) (xy 0.254 0.1778) (xy 0.254 -0.1778) (xy 0.1778 -0.254) (xy -0.1778 -0.254)
						(xy -0.254 -0.1778) (xy -0.254 0.1778)
					)
					(width 0)
					(fill yes)
				)
			)
		)
		(pad "2" smd custom
			(at 0 0.500126 90)
			(size 0.127 0.127)
			(layers "B.Cu" "B.Mask" "B.Paste")
			(net "VDD_CORE")
			(options
				(clearance outline)
				(anchor circle)
			)
			(primitives
				(gr_poly
					(pts
						(xy -0.1778 0.254) (xy 0.1778 0.254) (xy 0.254 0.1778) (xy 0.254 -0.1778) (xy 0.1778 -0.254) (xy -0.1778 -0.254)
						(xy -0.254 -0.1778) (xy -0.254 0.1778)
					)
					(width 0)
					(fill yes)
				)
			)
		)
	)
	(footprint ""
		(layer "B.Cu")
		(at 72.251011 18.255996)
		(property "Reference" "V_A-DQ28"
			(at 0 0 0)
			(layer "B.SilkS")
			(hide yes)
			(effects
				(font
					(size 1.27 1.27)
				)
				(justify mirror)
			)
		)
		(property "Value" ""
			(at 0 0 0)
			(layer "B.Fab")
			(effects
				(font
					(size 1.27 1.27)
				)
				(justify mirror)
			)
		)
		(duplicate_pad_numbers_are_jumpers no)
		(pad "1" thru_hole circle
			(at 0 0 180)
			(size 0.4572 0.4572)
			(drill 0.20574)
			(layers "*.Cu" "*.Mask")
			(remove_unused_layers no)
			(net "DDR0_32A_DQ28")
			(clearance 0.1143)
			(thermal_gap 0.1143)
		)
	)
	(footprint ""
		(layer "B.Cu")
		(at 48.781691 6.542024 90)
		(property "Reference" "C281"
			(at 0 0 90)
			(layer "B.SilkS")
			(hide yes)
			(effects
				(font
					(size 1.27 1.27)
				)
				(justify mirror)
			)
		)
		(property "Value" "22UF"
			(at 0.148158 1.7526 0)
			(unlocked yes)
			(layer "B.Fab")
			(hide yes)
			(effects
				(font
					(size 1.27 0.9652)
					(thickness 0.000001)
				)
				(justify left mirror)
			)
		)
		(property "Device Type" "CAPC0063"
			(at 0.148158 1.7526 0)
			(unlocked yes)
			(layer "B.Fab")
			(hide yes)
			(effects
				(font
					(size 1.27 0.9652)
					(thickness 0.000001)
				)
				(justify left mirror)
			)
		)
		(duplicate_pad_numbers_are_jumpers no)
		(fp_circle
			(center 0 0)
			(end 0 0.127)
			(stroke
				(width 0.2032)
				(type default)
			)
			(fill no)
			(layer "B.SilkS")
		)
		(fp_poly
			(pts
				(xy -0.7874 -1.6637) (xy 0.7874 -1.6637) (xy 0.7874 1.6637) (xy -0.7874 1.6637)
			)
			(stroke
				(width 0)
				(type default)
			)
			(fill no)
			(layer "B.CrtYd")
		)
		(fp_line
			(start 0.4064 -0.7874)
			(end -0.4064 -0.7874)
			(stroke
				(width 0.0254)
				(type default)
			)
			(layer "B.Fab")
		)
		(fp_line
			(start -0.4064 -0.7874)
			(end -0.4064 0.8128)
			(stroke
				(width 0.0254)
				(type default)
			)
			(layer "B.Fab")
		)
		(fp_line
			(start 0.4064 0.8128)
			(end 0.4064 -0.7874)
			(stroke
				(width 0.0254)
				(type default)
			)
			(layer "B.Fab")
		)
		(fp_line
			(start -0.4064 0.8128)
			(end 0.4064 0.8128)
			(stroke
				(width 0.0254)
				(type default)
			)
			(layer "B.Fab")
		)
		(pad "1" smd rect
			(at 0 -0.8001 270)
			(size 0.8636 0.9652)
			(layers "B.Cu" "B.Mask" "B.Paste")
			(net "VDDA_SERDES")
		)
		(pad "2" smd rect
			(at 0 0.8001 270)
			(size 0.8636 0.9652)
			(layers "B.Cu" "B.Mask" "B.Paste")
			(net "GND")
		)
		(zone
			(layer "B.Cu")
			(hatch none 0.5)
			(connect_pads
				(clearance 0)
			)
			(min_thickness 0.25)
			(keepout
				(tracks not_allowed)
				(vias allowed)
				(pads allowed)
				(copperpour not_allowed)
				(footprints allowed)
			)
			(placement
				(enabled no)
				(sheetname "")
			)
			(fill
				(thermal_gap 0.5)
				(thermal_bridge_width 0.5)
				(island_removal_mode 0)
			)
			(polygon
				(pts
					(xy 48.527691 6.478524) (xy 48.527691 6.605524) (xy 49.035691 6.605524) (xy 49.035691 6.478524)
				)
			)
		)
	)
	(footprint ""
		(layer "B.Cu")
		(at 72.251011 6.698996)
		(property "Reference" "V_A-DQ11"
			(at 0 0 0)
			(layer "B.SilkS")
			(hide yes)
			(effects
				(font
					(size 1.27 1.27)
				)
				(justify mirror)
			)
		)
		(property "Value" ""
			(at 0 0 0)
			(layer "B.Fab")
			(effects
				(font
					(size 1.27 1.27)
				)
				(justify mirror)
			)
		)
		(duplicate_pad_numbers_are_jumpers no)
		(pad "1" thru_hole circle
			(at 0 0 180)
			(size 0.4572 0.4572)
			(drill 0.20574)
			(layers "*.Cu" "*.Mask")
			(remove_unused_layers no)
			(net "DDR0_32A_DQ11")
			(clearance 0.1143)
			(thermal_gap 0.1143)
		)
	)
	(footprint ""
		(layer "B.Cu")
		(at 75.451005 19.055994)
		(property "Reference" "V_A-DQ20"
			(at 0 0 0)
			(layer "B.SilkS")
			(hide yes)
			(effects
				(font
					(size 1.27 1.27)
				)
				(justify mirror)
			)
		)
		(property "Value" ""
			(at 0 0 0)
			(layer "B.Fab")
			(effects
				(font
					(size 1.27 1.27)
				)
				(justify mirror)
			)
		)
		(duplicate_pad_numbers_are_jumpers no)
		(pad "1" thru_hole circle
			(at 0 0 180)
			(size 0.4572 0.4572)
			(drill 0.20574)
			(layers "*.Cu" "*.Mask")
			(remove_unused_layers no)
			(net "DDR0_32A_DQ20")
			(clearance 0.1143)
			(thermal_gap 0.1143)
		)
	)
	(footprint ""
		(layer "B.Cu")
		(at 58.236993 7.542022 180)
		(property "Reference" "C90"
			(at 0.097663 2.335022 270)
			(unlocked yes)
			(layer "B.SilkS")
			(effects
				(font
					(size 0.7874 0.5842)
					(thickness 0.127)
				)
				(justify mirror)
			)
		)
		(property "Value" ""
			(at 0 0 0)
			(layer "B.Fab")
			(effects
				(font
					(size 1.27 1.27)
				)
				(justify mirror)
			)
		)
		(duplicate_pad_numbers_are_jumpers no)
		(fp_circle
			(center 0 0)
			(end -0.104648 0)
			(stroke
				(width 0.1016)
				(type default)
			)
			(fill no)
			(layer "B.SilkS")
		)
		(fp_poly
			(pts
				(xy 0.381 -0.889) (xy 0.381 0.889) (xy -0.381 0.889) (xy -0.381 -0.889)
			)
			(stroke
				(width 0)
				(type default)
			)
			(fill no)
			(layer "B.CrtYd")
		)
		(fp_line
			(start 0.508 1.016)
			(end 0.508 -1.016)
			(stroke
				(width 0.0254)
				(type default)
			)
			(layer "B.Fab")
		)
		(fp_line
			(start 0.508 -1.016)
			(end 0.254 -1.016)
			(stroke
				(width 0.0254)
				(type default)
			)
			(layer "B.Fab")
		)
		(fp_line
			(start 0.254 -1.016)
			(end -0.508 -1.016)
			(stroke
				(width 0.0254)
				(type default)
			)
			(layer "B.Fab")
		)
		(fp_line
			(start -0.508 1.016)
			(end 0.508 1.016)
			(stroke
				(width 0.0254)
				(type default)
			)
			(layer "B.Fab")
		)
		(fp_line
			(start -0.508 -1.016)
			(end -0.508 1.016)
			(stroke
				(width 0.0254)
				(type default)
			)
			(layer "B.Fab")
		)
		(pad "1" smd custom
			(at 0 -0.500126)
			(size 0.127 0.127)
			(layers "B.Cu" "B.Mask" "B.Paste")
			(net "VDDA_PCIE0")
			(options
				(clearance outline)
				(anchor circle)
			)
			(primitives
				(gr_poly
					(pts
						(xy -0.1778 0.254) (xy 0.1778 0.254) (xy 0.254 0.1778) (xy 0.254 -0.1778) (xy 0.1778 -0.254) (xy -0.1778 -0.254)
						(xy -0.254 -0.1778) (xy -0.254 0.1778)
					)
					(width 0)
					(fill yes)
				)
			)
		)
		(pad "2" smd custom
			(at 0 0.500126)
			(size 0.127 0.127)
			(layers "B.Cu" "B.Mask" "B.Paste")
			(net "GND")
			(options
				(clearance outline)
				(anchor circle)
			)
			(primitives
				(gr_poly
					(pts
						(xy -0.1778 0.254) (xy 0.1778 0.254) (xy 0.254 0.1778) (xy 0.254 -0.1778) (xy 0.1778 -0.254) (xy -0.1778 -0.254)
						(xy -0.254 -0.1778) (xy -0.254 0.1778)
					)
					(width 0)
					(fill yes)
				)
			)
		)
	)
	(footprint ""
		(layer "B.Cu")
		(at 59.7916 35.56 90)
		(property "Reference" "C12"
			(at 0.98933 0.5334 0)
			(unlocked yes)
			(layer "B.SilkS")
			(effects
				(font
					(size 0.7874 0.5842)
					(thickness 0.127)
				)
				(justify left mirror)
			)
		)
		(property "Value" "22UF"
			(at 0.148158 1.7526 0)
			(unlocked yes)
			(layer "B.Fab")
			(hide yes)
			(effects
				(font
					(size 1.27 0.9652)
					(thickness 0.000001)
				)
				(justify left mirror)
			)
		)
		(property "Device Type" "CAPC0063"
			(at 0.148158 1.7526 0)
			(unlocked yes)
			(layer "B.Fab")
			(hide yes)
			(effects
				(font
					(size 1.27 0.9652)
					(thickness 0.000001)
				)
				(justify left mirror)
			)
		)
		(duplicate_pad_numbers_are_jumpers no)
		(fp_circle
			(center 0 0)
			(end 0 0.127)
			(stroke
				(width 0.2032)
				(type default)
			)
			(fill no)
			(layer "B.SilkS")
		)
		(fp_poly
			(pts
				(xy -0.7874 -1.6637) (xy 0.7874 -1.6637) (xy 0.7874 1.6637) (xy -0.7874 1.6637)
			)
			(stroke
				(width 0)
				(type default)
			)
			(fill no)
			(layer "B.CrtYd")
		)
		(fp_line
			(start 0.4064 -0.7874)
			(end -0.4064 -0.7874)
			(stroke
				(width 0.0254)
				(type default)
			)
			(layer "B.Fab")
		)
		(fp_line
			(start -0.4064 -0.7874)
			(end -0.4064 0.8128)
			(stroke
				(width 0.0254)
				(type default)
			)
			(layer "B.Fab")
		)
		(fp_line
			(start 0.4064 0.8128)
			(end 0.4064 -0.7874)
			(stroke
				(width 0.0254)
				(type default)
			)
			(layer "B.Fab")
		)
		(fp_line
			(start -0.4064 0.8128)
			(end 0.4064 0.8128)
			(stroke
				(width 0.0254)
				(type default)
			)
			(layer "B.Fab")
		)
		(pad "1" smd rect
			(at 0 -0.8001 270)
			(size 0.8636 0.9652)
			(layers "B.Cu" "B.Mask" "B.Paste")
			(net "VDD_CORE")
		)
		(pad "2" smd rect
			(at 0 0.8001 270)
			(size 0.8636 0.9652)
			(layers "B.Cu" "B.Mask" "B.Paste")
			(net "GND")
		)
		(zone
			(layer "B.Cu")
			(hatch none 0.5)
			(connect_pads
				(clearance 0)
			)
			(min_thickness 0.25)
			(keepout
				(tracks not_allowed)
				(vias allowed)
				(pads allowed)
				(copperpour not_allowed)
				(footprints allowed)
			)
			(placement
				(enabled no)
				(sheetname "")
			)
			(fill
				(thermal_gap 0.5)
				(thermal_bridge_width 0.5)
				(island_removal_mode 0)
			)
			(polygon
				(pts
					(xy 59.5376 35.4965) (xy 59.5376 35.6235) (xy 60.0456 35.6235) (xy 60.0456 35.4965)
				)
			)
		)
	)
	(footprint ""
		(layer "B.Cu")
		(at 83.185 44.323 180)
		(property "Reference" "C205"
			(at -0.98933 -3.429 270)
			(unlocked yes)
			(layer "B.SilkS")
			(effects
				(font
					(size 0.7874 0.5842)
					(thickness 0.127)
				)
				(justify left mirror)
			)
		)
		(property "Value" "1UF"
			(at 0.091846 0.2921 90)
			(unlocked yes)
			(layer "B.Fab")
			(hide yes)
			(effects
				(font
					(size 0.7874 0.5842)
					(thickness 0.2032)
				)
				(justify left mirror)
			)
		)
		(property "Device Type" "CAPC0028"
			(at 0.091846 0.2921 90)
			(unlocked yes)
			(layer "B.Fab")
			(hide yes)
			(effects
				(font
					(size 0.7874 0.5842)
					(thickness 0.2032)
				)
				(justify left mirror)
			)
		)
		(duplicate_pad_numbers_are_jumpers no)
		(fp_poly
			(pts
				(xy -0.635 1.0668) (xy -0.635 -1.0668) (xy 0.635 -1.0668) (xy 0.635 1.0668)
			)
			(stroke
				(width 0)
				(type default)
			)
			(fill no)
			(layer "B.CrtYd")
		)
		(fp_line
			(start 0.254 0.508)
			(end 0.254 -0.508)
			(stroke
				(width 0.0254)
				(type default)
			)
			(layer "B.Fab")
		)
		(fp_line
			(start 0.254 -0.508)
			(end -0.254 -0.508)
			(stroke
				(width 0.0254)
				(type default)
			)
			(layer "B.Fab")
		)
		(fp_line
			(start -0.254 0.508)
			(end 0.254 0.508)
			(stroke
				(width 0.0254)
				(type default)
			)
			(layer "B.Fab")
		)
		(fp_line
			(start -0.254 -0.508)
			(end -0.254 0.508)
			(stroke
				(width 0.0254)
				(type default)
			)
			(layer "B.Fab")
		)
		(pad "1" smd rect
			(at 0 -0.4191)
			(size 0.508 0.5334)
			(layers "B.Cu" "B.Mask" "B.Paste")
			(net "11N2159")
		)
		(pad "2" smd rect
			(at 0 0.4191)
			(size 0.508 0.5334)
			(layers "B.Cu" "B.Mask" "B.Paste")
			(net "GND")
		)
		(zone
			(layer "B.Cu")
			(hatch none 0.5)
			(connect_pads
				(clearance 0)
			)
			(min_thickness 0.25)
			(keepout
				(tracks not_allowed)
				(vias allowed)
				(pads allowed)
				(copperpour not_allowed)
				(footprints allowed)
			)
			(placement
				(enabled no)
				(sheetname "")
			)
			(fill
				(thermal_gap 0.5)
				(thermal_bridge_width 0.5)
				(island_removal_mode 0)
			)
			(polygon
				(pts
					(xy 83.2104 44.3484) (xy 83.2104 44.2976) (xy 83.1596 44.2976) (xy 83.1596 44.3484)
				)
			)
		)
	)
	(footprint ""
		(layer "B.Cu")
		(at 52.737004 6.042025 90)
		(property "Reference" "C42"
			(at 0 0 90)
			(layer "B.SilkS")
			(hide yes)
			(effects
				(font
					(size 1.27 1.27)
				)
				(justify mirror)
			)
		)
		(property "Value" ""
			(at 0 0 90)
			(layer "B.Fab")
			(effects
				(font
					(size 1.27 1.27)
				)
				(justify mirror)
			)
		)
		(duplicate_pad_numbers_are_jumpers no)
		(fp_circle
			(center 0 0)
			(end 0 0.104648)
			(stroke
				(width 0.1016)
				(type default)
			)
			(fill no)
			(layer "B.SilkS")
		)
		(fp_poly
			(pts
				(xy 0.381 -0.889) (xy 0.381 0.889) (xy -0.381 0.889) (xy -0.381 -0.889)
			)
			(stroke
				(width 0)
				(type default)
			)
			(fill no)
			(layer "B.CrtYd")
		)
		(fp_line
			(start 0.508 -1.016)
			(end 0.254 -1.016)
			(stroke
				(width 0.0254)
				(type default)
			)
			(layer "B.Fab")
		)
		(fp_line
			(start 0.254 -1.016)
			(end -0.508 -1.016)
			(stroke
				(width 0.0254)
				(type default)
			)
			(layer "B.Fab")
		)
		(fp_line
			(start -0.508 -1.016)
			(end -0.508 1.016)
			(stroke
				(width 0.0254)
				(type default)
			)
			(layer "B.Fab")
		)
		(fp_line
			(start 0.508 1.016)
			(end 0.508 -1.016)
			(stroke
				(width 0.0254)
				(type default)
			)
			(layer "B.Fab")
		)
		(fp_line
			(start -0.508 1.016)
			(end 0.508 1.016)
			(stroke
				(width 0.0254)
				(type default)
			)
			(layer "B.Fab")
		)
		(pad "1" smd custom
			(at 0 -0.500126 270)
			(size 0.127 0.127)
			(layers "B.Cu" "B.Mask" "B.Paste")
			(net "VDDAH_SERDES")
			(options
				(clearance outline)
				(anchor circle)
			)
			(primitives
				(gr_poly
					(pts
						(xy -0.1778 0.254) (xy 0.1778 0.254) (xy 0.254 0.1778) (xy 0.254 -0.1778) (xy 0.1778 -0.254) (xy -0.1778 -0.254)
						(xy -0.254 -0.1778) (xy -0.254 0.1778)
					)
					(width 0)
					(fill yes)
				)
			)
		)
		(pad "2" smd custom
			(at 0 0.500126 270)
			(size 0.127 0.127)
			(layers "B.Cu" "B.Mask" "B.Paste")
			(net "GND")
			(options
				(clearance outline)
				(anchor circle)
			)
			(primitives
				(gr_poly
					(pts
						(xy -0.1778 0.254) (xy 0.1778 0.254) (xy 0.254 0.1778) (xy 0.254 -0.1778) (xy 0.1778 -0.254) (xy -0.1778 -0.254)
						(xy -0.254 -0.1778) (xy -0.254 0.1778)
					)
					(width 0)
					(fill yes)
				)
			)
		)
	)
	(footprint ""
		(layer "B.Cu")
		(at 64.262 25.908 180)
		(property "Reference" "C67"
			(at -1.37033 -2.159 270)
			(unlocked yes)
			(layer "B.SilkS")
			(effects
				(font
					(size 0.7874 0.5842)
					(thickness 0.127)
				)
				(justify left mirror)
			)
		)
		(property "Value" "100UF"
			(at 0.78232 0.4826 90)
			(unlocked yes)
			(layer "B.Fab")
			(hide yes)
			(effects
				(font
					(size 1.27 0.9652)
					(thickness 0.000001)
				)
				(justify left mirror)
			)
		)
		(property "Device Type" "CAPC0087"
			(at 0.78232 0.4826 90)
			(unlocked yes)
			(layer "B.Fab")
			(hide yes)
			(effects
				(font
					(size 1.27 0.9652)
					(thickness 0.000001)
				)
				(justify left mirror)
			)
		)
		(duplicate_pad_numbers_are_jumpers no)
		(fp_circle
			(center 0 0)
			(end -0.508 0)
			(stroke
				(width 0.2032)
				(type default)
			)
			(fill no)
			(layer "B.SilkS")
		)
		(fp_poly
			(pts
				(xy 1.007212 2.9464) (xy -1.27 2.9464) (xy -1.27 -2.9464) (xy 1.007212 -2.9464)
			)
			(stroke
				(width 0)
				(type default)
			)
			(fill no)
			(layer "B.CrtYd")
		)
		(fp_line
			(start 1.016 2.794)
			(end 1.016 -2.794)
			(stroke
				(width 0.0254)
				(type default)
			)
			(layer "B.Fab")
		)
		(fp_line
			(start 1.016 -2.794)
			(end -1.016 -2.794)
			(stroke
				(width 0.0254)
				(type default)
			)
			(layer "B.Fab")
		)
		(fp_line
			(start -1.016 2.794)
			(end 1.016 2.794)
			(stroke
				(width 0.0254)
				(type default)
			)
			(layer "B.Fab")
		)
		(fp_line
			(start -1.016 -2.794)
			(end -1.016 2.794)
			(stroke
				(width 0.0254)
				(type default)
			)
			(layer "B.Fab")
		)
		(pad "1" smd rect
			(at 0 -1.6764)
			(size 1.524 1.524)
			(layers "B.Cu" "B.Mask" "B.Paste")
			(net "DDR_VDDQ")
		)
		(pad "2" smd rect
			(at 0 1.6764)
			(size 1.524 1.524)
			(layers "B.Cu" "B.Mask" "B.Paste")
			(net "GND")
		)
		(zone
			(layer "B.Cu")
			(hatch none 0.5)
			(connect_pads
				(clearance 0)
			)
			(min_thickness 0.25)
			(keepout
				(tracks allowed)
				(vias not_allowed)
				(pads allowed)
				(copperpour not_allowed)
				(footprints allowed)
			)
			(placement
				(enabled no)
				(sheetname "")
			)
			(fill
				(thermal_gap 0.5)
				(thermal_bridge_width 0.5)
				(island_removal_mode 0)
			)
			(polygon
				(pts
					(xy 63.4746 24.3078) (xy 65.0494 24.3078) (xy 65.0494 27.5082) (xy 63.4746 27.5082)
				)
			)
		)
		(zone
			(layer "B.Cu")
			(hatch none 0.5)
			(connect_pads
				(clearance 0)
			)
			(min_thickness 0.25)
			(keepout
				(tracks not_allowed)
				(vias allowed)
				(pads allowed)
				(copperpour not_allowed)
				(footprints allowed)
			)
			(placement
				(enabled no)
				(sheetname "")
			)
			(fill
				(thermal_gap 0.5)
				(thermal_bridge_width 0.5)
				(island_removal_mode 0)
			)
			(polygon
				(pts
					(xy 63.4746 25.1714) (xy 65.0494 25.1714) (xy 65.0494 25.019) (xy 63.4746 25.019)
				)
			)
		)
		(zone
			(layer "B.Cu")
			(hatch none 0.5)
			(connect_pads
				(clearance 0)
			)
			(min_thickness 0.25)
			(keepout
				(tracks not_allowed)
				(vias allowed)
				(pads allowed)
				(copperpour not_allowed)
				(footprints allowed)
			)
			(placement
				(enabled no)
				(sheetname "")
			)
			(fill
				(thermal_gap 0.5)
				(thermal_bridge_width 0.5)
				(island_removal_mode 0)
			)
			(polygon
				(pts
					(xy 63.4746 26.797) (xy 65.0494 26.797) (xy 65.0494 26.6446) (xy 63.4746 26.6446)
				)
			)
		)
	)
	(footprint ""
		(layer "B.Cu")
		(at 82.65099 1.899006)
		(property "Reference" "V1_A-A05"
			(at 0 0 0)
			(layer "B.SilkS")
			(hide yes)
			(effects
				(font
					(size 1.27 1.27)
				)
				(justify mirror)
			)
		)
		(property "Value" ""
			(at 0 0 0)
			(layer "B.Fab")
			(effects
				(font
					(size 1.27 1.27)
				)
				(justify mirror)
			)
		)
		(duplicate_pad_numbers_are_jumpers no)
		(pad "1" thru_hole circle
			(at 0 0 180)
			(size 0.4572 0.4572)
			(drill 0.20574)
			(layers "*.Cu" "*.Mask")
			(remove_unused_layers no)
			(net "DDR0_32A_A5")
			(clearance 0.1143)
			(thermal_gap 0.1143)
		)
	)
	(footprint ""
		(layer "B.Cu")
		(at 23.241 16.891)
		(property "Reference" "R29"
			(at 0.86233 0.254 270)
			(unlocked yes)
			(layer "B.SilkS")
			(effects
				(font
					(size 0.7874 0.5842)
					(thickness 0.127)
				)
				(justify left mirror)
			)
		)
		(property "Value" "4.75K"
			(at 0.148158 1.3462 270)
			(unlocked yes)
			(layer "B.Fab")
			(hide yes)
			(effects
				(font
					(size 1.27 0.9652)
					(thickness 0.000001)
				)
				(justify left mirror)
			)
		)
		(property "Device Type" "REST4024"
			(at 0.148158 1.3462 270)
			(unlocked yes)
			(layer "B.Fab")
			(hide yes)
			(effects
				(font
					(size 1.27 0.9652)
					(thickness 0.000001)
				)
				(justify left mirror)
			)
		)
		(duplicate_pad_numbers_are_jumpers no)
		(fp_poly
			(pts
				(xy -0.635 1.0668) (xy -0.635 -1.0668) (xy 0.635 -1.0668) (xy 0.635 1.0668)
			)
			(stroke
				(width 0)
				(type default)
			)
			(fill no)
			(layer "B.CrtYd")
		)
		(fp_line
			(start -0.254 -0.508)
			(end -0.254 0.508)
			(stroke
				(width 0.0254)
				(type default)
			)
			(layer "B.Fab")
		)
		(fp_line
			(start -0.254 0.508)
			(end 0.254 0.508)
			(stroke
				(width 0.0254)
				(type default)
			)
			(layer "B.Fab")
		)
		(fp_line
			(start 0.254 -0.508)
			(end -0.254 -0.508)
			(stroke
				(width 0.0254)
				(type default)
			)
			(layer "B.Fab")
		)
		(fp_line
			(start 0.254 0.508)
			(end 0.254 -0.508)
			(stroke
				(width 0.0254)
				(type default)
			)
			(layer "B.Fab")
		)
		(pad "1" smd rect
			(at 0 -0.4191 180)
			(size 0.508 0.5334)
			(layers "B.Cu" "B.Mask" "B.Paste")
			(net "VDD_3.3V")
		)
		(pad "2" smd rect
			(at 0 0.4191 180)
			(size 0.508 0.5334)
			(layers "B.Cu" "B.Mask" "B.Paste")
			(net "NFP_ARM_SPI_FLASH_WP_L")
		)
		(zone
			(layer "B.Cu")
			(hatch none 0.5)
			(connect_pads
				(clearance 0)
			)
			(min_thickness 0.25)
			(keepout
				(tracks not_allowed)
				(vias allowed)
				(pads allowed)
				(copperpour not_allowed)
				(footprints allowed)
			)
			(placement
				(enabled no)
				(sheetname "")
			)
			(fill
				(thermal_gap 0.5)
				(thermal_bridge_width 0.5)
				(island_removal_mode 0)
			)
			(polygon
				(pts
					(xy 23.2156 16.8656) (xy 23.2156 16.9164) (xy 23.2664 16.9164) (xy 23.2664 16.8656)
				)
			)
		)
	)
	(footprint ""
		(layer "B.Cu")
		(at 60.325 0.762 180)
		(property "Reference" "C155"
			(at 0.145212 0.8763 270)
			(unlocked yes)
			(layer "B.SilkS")
			(effects
				(font
					(size 0.7874 0.5842)
					(thickness 0.127)
				)
				(justify left mirror)
			)
		)
		(property "Value" "0.22UF"
			(at 0.091846 0.2921 90)
			(unlocked yes)
			(layer "B.Fab")
			(hide yes)
			(effects
				(font
					(size 0.7874 0.5842)
					(thickness 0.2032)
				)
				(justify left mirror)
			)
		)
		(property "Device Type" "CAPC0062"
			(at 0.091846 0.2921 90)
			(unlocked yes)
			(layer "B.Fab")
			(hide yes)
			(effects
				(font
					(size 0.7874 0.5842)
					(thickness 0.2032)
				)
				(justify left mirror)
			)
		)
		(duplicate_pad_numbers_are_jumpers no)
		(fp_poly
			(pts
				(xy -0.635 1.0668) (xy -0.635 -1.0668) (xy 0.635 -1.0668) (xy 0.635 1.0668)
			)
			(stroke
				(width 0)
				(type default)
			)
			(fill no)
			(layer "B.CrtYd")
		)
		(fp_line
			(start 0.254 0.508)
			(end 0.254 -0.508)
			(stroke
				(width 0.0254)
				(type default)
			)
			(layer "B.Fab")
		)
		(fp_line
			(start 0.254 -0.508)
			(end -0.254 -0.508)
			(stroke
				(width 0.0254)
				(type default)
			)
			(layer "B.Fab")
		)
		(fp_line
			(start -0.254 0.508)
			(end 0.254 0.508)
			(stroke
				(width 0.0254)
				(type default)
			)
			(layer "B.Fab")
		)
		(fp_line
			(start -0.254 -0.508)
			(end -0.254 0.508)
			(stroke
				(width 0.0254)
				(type default)
			)
			(layer "B.Fab")
		)
		(pad "1" smd rect
			(at 0 -0.4191)
			(size 0.508 0.5334)
			(layers "B.Cu" "B.Mask" "B.Paste")
			(net "_NFP_PCIE0_PER1_P")
		)
		(pad "2" smd rect
			(at 0 0.4191)
			(size 0.508 0.5334)
			(layers "B.Cu" "B.Mask" "B.Paste")
			(net "NFP_PCIE0_PER1_P")
		)
		(zone
			(layer "B.Cu")
			(hatch none 0.5)
			(connect_pads
				(clearance 0)
			)
			(min_thickness 0.25)
			(keepout
				(tracks not_allowed)
				(vias allowed)
				(pads allowed)
				(copperpour not_allowed)
				(footprints allowed)
			)
			(placement
				(enabled no)
				(sheetname "")
			)
			(fill
				(thermal_gap 0.5)
				(thermal_bridge_width 0.5)
				(island_removal_mode 0)
			)
			(polygon
				(pts
					(xy 60.3504 0.7874) (xy 60.3504 0.7366) (xy 60.2996 0.7366) (xy 60.2996 0.7874)
				)
			)
		)
	)
	(footprint ""
		(layer "B.Cu")
		(at 32.766 32.639)
		(property "Reference" "R82"
			(at -0.02667 3.683 270)
			(unlocked yes)
			(layer "B.SilkS")
			(effects
				(font
					(size 0.7874 0.5842)
					(thickness 0.127)
				)
				(justify left mirror)
			)
		)
		(property "Value" "4.75K"
			(at 0.148158 1.3462 270)
			(unlocked yes)
			(layer "B.Fab")
			(hide yes)
			(effects
				(font
					(size 1.27 0.9652)
					(thickness 0.000001)
				)
				(justify left mirror)
			)
		)
		(property "Device Type" "REST4024"
			(at 0.148158 1.3462 270)
			(unlocked yes)
			(layer "B.Fab")
			(hide yes)
			(effects
				(font
					(size 1.27 0.9652)
					(thickness 0.000001)
				)
				(justify left mirror)
			)
		)
		(duplicate_pad_numbers_are_jumpers no)
		(fp_poly
			(pts
				(xy -0.635 1.0668) (xy -0.635 -1.0668) (xy 0.635 -1.0668) (xy 0.635 1.0668)
			)
			(stroke
				(width 0)
				(type default)
			)
			(fill no)
			(layer "B.CrtYd")
		)
		(fp_line
			(start -0.254 -0.508)
			(end -0.254 0.508)
			(stroke
				(width 0.0254)
				(type default)
			)
			(layer "B.Fab")
		)
		(fp_line
			(start -0.254 0.508)
			(end 0.254 0.508)
			(stroke
				(width 0.0254)
				(type default)
			)
			(layer "B.Fab")
		)
		(fp_line
			(start 0.254 -0.508)
			(end -0.254 -0.508)
			(stroke
				(width 0.0254)
				(type default)
			)
			(layer "B.Fab")
		)
		(fp_line
			(start 0.254 0.508)
			(end 0.254 -0.508)
			(stroke
				(width 0.0254)
				(type default)
			)
			(layer "B.Fab")
		)
		(pad "1" smd rect
			(at 0 -0.4191 180)
			(size 0.508 0.5334)
			(layers "B.Cu" "B.Mask" "B.Paste")
			(net "GND")
		)
		(pad "2" smd rect
			(at 0 0.4191 180)
			(size 0.508 0.5334)
			(layers "B.Cu" "B.Mask" "B.Paste")
			(net "_NFP_CORE_VID5")
		)
		(zone
			(layer "B.Cu")
			(hatch none 0.5)
			(connect_pads
				(clearance 0)
			)
			(min_thickness 0.25)
			(keepout
				(tracks not_allowed)
				(vias allowed)
				(pads allowed)
				(copperpour not_allowed)
				(footprints allowed)
			)
			(placement
				(enabled no)
				(sheetname "")
			)
			(fill
				(thermal_gap 0.5)
				(thermal_bridge_width 0.5)
				(island_removal_mode 0)
			)
			(polygon
				(pts
					(xy 32.7406 32.6136) (xy 32.7406 32.6644) (xy 32.7914 32.6644) (xy 32.7914 32.6136)
				)
			)
		)
	)
	(footprint ""
		(layer "B.Cu")
		(at 38.989 46.736)
		(property "Reference" "TP9"
			(at 1.651 -3.27533 0)
			(unlocked yes)
			(layer "B.SilkS")
			(effects
				(font
					(size 0.7874 0.5842)
					(thickness 0.127)
				)
				(justify left mirror)
			)
		)
		(property "Value" "*"
			(at 0.4826 -0.14732 0)
			(unlocked yes)
			(layer "B.Fab")
			(hide yes)
			(effects
				(font
					(size 1.27 0.9652)
					(thickness 0.000001)
				)
				(justify left mirror)
			)
		)
		(property "Device Type" "TP_SMALL"
			(at 0.4826 -0.14732 0)
			(unlocked yes)
			(layer "B.Fab")
			(hide yes)
			(effects
				(font
					(size 1.27 0.9652)
					(thickness 0.000001)
				)
				(justify left mirror)
			)
		)
		(duplicate_pad_numbers_are_jumpers no)
		(fp_line
			(start -0.8636 -0.8636)
			(end 0.8636 -0.8636)
			(stroke
				(width 0.1524)
				(type default)
			)
			(layer "B.SilkS")
		)
		(fp_line
			(start -0.8636 0.8636)
			(end -0.8636 -0.8636)
			(stroke
				(width 0.1524)
				(type default)
			)
			(layer "B.SilkS")
		)
		(fp_line
			(start 0.8636 -0.8636)
			(end 0.8636 0.8636)
			(stroke
				(width 0.1524)
				(type default)
			)
			(layer "B.SilkS")
		)
		(fp_line
			(start 0.8636 0.8636)
			(end -0.8636 0.8636)
			(stroke
				(width 0.1524)
				(type default)
			)
			(layer "B.SilkS")
		)
		(fp_poly
			(pts
				(xy 0.635 -0.635) (xy 0.635 0.635) (xy -0.635 0.635) (xy -0.635 -0.635)
			)
			(stroke
				(width 0)
				(type default)
			)
			(fill no)
			(layer "B.CrtYd")
		)
		(pad "1" smd rect
			(at 0 0 180)
			(size 1.27 1.27)
			(layers "B.Cu" "B.Mask" "B.Paste")
			(net "NFP_JTAG_ARM_TMS")
		)
	)
	(footprint ""
		(layer "B.Cu")
		(at 80.250995 2.699004)
		(property "Reference" "V1_A-WE"
			(at 0 0 0)
			(layer "B.SilkS")
			(hide yes)
			(effects
				(font
					(size 1.27 1.27)
				)
				(justify mirror)
			)
		)
		(property "Value" ""
			(at 0 0 0)
			(layer "B.Fab")
			(effects
				(font
					(size 1.27 1.27)
				)
				(justify mirror)
			)
		)
		(duplicate_pad_numbers_are_jumpers no)
		(pad "1" thru_hole circle
			(at 0 0 180)
			(size 0.4572 0.4572)
			(drill 0.20574)
			(layers "*.Cu" "*.Mask")
			(remove_unused_layers no)
			(net "DDR0_32A_WE_L")
			(clearance 0.1143)
			(thermal_gap 0.1143)
		)
	)
	(footprint ""
		(layer "B.Cu")
		(at 60.579 41.91)
		(property "Reference" "C16"
			(at -0.91567 1.27 270)
			(unlocked yes)
			(layer "B.SilkS")
			(effects
				(font
					(size 0.7874 0.5842)
					(thickness 0.127)
				)
				(justify left mirror)
			)
		)
		(property "Value" "22UF"
			(at 0.148158 1.7526 270)
			(unlocked yes)
			(layer "B.Fab")
			(hide yes)
			(effects
				(font
					(size 1.27 0.9652)
					(thickness 0.000001)
				)
				(justify left mirror)
			)
		)
		(property "Device Type" "CAPC0063"
			(at 0.148158 1.7526 270)
			(unlocked yes)
			(layer "B.Fab")
			(hide yes)
			(effects
				(font
					(size 1.27 0.9652)
					(thickness 0.000001)
				)
				(justify left mirror)
			)
		)
		(duplicate_pad_numbers_are_jumpers no)
		(fp_circle
			(center 0 0)
			(end 0.127 0)
			(stroke
				(width 0.2032)
				(type default)
			)
			(fill no)
			(layer "B.SilkS")
		)
		(fp_poly
			(pts
				(xy -0.7874 -1.6637) (xy 0.7874 -1.6637) (xy 0.7874 1.6637) (xy -0.7874 1.6637)
			)
			(stroke
				(width 0)
				(type default)
			)
			(fill no)
			(layer "B.CrtYd")
		)
		(fp_line
			(start -0.4064 -0.7874)
			(end -0.4064 0.8128)
			(stroke
				(width 0.0254)
				(type default)
			)
			(layer "B.Fab")
		)
		(fp_line
			(start -0.4064 0.8128)
			(end 0.4064 0.8128)
			(stroke
				(width 0.0254)
				(type default)
			)
			(layer "B.Fab")
		)
		(fp_line
			(start 0.4064 -0.7874)
			(end -0.4064 -0.7874)
			(stroke
				(width 0.0254)
				(type default)
			)
			(layer "B.Fab")
		)
		(fp_line
			(start 0.4064 0.8128)
			(end 0.4064 -0.7874)
			(stroke
				(width 0.0254)
				(type default)
			)
			(layer "B.Fab")
		)
		(pad "1" smd rect
			(at 0 -0.8001 180)
			(size 0.8636 0.9652)
			(layers "B.Cu" "B.Mask" "B.Paste")
			(net "VDD_CORE")
		)
		(pad "2" smd rect
			(at 0 0.8001 180)
			(size 0.8636 0.9652)
			(layers "B.Cu" "B.Mask" "B.Paste")
			(net "GND")
		)
		(zone
			(layer "B.Cu")
			(hatch none 0.5)
			(connect_pads
				(clearance 0)
			)
			(min_thickness 0.25)
			(keepout
				(tracks not_allowed)
				(vias allowed)
				(pads allowed)
				(copperpour not_allowed)
				(footprints allowed)
			)
			(placement
				(enabled no)
				(sheetname "")
			)
			(fill
				(thermal_gap 0.5)
				(thermal_bridge_width 0.5)
				(island_removal_mode 0)
			)
			(polygon
				(pts
					(xy 60.6425 41.656) (xy 60.5155 41.656) (xy 60.5155 42.164) (xy 60.6425 42.164)
				)
			)
		)
	)
	(footprint ""
		(layer "B.Cu")
		(at 26.035 22.225 180)
		(property "Reference" "R410"
			(at 0.02667 0.889 270)
			(unlocked yes)
			(layer "B.SilkS")
			(effects
				(font
					(size 0.7874 0.5842)
					(thickness 0.127)
				)
				(justify left mirror)
			)
		)
		(property "Value" "240"
			(at 0.148158 1.3462 90)
			(unlocked yes)
			(layer "B.Fab")
			(hide yes)
			(effects
				(font
					(size 1.27 0.9652)
					(thickness 0.000001)
				)
				(justify left mirror)
			)
		)
		(property "Device Type" "REST0009"
			(at 0.148158 1.3462 90)
			(unlocked yes)
			(layer "B.Fab")
			(hide yes)
			(effects
				(font
					(size 1.27 0.9652)
					(thickness 0.000001)
				)
				(justify left mirror)
			)
		)
		(duplicate_pad_numbers_are_jumpers no)
		(fp_poly
			(pts
				(xy -0.635 1.0668) (xy -0.635 -1.0668) (xy 0.635 -1.0668) (xy 0.635 1.0668)
			)
			(stroke
				(width 0)
				(type default)
			)
			(fill no)
			(layer "B.CrtYd")
		)
		(fp_line
			(start 0.254 0.508)
			(end 0.254 -0.508)
			(stroke
				(width 0.0254)
				(type default)
			)
			(layer "B.Fab")
		)
		(fp_line
			(start 0.254 -0.508)
			(end -0.254 -0.508)
			(stroke
				(width 0.0254)
				(type default)
			)
			(layer "B.Fab")
		)
		(fp_line
			(start -0.254 0.508)
			(end 0.254 0.508)
			(stroke
				(width 0.0254)
				(type default)
			)
			(layer "B.Fab")
		)
		(fp_line
			(start -0.254 -0.508)
			(end -0.254 0.508)
			(stroke
				(width 0.0254)
				(type default)
			)
			(layer "B.Fab")
		)
		(pad "1" smd rect
			(at 0 -0.4191)
			(size 0.508 0.5334)
			(layers "B.Cu" "B.Mask" "B.Paste")
			(net "_NFP_CLK_NRESET_L")
		)
		(pad "2" smd rect
			(at 0 0.4191)
			(size 0.508 0.5334)
			(layers "B.Cu" "B.Mask" "B.Paste")
			(net "NFP_CLK_NRESET_L")
		)
		(zone
			(layer "B.Cu")
			(hatch none 0.5)
			(connect_pads
				(clearance 0)
			)
			(min_thickness 0.25)
			(keepout
				(tracks not_allowed)
				(vias allowed)
				(pads allowed)
				(copperpour not_allowed)
				(footprints allowed)
			)
			(placement
				(enabled no)
				(sheetname "")
			)
			(fill
				(thermal_gap 0.5)
				(thermal_bridge_width 0.5)
				(island_removal_mode 0)
			)
			(polygon
				(pts
					(xy 26.0604 22.2504) (xy 26.0604 22.1996) (xy 26.0096 22.1996) (xy 26.0096 22.2504)
				)
			)
		)
	)
	(footprint ""
		(layer "B.Cu")
		(at 54.737 12.292736 -90)
		(property "Reference" "L3"
			(at -1.725066 -0.635 0)
			(unlocked yes)
			(layer "B.SilkS")
			(effects
				(font
					(size 0.7874 0.5842)
					(thickness 0.127)
				)
				(justify left mirror)
			)
		)
		(property "Value" ""
			(at 0 0 90)
			(layer "B.Fab")
			(effects
				(font
					(size 1.27 1.27)
				)
				(justify mirror)
			)
		)
		(duplicate_pad_numbers_are_jumpers no)
		(fp_rect
			(start -1.7907 0.889)
			(end 1.7907 -0.889)
			(stroke
				(width 0)
				(type default)
			)
			(fill no)
			(layer "B.CrtYd")
		)
		(fp_line
			(start -1.778 0.762)
			(end 1.778 0.762)
			(stroke
				(width 0.0254)
				(type default)
			)
			(layer "B.Fab")
		)
		(fp_line
			(start 1.778 0.762)
			(end 1.778 -0.762)
			(stroke
				(width 0.0254)
				(type default)
			)
			(layer "B.Fab")
		)
		(fp_line
			(start -1.778 -0.762)
			(end -1.778 0.762)
			(stroke
				(width 0.0254)
				(type default)
			)
			(layer "B.Fab")
		)
		(fp_line
			(start 1.778 -0.762)
			(end -1.778 -0.762)
			(stroke
				(width 0.0254)
				(type default)
			)
			(layer "B.Fab")
		)
		(pad "1" smd rect
			(at 0.7493 0)
			(size 0.7874 0.8128)
			(layers "B.Cu" "B.Mask" "B.Paste")
			(net "VDD_CORE")
		)
		(pad "2" smd rect
			(at -0.7493 0)
			(size 0.7874 0.8128)
			(layers "B.Cu" "B.Mask" "B.Paste")
			(net "VDDA_SERDES")
		)
		(zone
			(layer "B.Cu")
			(hatch none 0.5)
			(connect_pads
				(clearance 0)
			)
			(min_thickness 0.25)
			(keepout
				(tracks not_allowed)
				(vias allowed)
				(pads allowed)
				(copperpour not_allowed)
				(footprints allowed)
			)
			(placement
				(enabled no)
				(sheetname "")
			)
			(fill
				(thermal_gap 0.5)
				(thermal_bridge_width 0.5)
				(island_removal_mode 0)
			)
			(polygon
				(pts
					(xy 55.1434 12.572136) (xy 54.3306 12.572136) (xy 54.3306 12.013336) (xy 55.1434 12.013336)
				)
			)
		)
	)
	(footprint ""
		(layer "B.Cu")
		(at 20.701 27.305)
		(property "Reference" "R28"
			(at -0.66167 1.778 270)
			(unlocked yes)
			(layer "B.SilkS")
			(effects
				(font
					(size 0.7874 0.5842)
					(thickness 0.127)
				)
				(justify left mirror)
			)
		)
		(property "Value" "4.75K"
			(at 0.148158 1.3462 270)
			(unlocked yes)
			(layer "B.Fab")
			(hide yes)
			(effects
				(font
					(size 1.27 0.9652)
					(thickness 0.000001)
				)
				(justify left mirror)
			)
		)
		(property "Device Type" "REST4024"
			(at 0.148158 1.3462 270)
			(unlocked yes)
			(layer "B.Fab")
			(hide yes)
			(effects
				(font
					(size 1.27 0.9652)
					(thickness 0.000001)
				)
				(justify left mirror)
			)
		)
		(duplicate_pad_numbers_are_jumpers no)
		(fp_poly
			(pts
				(xy -0.635 1.0668) (xy -0.635 -1.0668) (xy 0.635 -1.0668) (xy 0.635 1.0668)
			)
			(stroke
				(width 0)
				(type default)
			)
			(fill no)
			(layer "B.CrtYd")
		)
		(fp_line
			(start -0.254 -0.508)
			(end -0.254 0.508)
			(stroke
				(width 0.0254)
				(type default)
			)
			(layer "B.Fab")
		)
		(fp_line
			(start -0.254 0.508)
			(end 0.254 0.508)
			(stroke
				(width 0.0254)
				(type default)
			)
			(layer "B.Fab")
		)
		(fp_line
			(start 0.254 -0.508)
			(end -0.254 -0.508)
			(stroke
				(width 0.0254)
				(type default)
			)
			(layer "B.Fab")
		)
		(fp_line
			(start 0.254 0.508)
			(end 0.254 -0.508)
			(stroke
				(width 0.0254)
				(type default)
			)
			(layer "B.Fab")
		)
		(pad "1" smd rect
			(at 0 -0.4191 180)
			(size 0.508 0.5334)
			(layers "B.Cu" "B.Mask" "B.Paste")
			(net "VDD_3.3V")
		)
		(pad "2" smd rect
			(at 0 0.4191 180)
			(size 0.508 0.5334)
			(layers "B.Cu" "B.Mask" "B.Paste")
			(net "NFP_ARM_SPI_FLASH_SEL")
		)
		(zone
			(layer "B.Cu")
			(hatch none 0.5)
			(connect_pads
				(clearance 0)
			)
			(min_thickness 0.25)
			(keepout
				(tracks not_allowed)
				(vias allowed)
				(pads allowed)
				(copperpour not_allowed)
				(footprints allowed)
			)
			(placement
				(enabled no)
				(sheetname "")
			)
			(fill
				(thermal_gap 0.5)
				(thermal_bridge_width 0.5)
				(island_removal_mode 0)
			)
			(polygon
				(pts
					(xy 20.6756 27.2796) (xy 20.6756 27.3304) (xy 20.7264 27.3304) (xy 20.7264 27.2796)
				)
			)
		)
	)
	(footprint ""
		(layer "B.Cu")
		(at 43.5229 41.0845)
		(property "Reference" "R117"
			(at 0 0 0)
			(layer "B.SilkS")
			(hide yes)
			(effects
				(font
					(size 1.27 1.27)
				)
				(justify mirror)
			)
		)
		(property "Value" "2.2"
			(at 0.148158 1.7526 270)
			(unlocked yes)
			(layer "B.Fab")
			(hide yes)
			(effects
				(font
					(size 1.27 0.9652)
					(thickness 0.000001)
				)
				(justify left mirror)
			)
		)
		(property "Device Type" "REST0145"
			(at 0.148158 1.7526 270)
			(unlocked yes)
			(layer "B.Fab")
			(hide yes)
			(effects
				(font
					(size 1.27 0.9652)
					(thickness 0.000001)
				)
				(justify left mirror)
			)
		)
		(duplicate_pad_numbers_are_jumpers no)
		(fp_circle
			(center 0 0)
			(end 0.127 0)
			(stroke
				(width 0.2032)
				(type default)
			)
			(fill no)
			(layer "B.SilkS")
		)
		(fp_poly
			(pts
				(xy -0.7874 -1.6637) (xy 0.7874 -1.6637) (xy 0.7874 1.6637) (xy -0.7874 1.6637)
			)
			(stroke
				(width 0)
				(type default)
			)
			(fill no)
			(layer "B.CrtYd")
		)
		(fp_line
			(start -0.4064 -0.8128)
			(end -0.4064 0.8128)
			(stroke
				(width 0.0254)
				(type default)
			)
			(layer "B.Fab")
		)
		(fp_line
			(start -0.4064 0.8128)
			(end 0.4064 0.8128)
			(stroke
				(width 0.0254)
				(type default)
			)
			(layer "B.Fab")
		)
		(fp_line
			(start 0.4064 -0.8128)
			(end -0.4064 -0.8128)
			(stroke
				(width 0.0254)
				(type default)
			)
			(layer "B.Fab")
		)
		(fp_line
			(start 0.4064 0.8128)
			(end 0.4064 -0.8128)
			(stroke
				(width 0.0254)
				(type default)
			)
			(layer "B.Fab")
		)
		(pad "1" smd rect
			(at 0 -0.8001 180)
			(size 0.762 0.9652)
			(layers "B.Cu" "B.Mask" "B.Paste")
			(net "10N2223")
		)
		(pad "2" smd rect
			(at 0 0.8001 180)
			(size 0.762 0.9652)
			(layers "B.Cu" "B.Mask" "B.Paste")
			(net "L_2_CORE_PHASE")
		)
		(zone
			(layer "B.Cu")
			(hatch none 0.5)
			(connect_pads
				(clearance 0)
			)
			(min_thickness 0.25)
			(keepout
				(tracks not_allowed)
				(vias allowed)
				(pads allowed)
				(copperpour not_allowed)
				(footprints allowed)
			)
			(placement
				(enabled no)
				(sheetname "")
			)
			(fill
				(thermal_gap 0.5)
				(thermal_bridge_width 0.5)
				(island_removal_mode 0)
			)
			(polygon
				(pts
					(xy 43.5864 40.8305) (xy 43.4594 40.8305) (xy 43.4594 41.3385) (xy 43.5864 41.3385)
				)
			)
		)
	)
	(footprint ""
		(layer "B.Cu")
		(at 76.073 43.688)
		(property "Reference" "C140"
			(at 0.48133 4.445 270)
			(unlocked yes)
			(layer "B.SilkS")
			(effects
				(font
					(size 0.7874 0.5842)
					(thickness 0.127)
				)
				(justify left mirror)
			)
		)
		(property "Value" "10UF"
			(at 0.148158 1.7526 270)
			(unlocked yes)
			(layer "B.Fab")
			(hide yes)
			(effects
				(font
					(size 1.27 0.9652)
					(thickness 0.000001)
				)
				(justify left mirror)
			)
		)
		(property "Device Type" "CAPC0058"
			(at 0.148158 1.7526 270)
			(unlocked yes)
			(layer "B.Fab")
			(hide yes)
			(effects
				(font
					(size 1.27 0.9652)
					(thickness 0.000001)
				)
				(justify left mirror)
			)
		)
		(duplicate_pad_numbers_are_jumpers no)
		(fp_circle
			(center 0 0)
			(end 0.127 0)
			(stroke
				(width 0.2032)
				(type default)
			)
			(fill no)
			(layer "B.SilkS")
		)
		(fp_poly
			(pts
				(xy -0.7874 -1.6637) (xy 0.7874 -1.6637) (xy 0.7874 1.6637) (xy -0.7874 1.6637)
			)
			(stroke
				(width 0)
				(type default)
			)
			(fill no)
			(layer "B.CrtYd")
		)
		(fp_line
			(start -0.4064 -0.7874)
			(end -0.4064 0.8128)
			(stroke
				(width 0.0254)
				(type default)
			)
			(layer "B.Fab")
		)
		(fp_line
			(start -0.4064 0.8128)
			(end 0.4064 0.8128)
			(stroke
				(width 0.0254)
				(type default)
			)
			(layer "B.Fab")
		)
		(fp_line
			(start 0.4064 -0.7874)
			(end -0.4064 -0.7874)
			(stroke
				(width 0.0254)
				(type default)
			)
			(layer "B.Fab")
		)
		(fp_line
			(start 0.4064 0.8128)
			(end 0.4064 -0.7874)
			(stroke
				(width 0.0254)
				(type default)
			)
			(layer "B.Fab")
		)
		(pad "1" smd rect
			(at 0 -0.8001 180)
			(size 0.8636 0.9652)
			(layers "B.Cu" "B.Mask" "B.Paste")
			(net "DDR_VTT")
		)
		(pad "2" smd rect
			(at 0 0.8001 180)
			(size 0.8636 0.9652)
			(layers "B.Cu" "B.Mask" "B.Paste")
			(net "GND")
		)
	)
	(footprint ""
		(layer "B.Cu")
		(at 63.236983 9.542018 180)
		(property "Reference" "C195"
			(at 0 0 0)
			(layer "B.SilkS")
			(hide yes)
			(effects
				(font
					(size 1.27 1.27)
				)
				(justify mirror)
			)
		)
		(property "Value" ""
			(at 0 0 0)
			(layer "B.Fab")
			(effects
				(font
					(size 1.27 1.27)
				)
				(justify mirror)
			)
		)
		(duplicate_pad_numbers_are_jumpers no)
		(fp_circle
			(center 0 0)
			(end -0.104648 0)
			(stroke
				(width 0.1016)
				(type default)
			)
			(fill no)
			(layer "B.SilkS")
		)
		(fp_poly
			(pts
				(xy 0.381 -0.889) (xy 0.381 0.889) (xy -0.381 0.889) (xy -0.381 -0.889)
			)
			(stroke
				(width 0)
				(type default)
			)
			(fill no)
			(layer "B.CrtYd")
		)
		(fp_line
			(start 0.508 1.016)
			(end 0.508 -1.016)
			(stroke
				(width 0.0254)
				(type default)
			)
			(layer "B.Fab")
		)
		(fp_line
			(start 0.508 -1.016)
			(end 0.254 -1.016)
			(stroke
				(width 0.0254)
				(type default)
			)
			(layer "B.Fab")
		)
		(fp_line
			(start 0.254 -1.016)
			(end -0.508 -1.016)
			(stroke
				(width 0.0254)
				(type default)
			)
			(layer "B.Fab")
		)
		(fp_line
			(start -0.508 1.016)
			(end 0.508 1.016)
			(stroke
				(width 0.0254)
				(type default)
			)
			(layer "B.Fab")
		)
		(fp_line
			(start -0.508 -1.016)
			(end -0.508 1.016)
			(stroke
				(width 0.0254)
				(type default)
			)
			(layer "B.Fab")
		)
		(pad "1" smd custom
			(at 0 -0.500126)
			(size 0.127 0.127)
			(layers "B.Cu" "B.Mask" "B.Paste")
			(net "DDR_VDDQ")
			(options
				(clearance outline)
				(anchor circle)
			)
			(primitives
				(gr_poly
					(pts
						(xy -0.1778 0.254) (xy 0.1778 0.254) (xy 0.254 0.1778) (xy 0.254 -0.1778) (xy 0.1778 -0.254) (xy -0.1778 -0.254)
						(xy -0.254 -0.1778) (xy -0.254 0.1778)
					)
					(width 0)
					(fill yes)
				)
			)
		)
		(pad "2" smd custom
			(at 0 0.500126)
			(size 0.127 0.127)
			(layers "B.Cu" "B.Mask" "B.Paste")
			(net "GND")
			(options
				(clearance outline)
				(anchor circle)
			)
			(primitives
				(gr_poly
					(pts
						(xy -0.1778 0.254) (xy 0.1778 0.254) (xy 0.254 0.1778) (xy 0.254 -0.1778) (xy 0.1778 -0.254) (xy -0.1778 -0.254)
						(xy -0.254 -0.1778) (xy -0.254 0.1778)
					)
					(width 0)
					(fill yes)
				)
			)
		)
	)
	(footprint ""
		(layer "B.Cu")
		(at 80.250995 25.813004)
		(property "Reference" "V3_A-WE"
			(at 0 0 0)
			(layer "B.SilkS")
			(hide yes)
			(effects
				(font
					(size 1.27 1.27)
				)
				(justify mirror)
			)
		)
		(property "Value" ""
			(at 0 0 0)
			(layer "B.Fab")
			(effects
				(font
					(size 1.27 1.27)
				)
				(justify mirror)
			)
		)
		(duplicate_pad_numbers_are_jumpers no)
		(pad "1" thru_hole circle
			(at 0 0 180)
			(size 0.4572 0.4572)
			(drill 0.20574)
			(layers "*.Cu" "*.Mask")
			(remove_unused_layers no)
			(net "DDR0_32A_WE_L")
			(clearance 0.1143)
			(thermal_gap 0.1143)
		)
	)
	(footprint ""
		(layer "B.Cu")
		(at 75.451005 1.899006)
		(property "Reference" "V_A-DQ00"
			(at 0 0 0)
			(layer "B.SilkS")
			(hide yes)
			(effects
				(font
					(size 1.27 1.27)
				)
				(justify mirror)
			)
		)
		(property "Value" ""
			(at 0 0 0)
			(layer "B.Fab")
			(effects
				(font
					(size 1.27 1.27)
				)
				(justify mirror)
			)
		)
		(duplicate_pad_numbers_are_jumpers no)
		(pad "1" thru_hole circle
			(at 0 0 180)
			(size 0.4572 0.4572)
			(drill 0.20574)
			(layers "*.Cu" "*.Mask")
			(remove_unused_layers no)
			(net "DDR0_32A_DQ0")
			(clearance 0.1143)
			(thermal_gap 0.1143)
		)
	)
	(footprint ""
		(layer "B.Cu")
		(at 47.736887 12.04214 -90)
		(property "Reference" "C93"
			(at 0 0 90)
			(layer "B.SilkS")
			(hide yes)
			(effects
				(font
					(size 1.27 1.27)
				)
				(justify mirror)
			)
		)
		(property "Value" ""
			(at 0 0 90)
			(layer "B.Fab")
			(effects
				(font
					(size 1.27 1.27)
				)
				(justify mirror)
			)
		)
		(duplicate_pad_numbers_are_jumpers no)
		(fp_circle
			(center 0 0)
			(end 0 -0.104648)
			(stroke
				(width 0.1016)
				(type default)
			)
			(fill no)
			(layer "B.SilkS")
		)
		(fp_poly
			(pts
				(xy 0.381 -0.889) (xy 0.381 0.889) (xy -0.381 0.889) (xy -0.381 -0.889)
			)
			(stroke
				(width 0)
				(type default)
			)
			(fill no)
			(layer "B.CrtYd")
		)
		(fp_line
			(start -0.508 1.016)
			(end 0.508 1.016)
			(stroke
				(width 0.0254)
				(type default)
			)
			(layer "B.Fab")
		)
		(fp_line
			(start 0.508 1.016)
			(end 0.508 -1.016)
			(stroke
				(width 0.0254)
				(type default)
			)
			(layer "B.Fab")
		)
		(fp_line
			(start -0.508 -1.016)
			(end -0.508 1.016)
			(stroke
				(width 0.0254)
				(type default)
			)
			(layer "B.Fab")
		)
		(fp_line
			(start 0.254 -1.016)
			(end -0.508 -1.016)
			(stroke
				(width 0.0254)
				(type default)
			)
			(layer "B.Fab")
		)
		(fp_line
			(start 0.508 -1.016)
			(end 0.254 -1.016)
			(stroke
				(width 0.0254)
				(type default)
			)
			(layer "B.Fab")
		)
		(pad "1" smd custom
			(at 0 -0.500126 90)
			(size 0.127 0.127)
			(layers "B.Cu" "B.Mask" "B.Paste")
			(net "VDDA_SERDES")
			(options
				(clearance outline)
				(anchor circle)
			)
			(primitives
				(gr_poly
					(pts
						(xy -0.1778 0.254) (xy 0.1778 0.254) (xy 0.254 0.1778) (xy 0.254 -0.1778) (xy 0.1778 -0.254) (xy -0.1778 -0.254)
						(xy -0.254 -0.1778) (xy -0.254 0.1778)
					)
					(width 0)
					(fill yes)
				)
			)
		)
		(pad "2" smd custom
			(at 0 0.500126 90)
			(size 0.127 0.127)
			(layers "B.Cu" "B.Mask" "B.Paste")
			(net "GND")
			(options
				(clearance outline)
				(anchor circle)
			)
			(primitives
				(gr_poly
					(pts
						(xy -0.1778 0.254) (xy 0.1778 0.254) (xy 0.254 0.1778) (xy 0.254 -0.1778) (xy 0.1778 -0.254) (xy -0.1778 -0.254)
						(xy -0.254 -0.1778) (xy -0.254 0.1778)
					)
					(width 0)
					(fill yes)
				)
			)
		)
	)
	(footprint ""
		(layer "B.Cu")
		(at 74.651006 2.699004)
		(property "Reference" "V_A-DQ05"
			(at 0 0 0)
			(layer "B.SilkS")
			(hide yes)
			(effects
				(font
					(size 1.27 1.27)
				)
				(justify mirror)
			)
		)
		(property "Value" ""
			(at 0 0 0)
			(layer "B.Fab")
			(effects
				(font
					(size 1.27 1.27)
				)
				(justify mirror)
			)
		)
		(duplicate_pad_numbers_are_jumpers no)
		(pad "1" thru_hole circle
			(at 0 0 180)
			(size 0.4572 0.4572)
			(drill 0.20574)
			(layers "*.Cu" "*.Mask")
			(remove_unused_layers no)
			(net "DDR0_32A_DQ5")
			(clearance 0.1143)
			(thermal_gap 0.1143)
		)
	)
	(footprint ""
		(layer "B.Cu")
		(at 57.277 41.91)
		(property "Reference" "C18"
			(at 0.60833 3.429 270)
			(unlocked yes)
			(layer "B.SilkS")
			(effects
				(font
					(size 0.7874 0.5842)
					(thickness 0.127)
				)
				(justify left mirror)
			)
		)
		(property "Value" "22UF"
			(at 0.148158 1.7526 270)
			(unlocked yes)
			(layer "B.Fab")
			(hide yes)
			(effects
				(font
					(size 1.27 0.9652)
					(thickness 0.000001)
				)
				(justify left mirror)
			)
		)
		(property "Device Type" "CAPC0063"
			(at 0.148158 1.7526 270)
			(unlocked yes)
			(layer "B.Fab")
			(hide yes)
			(effects
				(font
					(size 1.27 0.9652)
					(thickness 0.000001)
				)
				(justify left mirror)
			)
		)
		(duplicate_pad_numbers_are_jumpers no)
		(fp_circle
			(center 0 0)
			(end 0.127 0)
			(stroke
				(width 0.2032)
				(type default)
			)
			(fill no)
			(layer "B.SilkS")
		)
		(fp_poly
			(pts
				(xy -0.7874 -1.6637) (xy 0.7874 -1.6637) (xy 0.7874 1.6637) (xy -0.7874 1.6637)
			)
			(stroke
				(width 0)
				(type default)
			)
			(fill no)
			(layer "B.CrtYd")
		)
		(fp_line
			(start -0.4064 -0.7874)
			(end -0.4064 0.8128)
			(stroke
				(width 0.0254)
				(type default)
			)
			(layer "B.Fab")
		)
		(fp_line
			(start -0.4064 0.8128)
			(end 0.4064 0.8128)
			(stroke
				(width 0.0254)
				(type default)
			)
			(layer "B.Fab")
		)
		(fp_line
			(start 0.4064 -0.7874)
			(end -0.4064 -0.7874)
			(stroke
				(width 0.0254)
				(type default)
			)
			(layer "B.Fab")
		)
		(fp_line
			(start 0.4064 0.8128)
			(end 0.4064 -0.7874)
			(stroke
				(width 0.0254)
				(type default)
			)
			(layer "B.Fab")
		)
		(pad "1" smd rect
			(at 0 -0.8001 180)
			(size 0.8636 0.9652)
			(layers "B.Cu" "B.Mask" "B.Paste")
			(net "VDD_CORE")
		)
		(pad "2" smd rect
			(at 0 0.8001 180)
			(size 0.8636 0.9652)
			(layers "B.Cu" "B.Mask" "B.Paste")
			(net "GND")
		)
		(zone
			(layer "B.Cu")
			(hatch none 0.5)
			(connect_pads
				(clearance 0)
			)
			(min_thickness 0.25)
			(keepout
				(tracks not_allowed)
				(vias allowed)
				(pads allowed)
				(copperpour not_allowed)
				(footprints allowed)
			)
			(placement
				(enabled no)
				(sheetname "")
			)
			(fill
				(thermal_gap 0.5)
				(thermal_bridge_width 0.5)
				(island_removal_mode 0)
			)
			(polygon
				(pts
					(xy 57.3405 41.656) (xy 57.2135 41.656) (xy 57.2135 42.164) (xy 57.3405 42.164)
				)
			)
		)
	)
	(footprint ""
		(layer "B.Cu")
		(at 50.237009 9.542018)
		(property "Reference" "C103"
			(at 0 0 0)
			(layer "B.SilkS")
			(hide yes)
			(effects
				(font
					(size 1.27 1.27)
				)
				(justify mirror)
			)
		)
		(property "Value" ""
			(at 0 0 0)
			(layer "B.Fab")
			(effects
				(font
					(size 1.27 1.27)
				)
				(justify mirror)
			)
		)
		(duplicate_pad_numbers_are_jumpers no)
		(fp_circle
			(center 0 0)
			(end 0.104648 0)
			(stroke
				(width 0.1016)
				(type default)
			)
			(fill no)
			(layer "B.SilkS")
		)
		(fp_poly
			(pts
				(xy 0.381 -0.889) (xy 0.381 0.889) (xy -0.381 0.889) (xy -0.381 -0.889)
			)
			(stroke
				(width 0)
				(type default)
			)
			(fill no)
			(layer "B.CrtYd")
		)
		(fp_line
			(start -0.508 -1.016)
			(end -0.508 1.016)
			(stroke
				(width 0.0254)
				(type default)
			)
			(layer "B.Fab")
		)
		(fp_line
			(start -0.508 1.016)
			(end 0.508 1.016)
			(stroke
				(width 0.0254)
				(type default)
			)
			(layer "B.Fab")
		)
		(fp_line
			(start 0.254 -1.016)
			(end -0.508 -1.016)
			(stroke
				(width 0.0254)
				(type default)
			)
			(layer "B.Fab")
		)
		(fp_line
			(start 0.508 -1.016)
			(end 0.254 -1.016)
			(stroke
				(width 0.0254)
				(type default)
			)
			(layer "B.Fab")
		)
		(fp_line
			(start 0.508 1.016)
			(end 0.508 -1.016)
			(stroke
				(width 0.0254)
				(type default)
			)
			(layer "B.Fab")
		)
		(pad "1" smd custom
			(at 0 -0.500126 180)
			(size 0.127 0.127)
			(layers "B.Cu" "B.Mask" "B.Paste")
			(net "VDDAH_SERDES")
			(options
				(clearance outline)
				(anchor circle)
			)
			(primitives
				(gr_poly
					(pts
						(xy -0.1778 0.254) (xy 0.1778 0.254) (xy 0.254 0.1778) (xy 0.254 -0.1778) (xy 0.1778 -0.254) (xy -0.1778 -0.254)
						(xy -0.254 -0.1778) (xy -0.254 0.1778)
					)
					(width 0)
					(fill yes)
				)
			)
		)
		(pad "2" smd custom
			(at 0 0.500126 180)
			(size 0.127 0.127)
			(layers "B.Cu" "B.Mask" "B.Paste")
			(net "GND")
			(options
				(clearance outline)
				(anchor circle)
			)
			(primitives
				(gr_poly
					(pts
						(xy -0.1778 0.254) (xy 0.1778 0.254) (xy 0.254 0.1778) (xy 0.254 -0.1778) (xy 0.1778 -0.254) (xy -0.1778 -0.254)
						(xy -0.254 -0.1778) (xy -0.254 0.1778)
					)
					(width 0)
					(fill yes)
				)
			)
		)
	)
	(footprint ""
		(layer "B.Cu")
		(at 23.749 11.303 90)
		(property "Reference" "R403"
			(at 0 0 90)
			(layer "B.SilkS")
			(hide yes)
			(effects
				(font
					(size 1.27 1.27)
				)
				(justify mirror)
			)
		)
		(property "Value" "4.75K"
			(at 0.148158 1.3462 0)
			(unlocked yes)
			(layer "B.Fab")
			(hide yes)
			(effects
				(font
					(size 1.27 0.9652)
					(thickness 0.000001)
				)
				(justify left mirror)
			)
		)
		(property "Device Type" "REST4024"
			(at 0.148158 1.3462 0)
			(unlocked yes)
			(layer "B.Fab")
			(hide yes)
			(effects
				(font
					(size 1.27 0.9652)
					(thickness 0.000001)
				)
				(justify left mirror)
			)
		)
		(duplicate_pad_numbers_are_jumpers no)
		(fp_poly
			(pts
				(xy -0.635 1.0668) (xy -0.635 -1.0668) (xy 0.635 -1.0668) (xy 0.635 1.0668)
			)
			(stroke
				(width 0)
				(type default)
			)
			(fill no)
			(layer "B.CrtYd")
		)
		(fp_line
			(start 0.254 -0.508)
			(end -0.254 -0.508)
			(stroke
				(width 0.0254)
				(type default)
			)
			(layer "B.Fab")
		)
		(fp_line
			(start -0.254 -0.508)
			(end -0.254 0.508)
			(stroke
				(width 0.0254)
				(type default)
			)
			(layer "B.Fab")
		)
		(fp_line
			(start 0.254 0.508)
			(end 0.254 -0.508)
			(stroke
				(width 0.0254)
				(type default)
			)
			(layer "B.Fab")
		)
		(fp_line
			(start -0.254 0.508)
			(end 0.254 0.508)
			(stroke
				(width 0.0254)
				(type default)
			)
			(layer "B.Fab")
		)
		(pad "1" smd rect
			(at 0 -0.4191 270)
			(size 0.508 0.5334)
			(layers "B.Cu" "B.Mask" "B.Paste")
			(net "VDD_3.3V")
		)
		(pad "2" smd rect
			(at 0 0.4191 270)
			(size 0.508 0.5334)
			(layers "B.Cu" "B.Mask" "B.Paste")
			(net "NFP_JTAG_ARM_TDI")
		)
		(zone
			(layer "B.Cu")
			(hatch none 0.5)
			(connect_pads
				(clearance 0)
			)
			(min_thickness 0.25)
			(keepout
				(tracks not_allowed)
				(vias allowed)
				(pads allowed)
				(copperpour not_allowed)
				(footprints allowed)
			)
			(placement
				(enabled no)
				(sheetname "")
			)
			(fill
				(thermal_gap 0.5)
				(thermal_bridge_width 0.5)
				(island_removal_mode 0)
			)
			(polygon
				(pts
					(xy 23.7236 11.3284) (xy 23.7744 11.3284) (xy 23.7744 11.2776) (xy 23.7236 11.2776)
				)
			)
		)
	)
	(footprint ""
		(layer "B.Cu")
		(at 75.451005 18.255996)
		(property "Reference" "V_A-DQ18"
			(at 0 0 0)
			(layer "B.SilkS")
			(hide yes)
			(effects
				(font
					(size 1.27 1.27)
				)
				(justify mirror)
			)
		)
		(property "Value" ""
			(at 0 0 0)
			(layer "B.Fab")
			(effects
				(font
					(size 1.27 1.27)
				)
				(justify mirror)
			)
		)
		(duplicate_pad_numbers_are_jumpers no)
		(pad "1" thru_hole circle
			(at 0 0 180)
			(size 0.4572 0.4572)
			(drill 0.20574)
			(layers "*.Cu" "*.Mask")
			(remove_unused_layers no)
			(net "DDR0_32A_DQ18")
			(clearance 0.1143)
			(thermal_gap 0.1143)
		)
	)
	(footprint ""
		(layer "B.Cu")
		(at 60.736988 17.042003 -90)
		(property "Reference" "C29"
			(at 0 0 90)
			(layer "B.SilkS")
			(hide yes)
			(effects
				(font
					(size 1.27 1.27)
				)
				(justify mirror)
			)
		)
		(property "Value" ""
			(at 0 0 90)
			(layer "B.Fab")
			(effects
				(font
					(size 1.27 1.27)
				)
				(justify mirror)
			)
		)
		(duplicate_pad_numbers_are_jumpers no)
		(fp_circle
			(center 0 0)
			(end 0 -0.104648)
			(stroke
				(width 0.1016)
				(type default)
			)
			(fill no)
			(layer "B.SilkS")
		)
		(fp_poly
			(pts
				(xy 0.381 -0.889) (xy 0.381 0.889) (xy -0.381 0.889) (xy -0.381 -0.889)
			)
			(stroke
				(width 0)
				(type default)
			)
			(fill no)
			(layer "B.CrtYd")
		)
		(fp_line
			(start -0.508 1.016)
			(end 0.508 1.016)
			(stroke
				(width 0.0254)
				(type default)
			)
			(layer "B.Fab")
		)
		(fp_line
			(start 0.508 1.016)
			(end 0.508 -1.016)
			(stroke
				(width 0.0254)
				(type default)
			)
			(layer "B.Fab")
		)
		(fp_line
			(start -0.508 -1.016)
			(end -0.508 1.016)
			(stroke
				(width 0.0254)
				(type default)
			)
			(layer "B.Fab")
		)
		(fp_line
			(start 0.254 -1.016)
			(end -0.508 -1.016)
			(stroke
				(width 0.0254)
				(type default)
			)
			(layer "B.Fab")
		)
		(fp_line
			(start 0.508 -1.016)
			(end 0.254 -1.016)
			(stroke
				(width 0.0254)
				(type default)
			)
			(layer "B.Fab")
		)
		(pad "1" smd custom
			(at 0 -0.500126 90)
			(size 0.127 0.127)
			(layers "B.Cu" "B.Mask" "B.Paste")
			(net "VDDA_PLL")
			(options
				(clearance outline)
				(anchor circle)
			)
			(primitives
				(gr_poly
					(pts
						(xy -0.1778 0.254) (xy 0.1778 0.254) (xy 0.254 0.1778) (xy 0.254 -0.1778) (xy 0.1778 -0.254) (xy -0.1778 -0.254)
						(xy -0.254 -0.1778) (xy -0.254 0.1778)
					)
					(width 0)
					(fill yes)
				)
			)
		)
		(pad "2" smd custom
			(at 0 0.500126 90)
			(size 0.127 0.127)
			(layers "B.Cu" "B.Mask" "B.Paste")
			(net "GND")
			(options
				(clearance outline)
				(anchor circle)
			)
			(primitives
				(gr_poly
					(pts
						(xy -0.1778 0.254) (xy 0.1778 0.254) (xy 0.254 0.1778) (xy 0.254 -0.1778) (xy 0.1778 -0.254) (xy -0.1778 -0.254)
						(xy -0.254 -0.1778) (xy -0.254 0.1778)
					)
					(width 0)
					(fill yes)
				)
			)
		)
	)
	(footprint ""
		(layer "B.Cu")
		(at 29.845 22.225 180)
		(property "Reference" "R52"
			(at 0 0 0)
			(layer "B.SilkS")
			(hide yes)
			(effects
				(font
					(size 1.27 1.27)
				)
				(justify mirror)
			)
		)
		(property "Value" "4.75K"
			(at 0.148158 1.3462 90)
			(unlocked yes)
			(layer "B.Fab")
			(hide yes)
			(effects
				(font
					(size 1.27 0.9652)
					(thickness 0.000001)
				)
				(justify left mirror)
			)
		)
		(property "Device Type" "REST4024"
			(at 0.148158 1.3462 90)
			(unlocked yes)
			(layer "B.Fab")
			(hide yes)
			(effects
				(font
					(size 1.27 0.9652)
					(thickness 0.000001)
				)
				(justify left mirror)
			)
		)
		(duplicate_pad_numbers_are_jumpers no)
		(fp_poly
			(pts
				(xy -0.635 1.0668) (xy -0.635 -1.0668) (xy 0.635 -1.0668) (xy 0.635 1.0668)
			)
			(stroke
				(width 0)
				(type default)
			)
			(fill no)
			(layer "B.CrtYd")
		)
		(fp_line
			(start 0.254 0.508)
			(end 0.254 -0.508)
			(stroke
				(width 0.0254)
				(type default)
			)
			(layer "B.Fab")
		)
		(fp_line
			(start 0.254 -0.508)
			(end -0.254 -0.508)
			(stroke
				(width 0.0254)
				(type default)
			)
			(layer "B.Fab")
		)
		(fp_line
			(start -0.254 0.508)
			(end 0.254 0.508)
			(stroke
				(width 0.0254)
				(type default)
			)
			(layer "B.Fab")
		)
		(fp_line
			(start -0.254 -0.508)
			(end -0.254 0.508)
			(stroke
				(width 0.0254)
				(type default)
			)
			(layer "B.Fab")
		)
		(pad "1" smd rect
			(at 0 -0.4191)
			(size 0.508 0.5334)
			(layers "B.Cu" "B.Mask" "B.Paste")
			(net "EXT_3.3V")
		)
		(pad "2" smd rect
			(at 0 0.4191)
			(size 0.508 0.5334)
			(layers "B.Cu" "B.Mask" "B.Paste")
			(net "CPLD_VERSION_1")
		)
		(zone
			(layer "B.Cu")
			(hatch none 0.5)
			(connect_pads
				(clearance 0)
			)
			(min_thickness 0.25)
			(keepout
				(tracks not_allowed)
				(vias allowed)
				(pads allowed)
				(copperpour not_allowed)
				(footprints allowed)
			)
			(placement
				(enabled no)
				(sheetname "")
			)
			(fill
				(thermal_gap 0.5)
				(thermal_bridge_width 0.5)
				(island_removal_mode 0)
			)
			(polygon
				(pts
					(xy 29.8704 22.2504) (xy 29.8704 22.1996) (xy 29.8196 22.1996) (xy 29.8196 22.2504)
				)
			)
		)
	)
	(footprint ""
		(layer "B.Cu")
		(at 26.289 9.525 90)
		(property "Reference" "R43"
			(at 0.22733 3.556 0)
			(unlocked yes)
			(layer "B.SilkS")
			(effects
				(font
					(size 0.7874 0.5842)
					(thickness 0.127)
				)
				(justify left mirror)
			)
		)
		(property "Value" "4.75K"
			(at 0.148158 1.3462 0)
			(unlocked yes)
			(layer "B.Fab")
			(hide yes)
			(effects
				(font
					(size 1.27 0.9652)
					(thickness 0.000001)
				)
				(justify left mirror)
			)
		)
		(property "Device Type" "REST4024"
			(at 0.148158 1.3462 0)
			(unlocked yes)
			(layer "B.Fab")
			(hide yes)
			(effects
				(font
					(size 1.27 0.9652)
					(thickness 0.000001)
				)
				(justify left mirror)
			)
		)
		(duplicate_pad_numbers_are_jumpers no)
		(fp_poly
			(pts
				(xy -0.635 1.0668) (xy -0.635 -1.0668) (xy 0.635 -1.0668) (xy 0.635 1.0668)
			)
			(stroke
				(width 0)
				(type default)
			)
			(fill no)
			(layer "B.CrtYd")
		)
		(fp_line
			(start 0.254 -0.508)
			(end -0.254 -0.508)
			(stroke
				(width 0.0254)
				(type default)
			)
			(layer "B.Fab")
		)
		(fp_line
			(start -0.254 -0.508)
			(end -0.254 0.508)
			(stroke
				(width 0.0254)
				(type default)
			)
			(layer "B.Fab")
		)
		(fp_line
			(start 0.254 0.508)
			(end 0.254 -0.508)
			(stroke
				(width 0.0254)
				(type default)
			)
			(layer "B.Fab")
		)
		(fp_line
			(start -0.254 0.508)
			(end 0.254 0.508)
			(stroke
				(width 0.0254)
				(type default)
			)
			(layer "B.Fab")
		)
		(pad "1" smd rect
			(at 0 -0.4191 270)
			(size 0.508 0.5334)
			(layers "B.Cu" "B.Mask" "B.Paste")
			(net "VDD_3.3V")
		)
		(pad "2" smd rect
			(at 0 0.4191 270)
			(size 0.508 0.5334)
			(layers "B.Cu" "B.Mask" "B.Paste")
			(net "PGRM_JTAG_TDO")
		)
		(zone
			(layer "B.Cu")
			(hatch none 0.5)
			(connect_pads
				(clearance 0)
			)
			(min_thickness 0.25)
			(keepout
				(tracks not_allowed)
				(vias allowed)
				(pads allowed)
				(copperpour not_allowed)
				(footprints allowed)
			)
			(placement
				(enabled no)
				(sheetname "")
			)
			(fill
				(thermal_gap 0.5)
				(thermal_bridge_width 0.5)
				(island_removal_mode 0)
			)
			(polygon
				(pts
					(xy 26.2636 9.5504) (xy 26.3144 9.5504) (xy 26.3144 9.4996) (xy 26.2636 9.4996)
				)
			)
		)
	)
	(footprint ""
		(layer "B.Cu")
		(at 81.850992 7.498994)
		(property "Reference" "V1_A-BA1"
			(at 0 0 0)
			(layer "B.SilkS")
			(hide yes)
			(effects
				(font
					(size 1.27 1.27)
				)
				(justify mirror)
			)
		)
		(property "Value" ""
			(at 0 0 0)
			(layer "B.Fab")
			(effects
				(font
					(size 1.27 1.27)
				)
				(justify mirror)
			)
		)
		(duplicate_pad_numbers_are_jumpers no)
		(pad "1" thru_hole circle
			(at 0 0 180)
			(size 0.4572 0.4572)
			(drill 0.20574)
			(layers "*.Cu" "*.Mask")
			(remove_unused_layers no)
			(net "DDR0_32A_BA1")
			(clearance 0.1143)
			(thermal_gap 0.1143)
		)
	)
	(footprint ""
		(layer "B.Cu")
		(at 82.55 40.132 90)
		(property "Reference" "R331"
			(at 0.98933 0 0)
			(unlocked yes)
			(layer "B.SilkS")
			(effects
				(font
					(size 0.7874 0.5842)
					(thickness 0.127)
				)
				(justify left mirror)
			)
		)
		(property "Value" "0"
			(at 0.148158 1.7526 0)
			(unlocked yes)
			(layer "B.Fab")
			(hide yes)
			(effects
				(font
					(size 1.27 0.9652)
					(thickness 0.000001)
				)
				(justify left mirror)
			)
		)
		(property "Device Type" "REST1010"
			(at 0.148158 1.7526 0)
			(unlocked yes)
			(layer "B.Fab")
			(hide yes)
			(effects
				(font
					(size 1.27 0.9652)
					(thickness 0.000001)
				)
				(justify left mirror)
			)
		)
		(duplicate_pad_numbers_are_jumpers no)
		(fp_circle
			(center 0 0)
			(end 0 0.127)
			(stroke
				(width 0.2032)
				(type default)
			)
			(fill no)
			(layer "B.SilkS")
		)
		(fp_poly
			(pts
				(xy -0.7874 -1.6637) (xy 0.7874 -1.6637) (xy 0.7874 1.6637) (xy -0.7874 1.6637)
			)
			(stroke
				(width 0)
				(type default)
			)
			(fill no)
			(layer "B.CrtYd")
		)
		(fp_line
			(start 0.4064 -0.8128)
			(end -0.4064 -0.8128)
			(stroke
				(width 0.0254)
				(type default)
			)
			(layer "B.Fab")
		)
		(fp_line
			(start -0.4064 -0.8128)
			(end -0.4064 0.8128)
			(stroke
				(width 0.0254)
				(type default)
			)
			(layer "B.Fab")
		)
		(fp_line
			(start 0.4064 0.8128)
			(end 0.4064 -0.8128)
			(stroke
				(width 0.0254)
				(type default)
			)
			(layer "B.Fab")
		)
		(fp_line
			(start -0.4064 0.8128)
			(end 0.4064 0.8128)
			(stroke
				(width 0.0254)
				(type default)
			)
			(layer "B.Fab")
		)
		(pad "1" smd rect
			(at 0 -0.8001 270)
			(size 0.762 0.9652)
			(layers "B.Cu" "B.Mask" "B.Paste")
			(net "VDD_5.0V")
		)
		(pad "2" smd rect
			(at 0 0.8001 270)
			(size 0.762 0.9652)
			(layers "B.Cu" "B.Mask" "B.Paste")
			(net "11N2159")
		)
		(zone
			(layer "B.Cu")
			(hatch none 0.5)
			(connect_pads
				(clearance 0)
			)
			(min_thickness 0.25)
			(keepout
				(tracks not_allowed)
				(vias allowed)
				(pads allowed)
				(copperpour not_allowed)
				(footprints allowed)
			)
			(placement
				(enabled no)
				(sheetname "")
			)
			(fill
				(thermal_gap 0.5)
				(thermal_bridge_width 0.5)
				(island_removal_mode 0)
			)
			(polygon
				(pts
					(xy 82.296 40.0685) (xy 82.296 40.1955) (xy 82.804 40.1955) (xy 82.804 40.0685)
				)
			)
		)
	)
	(footprint ""
		(layer "B.Cu")
		(at 20.32 2.667 180)
		(property "Reference" "R399"
			(at 0.28067 1.016 270)
			(unlocked yes)
			(layer "B.SilkS")
			(effects
				(font
					(size 0.7874 0.5842)
					(thickness 0.127)
				)
				(justify left mirror)
			)
		)
		(property "Value" "4.75K"
			(at 0.148158 1.3462 90)
			(unlocked yes)
			(layer "B.Fab")
			(hide yes)
			(effects
				(font
					(size 1.27 0.9652)
					(thickness 0.000001)
				)
				(justify left mirror)
			)
		)
		(property "Device Type" "REST4024"
			(at 0.148158 1.3462 90)
			(unlocked yes)
			(layer "B.Fab")
			(hide yes)
			(effects
				(font
					(size 1.27 0.9652)
					(thickness 0.000001)
				)
				(justify left mirror)
			)
		)
		(duplicate_pad_numbers_are_jumpers no)
		(fp_poly
			(pts
				(xy -0.635 1.0668) (xy -0.635 -1.0668) (xy 0.635 -1.0668) (xy 0.635 1.0668)
			)
			(stroke
				(width 0)
				(type default)
			)
			(fill no)
			(layer "B.CrtYd")
		)
		(fp_line
			(start 0.254 0.508)
			(end 0.254 -0.508)
			(stroke
				(width 0.0254)
				(type default)
			)
			(layer "B.Fab")
		)
		(fp_line
			(start 0.254 -0.508)
			(end -0.254 -0.508)
			(stroke
				(width 0.0254)
				(type default)
			)
			(layer "B.Fab")
		)
		(fp_line
			(start -0.254 0.508)
			(end 0.254 0.508)
			(stroke
				(width 0.0254)
				(type default)
			)
			(layer "B.Fab")
		)
		(fp_line
			(start -0.254 -0.508)
			(end -0.254 0.508)
			(stroke
				(width 0.0254)
				(type default)
			)
			(layer "B.Fab")
		)
		(pad "1" smd rect
			(at 0 -0.4191)
			(size 0.508 0.5334)
			(layers "B.Cu" "B.Mask" "B.Paste")
			(net "EXT_3.3V")
		)
		(pad "2" smd rect
			(at 0 0.4191)
			(size 0.508 0.5334)
			(layers "B.Cu" "B.Mask" "B.Paste")
			(net "CPLD_SMBUS_SCL")
		)
		(zone
			(layer "B.Cu")
			(hatch none 0.5)
			(connect_pads
				(clearance 0)
			)
			(min_thickness 0.25)
			(keepout
				(tracks not_allowed)
				(vias allowed)
				(pads allowed)
				(copperpour not_allowed)
				(footprints allowed)
			)
			(placement
				(enabled no)
				(sheetname "")
			)
			(fill
				(thermal_gap 0.5)
				(thermal_bridge_width 0.5)
				(island_removal_mode 0)
			)
			(polygon
				(pts
					(xy 20.3454 2.6924) (xy 20.3454 2.6416) (xy 20.2946 2.6416) (xy 20.2946 2.6924)
				)
			)
		)
	)
	(footprint ""
		(layer "B.Cu")
		(at 78.650998 25.813004)
		(property "Reference" "V3_A-RAS"
			(at 0 0 0)
			(layer "B.SilkS")
			(hide yes)
			(effects
				(font
					(size 1.27 1.27)
				)
				(justify mirror)
			)
		)
		(property "Value" ""
			(at 0 0 0)
			(layer "B.Fab")
			(effects
				(font
					(size 1.27 1.27)
				)
				(justify mirror)
			)
		)
		(duplicate_pad_numbers_are_jumpers no)
		(pad "1" thru_hole circle
			(at 0 0 180)
			(size 0.4572 0.4572)
			(drill 0.20574)
			(layers "*.Cu" "*.Mask")
			(remove_unused_layers no)
			(net "DDR0_32A_RAS_L")
			(clearance 0.1143)
			(thermal_gap 0.1143)
		)
	)
	(footprint ""
		(layer "B.Cu")
		(at 44.73702 19.041999 -90)
		(property "Reference" "R321"
			(at 0 0 90)
			(layer "B.SilkS")
			(hide yes)
			(effects
				(font
					(size 1.27 1.27)
				)
				(justify mirror)
			)
		)
		(property "Value" ""
			(at 0 0 90)
			(layer "B.Fab")
			(effects
				(font
					(size 1.27 1.27)
				)
				(justify mirror)
			)
		)
		(duplicate_pad_numbers_are_jumpers no)
		(fp_circle
			(center 0 0)
			(end 0 -0.104648)
			(stroke
				(width 0.1016)
				(type default)
			)
			(fill no)
			(layer "B.SilkS")
		)
		(fp_poly
			(pts
				(xy 0.381 -0.889) (xy 0.381 0.889) (xy -0.381 0.889) (xy -0.381 -0.889)
			)
			(stroke
				(width 0)
				(type default)
			)
			(fill no)
			(layer "B.CrtYd")
		)
		(fp_line
			(start -0.508 1.016)
			(end 0.508 1.016)
			(stroke
				(width 0.0254)
				(type default)
			)
			(layer "B.Fab")
		)
		(fp_line
			(start 0.508 1.016)
			(end 0.508 -1.016)
			(stroke
				(width 0.0254)
				(type default)
			)
			(layer "B.Fab")
		)
		(fp_line
			(start -0.508 -1.016)
			(end -0.508 1.016)
			(stroke
				(width 0.0254)
				(type default)
			)
			(layer "B.Fab")
		)
		(fp_line
			(start 0.254 -1.016)
			(end -0.508 -1.016)
			(stroke
				(width 0.0254)
				(type default)
			)
			(layer "B.Fab")
		)
		(fp_line
			(start 0.508 -1.016)
			(end 0.254 -1.016)
			(stroke
				(width 0.0254)
				(type default)
			)
			(layer "B.Fab")
		)
		(pad "1" smd custom
			(at 0 -0.500126 90)
			(size 0.127 0.127)
			(layers "B.Cu" "B.Mask" "B.Paste")
			(net "GND")
			(options
				(clearance outline)
				(anchor circle)
			)
			(primitives
				(gr_poly
					(pts
						(xy -0.1778 0.254) (xy 0.1778 0.254) (xy 0.254 0.1778) (xy 0.254 -0.1778) (xy 0.1778 -0.254) (xy -0.1778 -0.254)
						(xy -0.254 -0.1778) (xy -0.254 0.1778)
					)
					(width 0)
					(fill yes)
				)
			)
		)
		(pad "2" smd custom
			(at 0 0.500126 90)
			(size 0.127 0.127)
			(layers "B.Cu" "B.Mask" "B.Paste")
			(net "NFP_CLK_REF_N")
			(options
				(clearance outline)
				(anchor circle)
			)
			(primitives
				(gr_poly
					(pts
						(xy -0.1778 0.254) (xy 0.1778 0.254) (xy 0.254 0.1778) (xy 0.254 -0.1778) (xy 0.1778 -0.254) (xy -0.1778 -0.254)
						(xy -0.254 -0.1778) (xy -0.254 0.1778)
					)
					(width 0)
					(fill yes)
				)
			)
		)
	)
	(footprint ""
		(layer "B.Cu")
		(at 48.26 0.762 180)
		(property "Reference" "C152"
			(at 0.145212 0.8763 270)
			(unlocked yes)
			(layer "B.SilkS")
			(effects
				(font
					(size 0.7874 0.5842)
					(thickness 0.127)
				)
				(justify left mirror)
			)
		)
		(property "Value" "0.22UF"
			(at 0.091846 0.2921 90)
			(unlocked yes)
			(layer "B.Fab")
			(hide yes)
			(effects
				(font
					(size 0.7874 0.5842)
					(thickness 0.2032)
				)
				(justify left mirror)
			)
		)
		(property "Device Type" "CAPC0062"
			(at 0.091846 0.2921 90)
			(unlocked yes)
			(layer "B.Fab")
			(hide yes)
			(effects
				(font
					(size 0.7874 0.5842)
					(thickness 0.2032)
				)
				(justify left mirror)
			)
		)
		(duplicate_pad_numbers_are_jumpers no)
		(fp_poly
			(pts
				(xy -0.635 1.0668) (xy -0.635 -1.0668) (xy 0.635 -1.0668) (xy 0.635 1.0668)
			)
			(stroke
				(width 0)
				(type default)
			)
			(fill no)
			(layer "B.CrtYd")
		)
		(fp_line
			(start 0.254 0.508)
			(end 0.254 -0.508)
			(stroke
				(width 0.0254)
				(type default)
			)
			(layer "B.Fab")
		)
		(fp_line
			(start 0.254 -0.508)
			(end -0.254 -0.508)
			(stroke
				(width 0.0254)
				(type default)
			)
			(layer "B.Fab")
		)
		(fp_line
			(start -0.254 0.508)
			(end 0.254 0.508)
			(stroke
				(width 0.0254)
				(type default)
			)
			(layer "B.Fab")
		)
		(fp_line
			(start -0.254 -0.508)
			(end -0.254 0.508)
			(stroke
				(width 0.0254)
				(type default)
			)
			(layer "B.Fab")
		)
		(pad "1" smd rect
			(at 0 -0.4191)
			(size 0.508 0.5334)
			(layers "B.Cu" "B.Mask" "B.Paste")
			(net "_NFP_PCIE0_PER7_N")
		)
		(pad "2" smd rect
			(at 0 0.4191)
			(size 0.508 0.5334)
			(layers "B.Cu" "B.Mask" "B.Paste")
			(net "NFP_PCIE0_PER7_N")
		)
		(zone
			(layer "B.Cu")
			(hatch none 0.5)
			(connect_pads
				(clearance 0)
			)
			(min_thickness 0.25)
			(keepout
				(tracks not_allowed)
				(vias allowed)
				(pads allowed)
				(copperpour not_allowed)
				(footprints allowed)
			)
			(placement
				(enabled no)
				(sheetname "")
			)
			(fill
				(thermal_gap 0.5)
				(thermal_bridge_width 0.5)
				(island_removal_mode 0)
			)
			(polygon
				(pts
					(xy 48.2854 0.7874) (xy 48.2854 0.7366) (xy 48.2346 0.7366) (xy 48.2346 0.7874)
				)
			)
		)
	)
	(footprint ""
		(layer "B.Cu")
		(at 83.450989 19.055994)
		(property "Reference" "V2_A-A06"
			(at 0 0 0)
			(layer "B.SilkS")
			(hide yes)
			(effects
				(font
					(size 1.27 1.27)
				)
				(justify mirror)
			)
		)
		(property "Value" ""
			(at 0 0 0)
			(layer "B.Fab")
			(effects
				(font
					(size 1.27 1.27)
				)
				(justify mirror)
			)
		)
		(duplicate_pad_numbers_are_jumpers no)
		(pad "1" thru_hole circle
			(at 0 0 180)
			(size 0.4572 0.4572)
			(drill 0.20574)
			(layers "*.Cu" "*.Mask")
			(remove_unused_layers no)
			(net "DDR0_32A_A6")
			(clearance 0.1143)
			(thermal_gap 0.1143)
		)
	)
	(footprint ""
		(layer "B.Cu")
		(at 45.737018 12.042013 90)
		(property "Reference" "R285"
			(at 0 0 90)
			(layer "B.SilkS")
			(hide yes)
			(effects
				(font
					(size 1.27 1.27)
				)
				(justify mirror)
			)
		)
		(property "Value" ""
			(at 0 0 90)
			(layer "B.Fab")
			(effects
				(font
					(size 1.27 1.27)
				)
				(justify mirror)
			)
		)
		(duplicate_pad_numbers_are_jumpers no)
		(fp_circle
			(center 0 0)
			(end 0 0.104648)
			(stroke
				(width 0.1016)
				(type default)
			)
			(fill no)
			(layer "B.SilkS")
		)
		(fp_poly
			(pts
				(xy 0.381 -0.889) (xy 0.381 0.889) (xy -0.381 0.889) (xy -0.381 -0.889)
			)
			(stroke
				(width 0)
				(type default)
			)
			(fill no)
			(layer "B.CrtYd")
		)
		(fp_line
			(start 0.508 -1.016)
			(end 0.254 -1.016)
			(stroke
				(width 0.0254)
				(type default)
			)
			(layer "B.Fab")
		)
		(fp_line
			(start 0.254 -1.016)
			(end -0.508 -1.016)
			(stroke
				(width 0.0254)
				(type default)
			)
			(layer "B.Fab")
		)
		(fp_line
			(start -0.508 -1.016)
			(end -0.508 1.016)
			(stroke
				(width 0.0254)
				(type default)
			)
			(layer "B.Fab")
		)
		(fp_line
			(start 0.508 1.016)
			(end 0.508 -1.016)
			(stroke
				(width 0.0254)
				(type default)
			)
			(layer "B.Fab")
		)
		(fp_line
			(start -0.508 1.016)
			(end 0.508 1.016)
			(stroke
				(width 0.0254)
				(type default)
			)
			(layer "B.Fab")
		)
		(pad "1" smd custom
			(at 0 -0.500126 270)
			(size 0.127 0.127)
			(layers "B.Cu" "B.Mask" "B.Paste")
			(net "GND")
			(options
				(clearance outline)
				(anchor circle)
			)
			(primitives
				(gr_poly
					(pts
						(xy -0.1778 0.254) (xy 0.1778 0.254) (xy 0.254 0.1778) (xy 0.254 -0.1778) (xy 0.1778 -0.254) (xy -0.1778 -0.254)
						(xy -0.254 -0.1778) (xy -0.254 0.1778)
					)
					(width 0)
					(fill yes)
				)
			)
		)
		(pad "2" smd custom
			(at 0 0.500126 270)
			(size 0.127 0.127)
			(layers "B.Cu" "B.Mask" "B.Paste")
			(net "NFP_VDD_CORE_SENSE_VSS")
			(options
				(clearance outline)
				(anchor circle)
			)
			(primitives
				(gr_poly
					(pts
						(xy -0.1778 0.254) (xy 0.1778 0.254) (xy 0.254 0.1778) (xy 0.254 -0.1778) (xy 0.1778 -0.254) (xy -0.1778 -0.254)
						(xy -0.254 -0.1778) (xy -0.254 0.1778)
					)
					(width 0)
					(fill yes)
				)
			)
		)
	)
	(footprint ""
		(layer "B.Cu")
		(at 73.05101 17.455998)
		(property "Reference" "V_A-DQS3-N"
			(at 0 0 0)
			(layer "B.SilkS")
			(hide yes)
			(effects
				(font
					(size 1.27 1.27)
				)
				(justify mirror)
			)
		)
		(property "Value" ""
			(at 0 0 0)
			(layer "B.Fab")
			(effects
				(font
					(size 1.27 1.27)
				)
				(justify mirror)
			)
		)
		(duplicate_pad_numbers_are_jumpers no)
		(pad "1" thru_hole circle
			(at 0 0 180)
			(size 0.4572 0.4572)
			(drill 0.20574)
			(layers "*.Cu" "*.Mask")
			(remove_unused_layers no)
			(net "DDR0_32A_DQS3_N")
			(clearance 0.1143)
			(thermal_gap 0.1143)
		)
	)
	(footprint ""
		(layer "B.Cu")
		(at 40.894 48.641)
		(property "Reference" "TP4"
			(at 3.302 0.53467 0)
			(unlocked yes)
			(layer "B.SilkS")
			(effects
				(font
					(size 0.7874 0.5842)
					(thickness 0.127)
				)
				(justify left mirror)
			)
		)
		(property "Value" "*"
			(at 0.4826 -0.14732 0)
			(unlocked yes)
			(layer "B.Fab")
			(hide yes)
			(effects
				(font
					(size 1.27 0.9652)
					(thickness 0.000001)
				)
				(justify left mirror)
			)
		)
		(property "Device Type" "TP_SMALL"
			(at 0.4826 -0.14732 0)
			(unlocked yes)
			(layer "B.Fab")
			(hide yes)
			(effects
				(font
					(size 1.27 0.9652)
					(thickness 0.000001)
				)
				(justify left mirror)
			)
		)
		(duplicate_pad_numbers_are_jumpers no)
		(fp_line
			(start -0.8636 -0.8636)
			(end 0.8636 -0.8636)
			(stroke
				(width 0.1524)
				(type default)
			)
			(layer "B.SilkS")
		)
		(fp_line
			(start -0.8636 0.8636)
			(end -0.8636 -0.8636)
			(stroke
				(width 0.1524)
				(type default)
			)
			(layer "B.SilkS")
		)
		(fp_line
			(start 0.8636 -0.8636)
			(end 0.8636 0.8636)
			(stroke
				(width 0.1524)
				(type default)
			)
			(layer "B.SilkS")
		)
		(fp_line
			(start 0.8636 0.8636)
			(end -0.8636 0.8636)
			(stroke
				(width 0.1524)
				(type default)
			)
			(layer "B.SilkS")
		)
		(fp_poly
			(pts
				(xy 0.635 -0.635) (xy 0.635 0.635) (xy -0.635 0.635) (xy -0.635 -0.635)
			)
			(stroke
				(width 0)
				(type default)
			)
			(fill no)
			(layer "B.CrtYd")
		)
		(pad "1" smd rect
			(at 0 0 180)
			(size 1.27 1.27)
			(layers "B.Cu" "B.Mask" "B.Paste")
			(net "CNTRL_SPI_CS")
		)
	)
	(footprint ""
		(layer "B.Cu")
		(at 60.736988 13.042011 -90)
		(property "Reference" "C186"
			(at 0 0 90)
			(layer "B.SilkS")
			(hide yes)
			(effects
				(font
					(size 1.27 1.27)
				)
				(justify mirror)
			)
		)
		(property "Value" ""
			(at 0 0 90)
			(layer "B.Fab")
			(effects
				(font
					(size 1.27 1.27)
				)
				(justify mirror)
			)
		)
		(duplicate_pad_numbers_are_jumpers no)
		(fp_circle
			(center 0 0)
			(end 0 -0.104648)
			(stroke
				(width 0.1016)
				(type default)
			)
			(fill no)
			(layer "B.SilkS")
		)
		(fp_poly
			(pts
				(xy 0.381 -0.889) (xy 0.381 0.889) (xy -0.381 0.889) (xy -0.381 -0.889)
			)
			(stroke
				(width 0)
				(type default)
			)
			(fill no)
			(layer "B.CrtYd")
		)
		(fp_line
			(start -0.508 1.016)
			(end 0.508 1.016)
			(stroke
				(width 0.0254)
				(type default)
			)
			(layer "B.Fab")
		)
		(fp_line
			(start 0.508 1.016)
			(end 0.508 -1.016)
			(stroke
				(width 0.0254)
				(type default)
			)
			(layer "B.Fab")
		)
		(fp_line
			(start -0.508 -1.016)
			(end -0.508 1.016)
			(stroke
				(width 0.0254)
				(type default)
			)
			(layer "B.Fab")
		)
		(fp_line
			(start 0.254 -1.016)
			(end -0.508 -1.016)
			(stroke
				(width 0.0254)
				(type default)
			)
			(layer "B.Fab")
		)
		(fp_line
			(start 0.508 -1.016)
			(end 0.254 -1.016)
			(stroke
				(width 0.0254)
				(type default)
			)
			(layer "B.Fab")
		)
		(pad "1" smd custom
			(at 0 -0.500126 90)
			(size 0.127 0.127)
			(layers "B.Cu" "B.Mask" "B.Paste")
			(net "VDDA_DDR0_32A")
			(options
				(clearance outline)
				(anchor circle)
			)
			(primitives
				(gr_poly
					(pts
						(xy -0.1778 0.254) (xy 0.1778 0.254) (xy 0.254 0.1778) (xy 0.254 -0.1778) (xy 0.1778 -0.254) (xy -0.1778 -0.254)
						(xy -0.254 -0.1778) (xy -0.254 0.1778)
					)
					(width 0)
					(fill yes)
				)
			)
		)
		(pad "2" smd custom
			(at 0 0.500126 90)
			(size 0.127 0.127)
			(layers "B.Cu" "B.Mask" "B.Paste")
			(net "GND")
			(options
				(clearance outline)
				(anchor circle)
			)
			(primitives
				(gr_poly
					(pts
						(xy -0.1778 0.254) (xy 0.1778 0.254) (xy 0.254 0.1778) (xy 0.254 -0.1778) (xy 0.1778 -0.254) (xy -0.1778 -0.254)
						(xy -0.254 -0.1778) (xy -0.254 0.1778)
					)
					(width 0)
					(fill yes)
				)
			)
		)
	)
	(footprint ""
		(layer "B.Cu")
		(at 78.74 43.688)
		(property "Reference" "C136"
			(at 0.22733 4.445 270)
			(unlocked yes)
			(layer "B.SilkS")
			(effects
				(font
					(size 0.7874 0.5842)
					(thickness 0.127)
				)
				(justify left mirror)
			)
		)
		(property "Value" "10UF"
			(at 0.148158 1.7526 270)
			(unlocked yes)
			(layer "B.Fab")
			(hide yes)
			(effects
				(font
					(size 1.27 0.9652)
					(thickness 0.000001)
				)
				(justify left mirror)
			)
		)
		(property "Device Type" "CAPC0058"
			(at 0.148158 1.7526 270)
			(unlocked yes)
			(layer "B.Fab")
			(hide yes)
			(effects
				(font
					(size 1.27 0.9652)
					(thickness 0.000001)
				)
				(justify left mirror)
			)
		)
		(duplicate_pad_numbers_are_jumpers no)
		(fp_circle
			(center 0 0)
			(end 0.127 0)
			(stroke
				(width 0.2032)
				(type default)
			)
			(fill no)
			(layer "B.SilkS")
		)
		(fp_poly
			(pts
				(xy -0.7874 -1.6637) (xy 0.7874 -1.6637) (xy 0.7874 1.6637) (xy -0.7874 1.6637)
			)
			(stroke
				(width 0)
				(type default)
			)
			(fill no)
			(layer "B.CrtYd")
		)
		(fp_line
			(start -0.4064 -0.7874)
			(end -0.4064 0.8128)
			(stroke
				(width 0.0254)
				(type default)
			)
			(layer "B.Fab")
		)
		(fp_line
			(start -0.4064 0.8128)
			(end 0.4064 0.8128)
			(stroke
				(width 0.0254)
				(type default)
			)
			(layer "B.Fab")
		)
		(fp_line
			(start 0.4064 -0.7874)
			(end -0.4064 -0.7874)
			(stroke
				(width 0.0254)
				(type default)
			)
			(layer "B.Fab")
		)
		(fp_line
			(start 0.4064 0.8128)
			(end 0.4064 -0.7874)
			(stroke
				(width 0.0254)
				(type default)
			)
			(layer "B.Fab")
		)
		(pad "1" smd rect
			(at 0 -0.8001 180)
			(size 0.8636 0.9652)
			(layers "B.Cu" "B.Mask" "B.Paste")
			(net "DDR_VTT")
		)
		(pad "2" smd rect
			(at 0 0.8001 180)
			(size 0.8636 0.9652)
			(layers "B.Cu" "B.Mask" "B.Paste")
			(net "GND")
		)
		(zone
			(layer "B.Cu")
			(hatch none 0.5)
			(connect_pads
				(clearance 0)
			)
			(min_thickness 0.25)
			(keepout
				(tracks not_allowed)
				(vias allowed)
				(pads allowed)
				(copperpour not_allowed)
				(footprints allowed)
			)
			(placement
				(enabled no)
				(sheetname "")
			)
			(fill
				(thermal_gap 0.5)
				(thermal_bridge_width 0.5)
				(island_removal_mode 0)
			)
			(polygon
				(pts
					(xy 78.8035 43.434) (xy 78.6765 43.434) (xy 78.6765 43.942) (xy 78.8035 43.942)
				)
			)
		)
	)
	(footprint ""
		(layer "B.Cu")
		(at 53.237003 11.542014)
		(property "Reference" "C28"
			(at 0.076327 2.300986 270)
			(unlocked yes)
			(layer "B.SilkS")
			(effects
				(font
					(size 0.7874 0.5842)
					(thickness 0.127)
				)
				(justify mirror)
			)
		)
		(property "Value" ""
			(at 0 0 0)
			(layer "B.Fab")
			(effects
				(font
					(size 1.27 1.27)
				)
				(justify mirror)
			)
		)
		(duplicate_pad_numbers_are_jumpers no)
		(fp_circle
			(center 0 0)
			(end 0.104648 0)
			(stroke
				(width 0.1016)
				(type default)
			)
			(fill no)
			(layer "B.SilkS")
		)
		(fp_poly
			(pts
				(xy 0.381 -0.889) (xy 0.381 0.889) (xy -0.381 0.889) (xy -0.381 -0.889)
			)
			(stroke
				(width 0)
				(type default)
			)
			(fill no)
			(layer "B.CrtYd")
		)
		(fp_line
			(start -0.508 -1.016)
			(end -0.508 1.016)
			(stroke
				(width 0.0254)
				(type default)
			)
			(layer "B.Fab")
		)
		(fp_line
			(start -0.508 1.016)
			(end 0.508 1.016)
			(stroke
				(width 0.0254)
				(type default)
			)
			(layer "B.Fab")
		)
		(fp_line
			(start 0.254 -1.016)
			(end -0.508 -1.016)
			(stroke
				(width 0.0254)
				(type default)
			)
			(layer "B.Fab")
		)
		(fp_line
			(start 0.508 -1.016)
			(end 0.254 -1.016)
			(stroke
				(width 0.0254)
				(type default)
			)
			(layer "B.Fab")
		)
		(fp_line
			(start 0.508 1.016)
			(end 0.508 -1.016)
			(stroke
				(width 0.0254)
				(type default)
			)
			(layer "B.Fab")
		)
		(pad "1" smd custom
			(at 0 -0.500126 180)
			(size 0.127 0.127)
			(layers "B.Cu" "B.Mask" "B.Paste")
			(net "VDDA_PLL")
			(options
				(clearance outline)
				(anchor circle)
			)
			(primitives
				(gr_poly
					(pts
						(xy -0.1778 0.254) (xy 0.1778 0.254) (xy 0.254 0.1778) (xy 0.254 -0.1778) (xy 0.1778 -0.254) (xy -0.1778 -0.254)
						(xy -0.254 -0.1778) (xy -0.254 0.1778)
					)
					(width 0)
					(fill yes)
				)
			)
		)
		(pad "2" smd custom
			(at 0 0.500126 180)
			(size 0.127 0.127)
			(layers "B.Cu" "B.Mask" "B.Paste")
			(net "GND")
			(options
				(clearance outline)
				(anchor circle)
			)
			(primitives
				(gr_poly
					(pts
						(xy -0.1778 0.254) (xy 0.1778 0.254) (xy 0.254 0.1778) (xy 0.254 -0.1778) (xy 0.1778 -0.254) (xy -0.1778 -0.254)
						(xy -0.254 -0.1778) (xy -0.254 0.1778)
					)
					(width 0)
					(fill yes)
				)
			)
		)
	)
	(footprint ""
		(layer "B.Cu")
		(at 77.051002 30.612994)
		(property "Reference" "V_A-CB3"
			(at 0 0 0)
			(layer "B.SilkS")
			(hide yes)
			(effects
				(font
					(size 1.27 1.27)
				)
				(justify mirror)
			)
		)
		(property "Value" ""
			(at 0 0 0)
			(layer "B.Fab")
			(effects
				(font
					(size 1.27 1.27)
				)
				(justify mirror)
			)
		)
		(duplicate_pad_numbers_are_jumpers no)
		(pad "1" thru_hole circle
			(at 0 0 180)
			(size 0.4572 0.4572)
			(drill 0.20574)
			(layers "*.Cu" "*.Mask")
			(remove_unused_layers no)
			(net "DDR0_32A_CB3")
			(clearance 0.1143)
			(thermal_gap 0.1143)
		)
	)
	(footprint ""
		(layer "B.Cu")
		(at 47.237015 10.542016)
		(property "Reference" "C92"
			(at 0 0 0)
			(layer "B.SilkS")
			(hide yes)
			(effects
				(font
					(size 1.27 1.27)
				)
				(justify mirror)
			)
		)
		(property "Value" ""
			(at 0 0 0)
			(layer "B.Fab")
			(effects
				(font
					(size 1.27 1.27)
				)
				(justify mirror)
			)
		)
		(duplicate_pad_numbers_are_jumpers no)
		(fp_circle
			(center 0 0)
			(end 0.104648 0)
			(stroke
				(width 0.1016)
				(type default)
			)
			(fill no)
			(layer "B.SilkS")
		)
		(fp_poly
			(pts
				(xy 0.381 -0.889) (xy 0.381 0.889) (xy -0.381 0.889) (xy -0.381 -0.889)
			)
			(stroke
				(width 0)
				(type default)
			)
			(fill no)
			(layer "B.CrtYd")
		)
		(fp_line
			(start -0.508 -1.016)
			(end -0.508 1.016)
			(stroke
				(width 0.0254)
				(type default)
			)
			(layer "B.Fab")
		)
		(fp_line
			(start -0.508 1.016)
			(end 0.508 1.016)
			(stroke
				(width 0.0254)
				(type default)
			)
			(layer "B.Fab")
		)
		(fp_line
			(start 0.254 -1.016)
			(end -0.508 -1.016)
			(stroke
				(width 0.0254)
				(type default)
			)
			(layer "B.Fab")
		)
		(fp_line
			(start 0.508 -1.016)
			(end 0.254 -1.016)
			(stroke
				(width 0.0254)
				(type default)
			)
			(layer "B.Fab")
		)
		(fp_line
			(start 0.508 1.016)
			(end 0.508 -1.016)
			(stroke
				(width 0.0254)
				(type default)
			)
			(layer "B.Fab")
		)
		(pad "1" smd custom
			(at 0 -0.500126 180)
			(size 0.127 0.127)
			(layers "B.Cu" "B.Mask" "B.Paste")
			(net "VDDA_SERDES")
			(options
				(clearance outline)
				(anchor circle)
			)
			(primitives
				(gr_poly
					(pts
						(xy -0.1778 0.254) (xy 0.1778 0.254) (xy 0.254 0.1778) (xy 0.254 -0.1778) (xy 0.1778 -0.254) (xy -0.1778 -0.254)
						(xy -0.254 -0.1778) (xy -0.254 0.1778)
					)
					(width 0)
					(fill yes)
				)
			)
		)
		(pad "2" smd custom
			(at 0 0.500126 180)
			(size 0.127 0.127)
			(layers "B.Cu" "B.Mask" "B.Paste")
			(net "GND")
			(options
				(clearance outline)
				(anchor circle)
			)
			(primitives
				(gr_poly
					(pts
						(xy -0.1778 0.254) (xy 0.1778 0.254) (xy 0.254 0.1778) (xy 0.254 -0.1778) (xy 0.1778 -0.254) (xy -0.1778 -0.254)
						(xy -0.254 -0.1778) (xy -0.254 0.1778)
					)
					(width 0)
					(fill yes)
				)
			)
		)
	)
	(footprint ""
		(layer "B.Cu")
		(at 62.736984 13.042011 -90)
		(property "Reference" "R188"
			(at 0 0 90)
			(layer "B.SilkS")
			(hide yes)
			(effects
				(font
					(size 1.27 1.27)
				)
				(justify mirror)
			)
		)
		(property "Value" ""
			(at 0 0 90)
			(layer "B.Fab")
			(effects
				(font
					(size 1.27 1.27)
				)
				(justify mirror)
			)
		)
		(duplicate_pad_numbers_are_jumpers no)
		(fp_circle
			(center 0 0)
			(end 0 -0.104648)
			(stroke
				(width 0.1016)
				(type default)
			)
			(fill no)
			(layer "B.SilkS")
		)
		(fp_poly
			(pts
				(xy 0.381 -0.889) (xy 0.381 0.889) (xy -0.381 0.889) (xy -0.381 -0.889)
			)
			(stroke
				(width 0)
				(type default)
			)
			(fill no)
			(layer "B.CrtYd")
		)
		(fp_line
			(start -0.508 1.016)
			(end 0.508 1.016)
			(stroke
				(width 0.0254)
				(type default)
			)
			(layer "B.Fab")
		)
		(fp_line
			(start 0.508 1.016)
			(end 0.508 -1.016)
			(stroke
				(width 0.0254)
				(type default)
			)
			(layer "B.Fab")
		)
		(fp_line
			(start -0.508 -1.016)
			(end -0.508 1.016)
			(stroke
				(width 0.0254)
				(type default)
			)
			(layer "B.Fab")
		)
		(fp_line
			(start 0.254 -1.016)
			(end -0.508 -1.016)
			(stroke
				(width 0.0254)
				(type default)
			)
			(layer "B.Fab")
		)
		(fp_line
			(start 0.508 -1.016)
			(end 0.254 -1.016)
			(stroke
				(width 0.0254)
				(type default)
			)
			(layer "B.Fab")
		)
		(pad "1" smd custom
			(at 0 -0.500126 90)
			(size 0.127 0.127)
			(layers "B.Cu" "B.Mask" "B.Paste")
			(net "GND")
			(options
				(clearance outline)
				(anchor circle)
			)
			(primitives
				(gr_poly
					(pts
						(xy -0.1778 0.254) (xy 0.1778 0.254) (xy 0.254 0.1778) (xy 0.254 -0.1778) (xy 0.1778 -0.254) (xy -0.1778 -0.254)
						(xy -0.254 -0.1778) (xy -0.254 0.1778)
					)
					(width 0)
					(fill yes)
				)
			)
		)
		(pad "2" smd custom
			(at 0 0.500126 90)
			(size 0.127 0.127)
			(layers "B.Cu" "B.Mask" "B.Paste")
			(net "A_AZQ")
			(options
				(clearance outline)
				(anchor circle)
			)
			(primitives
				(gr_poly
					(pts
						(xy -0.1778 0.254) (xy 0.1778 0.254) (xy 0.254 0.1778) (xy 0.254 -0.1778) (xy 0.1778 -0.254) (xy -0.1778 -0.254)
						(xy -0.254 -0.1778) (xy -0.254 0.1778)
					)
					(width 0)
					(fill yes)
				)
			)
		)
	)
	(footprint ""
		(layer "B.Cu")
		(at 29.21 32.639)
		(property "Reference" "R172"
			(at -0.02667 5.08 270)
			(unlocked yes)
			(layer "B.SilkS")
			(effects
				(font
					(size 0.7874 0.5842)
					(thickness 0.127)
				)
				(justify left mirror)
			)
		)
		(property "Value" "0"
			(at 0.148158 1.3462 270)
			(unlocked yes)
			(layer "B.Fab")
			(hide yes)
			(effects
				(font
					(size 1.27 0.9652)
					(thickness 0.000001)
				)
				(justify left mirror)
			)
		)
		(property "Device Type" "REST1111"
			(at 0.148158 1.3462 270)
			(unlocked yes)
			(layer "B.Fab")
			(hide yes)
			(effects
				(font
					(size 1.27 0.9652)
					(thickness 0.000001)
				)
				(justify left mirror)
			)
		)
		(duplicate_pad_numbers_are_jumpers no)
		(fp_poly
			(pts
				(xy -0.635 1.0668) (xy -0.635 -1.0668) (xy 0.635 -1.0668) (xy 0.635 1.0668)
			)
			(stroke
				(width 0)
				(type default)
			)
			(fill no)
			(layer "B.CrtYd")
		)
		(fp_line
			(start -0.254 -0.508)
			(end -0.254 0.508)
			(stroke
				(width 0.0254)
				(type default)
			)
			(layer "B.Fab")
		)
		(fp_line
			(start -0.254 0.508)
			(end 0.254 0.508)
			(stroke
				(width 0.0254)
				(type default)
			)
			(layer "B.Fab")
		)
		(fp_line
			(start 0.254 -0.508)
			(end -0.254 -0.508)
			(stroke
				(width 0.0254)
				(type default)
			)
			(layer "B.Fab")
		)
		(fp_line
			(start 0.254 0.508)
			(end 0.254 -0.508)
			(stroke
				(width 0.0254)
				(type default)
			)
			(layer "B.Fab")
		)
		(pad "1" smd rect
			(at 0 -0.4191 180)
			(size 0.508 0.5334)
			(layers "B.Cu" "B.Mask" "B.Paste")
			(net "NFP_CORE_VID2")
		)
		(pad "2" smd rect
			(at 0 0.4191 180)
			(size 0.508 0.5334)
			(layers "B.Cu" "B.Mask" "B.Paste")
			(net "_NFP_CORE_VID2")
		)
		(zone
			(layer "B.Cu")
			(hatch none 0.5)
			(connect_pads
				(clearance 0)
			)
			(min_thickness 0.25)
			(keepout
				(tracks not_allowed)
				(vias allowed)
				(pads allowed)
				(copperpour not_allowed)
				(footprints allowed)
			)
			(placement
				(enabled no)
				(sheetname "")
			)
			(fill
				(thermal_gap 0.5)
				(thermal_bridge_width 0.5)
				(island_removal_mode 0)
			)
			(polygon
				(pts
					(xy 29.1846 32.6136) (xy 29.1846 32.6644) (xy 29.2354 32.6644) (xy 29.2354 32.6136)
				)
			)
		)
	)
	(footprint ""
		(layer "B.Cu")
		(at 65.786 35.6362 180)
		(property "Reference" "C201"
			(at 0 0 0)
			(layer "B.SilkS")
			(hide yes)
			(effects
				(font
					(size 1.27 1.27)
				)
				(justify mirror)
			)
		)
		(property "Value" "1UF"
			(at 0.091846 0.2921 90)
			(unlocked yes)
			(layer "B.Fab")
			(hide yes)
			(effects
				(font
					(size 0.7874 0.5842)
					(thickness 0.2032)
				)
				(justify left mirror)
			)
		)
		(property "Device Type" "CAPC0028"
			(at 0.091846 0.2921 90)
			(unlocked yes)
			(layer "B.Fab")
			(hide yes)
			(effects
				(font
					(size 0.7874 0.5842)
					(thickness 0.2032)
				)
				(justify left mirror)
			)
		)
		(duplicate_pad_numbers_are_jumpers no)
		(fp_poly
			(pts
				(xy -0.635 1.0668) (xy -0.635 -1.0668) (xy 0.635 -1.0668) (xy 0.635 1.0668)
			)
			(stroke
				(width 0)
				(type default)
			)
			(fill no)
			(layer "B.CrtYd")
		)
		(fp_line
			(start 0.254 0.508)
			(end 0.254 -0.508)
			(stroke
				(width 0.0254)
				(type default)
			)
			(layer "B.Fab")
		)
		(fp_line
			(start 0.254 -0.508)
			(end -0.254 -0.508)
			(stroke
				(width 0.0254)
				(type default)
			)
			(layer "B.Fab")
		)
		(fp_line
			(start -0.254 0.508)
			(end 0.254 0.508)
			(stroke
				(width 0.0254)
				(type default)
			)
			(layer "B.Fab")
		)
		(fp_line
			(start -0.254 -0.508)
			(end -0.254 0.508)
			(stroke
				(width 0.0254)
				(type default)
			)
			(layer "B.Fab")
		)
		(pad "1" smd rect
			(at 0 -0.4191)
			(size 0.508 0.5334)
			(layers "B.Cu" "B.Mask" "B.Paste")
			(net "VDD_5.0V")
		)
		(pad "2" smd rect
			(at 0 0.4191)
			(size 0.508 0.5334)
			(layers "B.Cu" "B.Mask" "B.Paste")
			(net "GND")
		)
		(zone
			(layer "B.Cu")
			(hatch none 0.5)
			(connect_pads
				(clearance 0)
			)
			(min_thickness 0.25)
			(keepout
				(tracks not_allowed)
				(vias allowed)
				(pads allowed)
				(copperpour not_allowed)
				(footprints allowed)
			)
			(placement
				(enabled no)
				(sheetname "")
			)
			(fill
				(thermal_gap 0.5)
				(thermal_bridge_width 0.5)
				(island_removal_mode 0)
			)
			(polygon
				(pts
					(xy 65.8114 35.6616) (xy 65.8114 35.6108) (xy 65.7606 35.6108) (xy 65.7606 35.6616)
				)
			)
		)
	)
	(footprint ""
		(layer "B.Cu")
		(at 51.737006 9.042019 90)
		(property "Reference" "C102"
			(at 0 0 90)
			(layer "B.SilkS")
			(hide yes)
			(effects
				(font
					(size 1.27 1.27)
				)
				(justify mirror)
			)
		)
		(property "Value" ""
			(at 0 0 90)
			(layer "B.Fab")
			(effects
				(font
					(size 1.27 1.27)
				)
				(justify mirror)
			)
		)
		(duplicate_pad_numbers_are_jumpers no)
		(fp_circle
			(center 0 0)
			(end 0 0.104648)
			(stroke
				(width 0.1016)
				(type default)
			)
			(fill no)
			(layer "B.SilkS")
		)
		(fp_poly
			(pts
				(xy 0.381 -0.889) (xy 0.381 0.889) (xy -0.381 0.889) (xy -0.381 -0.889)
			)
			(stroke
				(width 0)
				(type default)
			)
			(fill no)
			(layer "B.CrtYd")
		)
		(fp_line
			(start 0.508 -1.016)
			(end 0.254 -1.016)
			(stroke
				(width 0.0254)
				(type default)
			)
			(layer "B.Fab")
		)
		(fp_line
			(start 0.254 -1.016)
			(end -0.508 -1.016)
			(stroke
				(width 0.0254)
				(type default)
			)
			(layer "B.Fab")
		)
		(fp_line
			(start -0.508 -1.016)
			(end -0.508 1.016)
			(stroke
				(width 0.0254)
				(type default)
			)
			(layer "B.Fab")
		)
		(fp_line
			(start 0.508 1.016)
			(end 0.508 -1.016)
			(stroke
				(width 0.0254)
				(type default)
			)
			(layer "B.Fab")
		)
		(fp_line
			(start -0.508 1.016)
			(end 0.508 1.016)
			(stroke
				(width 0.0254)
				(type default)
			)
			(layer "B.Fab")
		)
		(pad "1" smd custom
			(at 0 -0.500126 270)
			(size 0.127 0.127)
			(layers "B.Cu" "B.Mask" "B.Paste")
			(net "VDDAH_SERDES")
			(options
				(clearance outline)
				(anchor circle)
			)
			(primitives
				(gr_poly
					(pts
						(xy -0.1778 0.254) (xy 0.1778 0.254) (xy 0.254 0.1778) (xy 0.254 -0.1778) (xy 0.1778 -0.254) (xy -0.1778 -0.254)
						(xy -0.254 -0.1778) (xy -0.254 0.1778)
					)
					(width 0)
					(fill yes)
				)
			)
		)
		(pad "2" smd custom
			(at 0 0.500126 270)
			(size 0.127 0.127)
			(layers "B.Cu" "B.Mask" "B.Paste")
			(net "GND")
			(options
				(clearance outline)
				(anchor circle)
			)
			(primitives
				(gr_poly
					(pts
						(xy -0.1778 0.254) (xy 0.1778 0.254) (xy 0.254 0.1778) (xy 0.254 -0.1778) (xy 0.1778 -0.254) (xy -0.1778 -0.254)
						(xy -0.254 -0.1778) (xy -0.254 0.1778)
					)
					(width 0)
					(fill yes)
				)
			)
		)
	)
	(footprint ""
		(layer "B.Cu")
		(at 58.674 47.2948 90)
		(property "Reference" "TP36"
			(at -4.0132 -0.53467 270)
			(unlocked yes)
			(layer "B.SilkS")
			(effects
				(font
					(size 0.7874 0.5842)
					(thickness 0.127)
				)
				(justify left mirror)
			)
		)
		(property "Value" "*"
			(at 0.4826 -0.14732 90)
			(unlocked yes)
			(layer "B.Fab")
			(hide yes)
			(effects
				(font
					(size 1.27 0.9652)
					(thickness 0.000001)
				)
				(justify left mirror)
			)
		)
		(property "Device Type" "TP_SMALL"
			(at 0.4826 -0.14732 90)
			(unlocked yes)
			(layer "B.Fab")
			(hide yes)
			(effects
				(font
					(size 1.27 0.9652)
					(thickness 0.000001)
				)
				(justify left mirror)
			)
		)
		(duplicate_pad_numbers_are_jumpers no)
		(fp_line
			(start 0.8636 -0.8636)
			(end 0.8636 0.8636)
			(stroke
				(width 0.1524)
				(type default)
			)
			(layer "B.SilkS")
		)
		(fp_line
			(start -0.8636 -0.8636)
			(end 0.8636 -0.8636)
			(stroke
				(width 0.1524)
				(type default)
			)
			(layer "B.SilkS")
		)
		(fp_line
			(start 0.8636 0.8636)
			(end -0.8636 0.8636)
			(stroke
				(width 0.1524)
				(type default)
			)
			(layer "B.SilkS")
		)
		(fp_line
			(start -0.8636 0.8636)
			(end -0.8636 -0.8636)
			(stroke
				(width 0.1524)
				(type default)
			)
			(layer "B.SilkS")
		)
		(fp_poly
			(pts
				(xy 0.635 -0.635) (xy 0.635 0.635) (xy -0.635 0.635) (xy -0.635 -0.635)
			)
			(stroke
				(width 0)
				(type default)
			)
			(fill no)
			(layer "B.CrtYd")
		)
		(pad "1" smd rect
			(at 0 0 270)
			(size 1.27 1.27)
			(layers "B.Cu" "B.Mask" "B.Paste")
			(net "GL_PHASE1")
		)
	)
	(footprint ""
		(layer "B.Cu")
		(at 20.955 8.128 180)
		(property "Reference" "C85"
			(at 1.04267 -2.159 270)
			(unlocked yes)
			(layer "B.SilkS")
			(effects
				(font
					(size 0.7874 0.5842)
					(thickness 0.127)
				)
				(justify left mirror)
			)
		)
		(property "Value" "0.1UF"
			(at 0.091846 0.2921 90)
			(unlocked yes)
			(layer "B.Fab")
			(hide yes)
			(effects
				(font
					(size 0.7874 0.5842)
					(thickness 0.2032)
				)
				(justify left mirror)
			)
		)
		(property "Device Type" "CAPC0073"
			(at 0.091846 0.2921 90)
			(unlocked yes)
			(layer "B.Fab")
			(hide yes)
			(effects
				(font
					(size 0.7874 0.5842)
					(thickness 0.2032)
				)
				(justify left mirror)
			)
		)
		(duplicate_pad_numbers_are_jumpers no)
		(fp_poly
			(pts
				(xy -0.635 1.0668) (xy -0.635 -1.0668) (xy 0.635 -1.0668) (xy 0.635 1.0668)
			)
			(stroke
				(width 0)
				(type default)
			)
			(fill no)
			(layer "B.CrtYd")
		)
		(fp_line
			(start 0.254 0.508)
			(end 0.254 -0.508)
			(stroke
				(width 0.0254)
				(type default)
			)
			(layer "B.Fab")
		)
		(fp_line
			(start 0.254 -0.508)
			(end -0.254 -0.508)
			(stroke
				(width 0.0254)
				(type default)
			)
			(layer "B.Fab")
		)
		(fp_line
			(start -0.254 0.508)
			(end 0.254 0.508)
			(stroke
				(width 0.0254)
				(type default)
			)
			(layer "B.Fab")
		)
		(fp_line
			(start -0.254 -0.508)
			(end -0.254 0.508)
			(stroke
				(width 0.0254)
				(type default)
			)
			(layer "B.Fab")
		)
		(pad "1" smd rect
			(at 0 -0.4191)
			(size 0.508 0.5334)
			(layers "B.Cu" "B.Mask" "B.Paste")
			(net "VDD_3.3V")
		)
		(pad "2" smd rect
			(at 0 0.4191)
			(size 0.508 0.5334)
			(layers "B.Cu" "B.Mask" "B.Paste")
			(net "GND")
		)
		(zone
			(layer "B.Cu")
			(hatch none 0.5)
			(connect_pads
				(clearance 0)
			)
			(min_thickness 0.25)
			(keepout
				(tracks not_allowed)
				(vias allowed)
				(pads allowed)
				(copperpour not_allowed)
				(footprints allowed)
			)
			(placement
				(enabled no)
				(sheetname "")
			)
			(fill
				(thermal_gap 0.5)
				(thermal_bridge_width 0.5)
				(island_removal_mode 0)
			)
			(polygon
				(pts
					(xy 20.9804 8.1534) (xy 20.9804 8.1026) (xy 20.9296 8.1026) (xy 20.9296 8.1534)
				)
			)
		)
	)
	(footprint ""
		(layer "B.Cu")
		(at 25.146 38.862)
		(property "Reference" "TP38"
			(at -1.143 0.02667 0)
			(unlocked yes)
			(layer "B.SilkS")
			(effects
				(font
					(size 0.7874 0.5842)
					(thickness 0.127)
				)
				(justify left mirror)
			)
		)
		(property "Value" "*"
			(at 0.4826 -0.14732 0)
			(unlocked yes)
			(layer "B.Fab")
			(hide yes)
			(effects
				(font
					(size 1.27 0.9652)
					(thickness 0.000001)
				)
				(justify left mirror)
			)
		)
		(property "Device Type" "TP_SMALL"
			(at 0.4826 -0.14732 0)
			(unlocked yes)
			(layer "B.Fab")
			(hide yes)
			(effects
				(font
					(size 1.27 0.9652)
					(thickness 0.000001)
				)
				(justify left mirror)
			)
		)
		(duplicate_pad_numbers_are_jumpers no)
		(fp_line
			(start -0.8636 -0.8636)
			(end 0.8636 -0.8636)
			(stroke
				(width 0.1524)
				(type default)
			)
			(layer "B.SilkS")
		)
		(fp_line
			(start -0.8636 0.8636)
			(end -0.8636 -0.8636)
			(stroke
				(width 0.1524)
				(type default)
			)
			(layer "B.SilkS")
		)
		(fp_line
			(start 0.8636 -0.8636)
			(end 0.8636 0.8636)
			(stroke
				(width 0.1524)
				(type default)
			)
			(layer "B.SilkS")
		)
		(fp_line
			(start 0.8636 0.8636)
			(end -0.8636 0.8636)
			(stroke
				(width 0.1524)
				(type default)
			)
			(layer "B.SilkS")
		)
		(fp_poly
			(pts
				(xy 0.635 -0.635) (xy 0.635 0.635) (xy -0.635 0.635) (xy -0.635 -0.635)
			)
			(stroke
				(width 0)
				(type default)
			)
			(fill no)
			(layer "B.CrtYd")
		)
		(pad "1" smd rect
			(at 0 0 180)
			(size 1.27 1.27)
			(layers "B.Cu" "B.Mask" "B.Paste")
			(net "NFP_VDD_CORE_IMON")
		)
	)
	(footprint ""
		(layer "B.Cu")
		(at 60.236989 7.542022 180)
		(property "Reference" "C169"
			(at 0 0 0)
			(layer "B.SilkS")
			(hide yes)
			(effects
				(font
					(size 1.27 1.27)
				)
				(justify mirror)
			)
		)
		(property "Value" ""
			(at 0 0 0)
			(layer "B.Fab")
			(effects
				(font
					(size 1.27 1.27)
				)
				(justify mirror)
			)
		)
		(duplicate_pad_numbers_are_jumpers no)
		(fp_circle
			(center 0 0)
			(end -0.104648 0)
			(stroke
				(width 0.1016)
				(type default)
			)
			(fill no)
			(layer "B.SilkS")
		)
		(fp_poly
			(pts
				(xy 0.381 -0.889) (xy 0.381 0.889) (xy -0.381 0.889) (xy -0.381 -0.889)
			)
			(stroke
				(width 0)
				(type default)
			)
			(fill no)
			(layer "B.CrtYd")
		)
		(fp_line
			(start 0.508 1.016)
			(end 0.508 -1.016)
			(stroke
				(width 0.0254)
				(type default)
			)
			(layer "B.Fab")
		)
		(fp_line
			(start 0.508 -1.016)
			(end 0.254 -1.016)
			(stroke
				(width 0.0254)
				(type default)
			)
			(layer "B.Fab")
		)
		(fp_line
			(start 0.254 -1.016)
			(end -0.508 -1.016)
			(stroke
				(width 0.0254)
				(type default)
			)
			(layer "B.Fab")
		)
		(fp_line
			(start -0.508 1.016)
			(end 0.508 1.016)
			(stroke
				(width 0.0254)
				(type default)
			)
			(layer "B.Fab")
		)
		(fp_line
			(start -0.508 -1.016)
			(end -0.508 1.016)
			(stroke
				(width 0.0254)
				(type default)
			)
			(layer "B.Fab")
		)
		(pad "1" smd custom
			(at 0 -0.500126)
			(size 0.127 0.127)
			(layers "B.Cu" "B.Mask" "B.Paste")
			(net "VDDA_PCIE0")
			(options
				(clearance outline)
				(anchor circle)
			)
			(primitives
				(gr_poly
					(pts
						(xy -0.1778 0.254) (xy 0.1778 0.254) (xy 0.254 0.1778) (xy 0.254 -0.1778) (xy 0.1778 -0.254) (xy -0.1778 -0.254)
						(xy -0.254 -0.1778) (xy -0.254 0.1778)
					)
					(width 0)
					(fill yes)
				)
			)
		)
		(pad "2" smd custom
			(at 0 0.500126)
			(size 0.127 0.127)
			(layers "B.Cu" "B.Mask" "B.Paste")
			(net "GND")
			(options
				(clearance outline)
				(anchor circle)
			)
			(primitives
				(gr_poly
					(pts
						(xy -0.1778 0.254) (xy 0.1778 0.254) (xy 0.254 0.1778) (xy 0.254 -0.1778) (xy 0.1778 -0.254) (xy -0.1778 -0.254)
						(xy -0.254 -0.1778) (xy -0.254 0.1778)
					)
					(width 0)
					(fill yes)
				)
			)
		)
	)
	(footprint ""
		(layer "B.Cu")
		(at 81.050994 2.699004)
		(property "Reference" "V1_A-BA2"
			(at 0 0 0)
			(layer "B.SilkS")
			(hide yes)
			(effects
				(font
					(size 1.27 1.27)
				)
				(justify mirror)
			)
		)
		(property "Value" ""
			(at 0 0 0)
			(layer "B.Fab")
			(effects
				(font
					(size 1.27 1.27)
				)
				(justify mirror)
			)
		)
		(duplicate_pad_numbers_are_jumpers no)
		(pad "1" thru_hole circle
			(at 0 0 180)
			(size 0.4572 0.4572)
			(drill 0.20574)
			(layers "*.Cu" "*.Mask")
			(remove_unused_layers no)
			(net "DDR0_32A_BA2")
			(clearance 0.1143)
			(thermal_gap 0.1143)
		)
	)
	(footprint ""
		(layer "B.Cu")
		(at 47.736887 31.041975 -90)
		(property "Reference" "C176"
			(at 0 0 90)
			(layer "B.SilkS")
			(hide yes)
			(effects
				(font
					(size 1.27 1.27)
				)
				(justify mirror)
			)
		)
		(property "Value" ""
			(at 0 0 90)
			(layer "B.Fab")
			(effects
				(font
					(size 1.27 1.27)
				)
				(justify mirror)
			)
		)
		(duplicate_pad_numbers_are_jumpers no)
		(fp_circle
			(center 0 0)
			(end 0 -0.104648)
			(stroke
				(width 0.1016)
				(type default)
			)
			(fill no)
			(layer "B.SilkS")
		)
		(fp_poly
			(pts
				(xy 0.381 -0.889) (xy 0.381 0.889) (xy -0.381 0.889) (xy -0.381 -0.889)
			)
			(stroke
				(width 0)
				(type default)
			)
			(fill no)
			(layer "B.CrtYd")
		)
		(fp_line
			(start -0.508 1.016)
			(end 0.508 1.016)
			(stroke
				(width 0.0254)
				(type default)
			)
			(layer "B.Fab")
		)
		(fp_line
			(start 0.508 1.016)
			(end 0.508 -1.016)
			(stroke
				(width 0.0254)
				(type default)
			)
			(layer "B.Fab")
		)
		(fp_line
			(start -0.508 -1.016)
			(end -0.508 1.016)
			(stroke
				(width 0.0254)
				(type default)
			)
			(layer "B.Fab")
		)
		(fp_line
			(start 0.254 -1.016)
			(end -0.508 -1.016)
			(stroke
				(width 0.0254)
				(type default)
			)
			(layer "B.Fab")
		)
		(fp_line
			(start 0.508 -1.016)
			(end 0.254 -1.016)
			(stroke
				(width 0.0254)
				(type default)
			)
			(layer "B.Fab")
		)
		(pad "1" smd custom
			(at 0 -0.500126 90)
			(size 0.127 0.127)
			(layers "B.Cu" "B.Mask" "B.Paste")
			(net "VDD_CORE")
			(options
				(clearance outline)
				(anchor circle)
			)
			(primitives
				(gr_poly
					(pts
						(xy -0.1778 0.254) (xy 0.1778 0.254) (xy 0.254 0.1778) (xy 0.254 -0.1778) (xy 0.1778 -0.254) (xy -0.1778 -0.254)
						(xy -0.254 -0.1778) (xy -0.254 0.1778)
					)
					(width 0)
					(fill yes)
				)
			)
		)
		(pad "2" smd custom
			(at 0 0.500126 90)
			(size 0.127 0.127)
			(layers "B.Cu" "B.Mask" "B.Paste")
			(net "GND")
			(options
				(clearance outline)
				(anchor circle)
			)
			(primitives
				(gr_poly
					(pts
						(xy -0.1778 0.254) (xy 0.1778 0.254) (xy 0.254 0.1778) (xy 0.254 -0.1778) (xy 0.1778 -0.254) (xy -0.1778 -0.254)
						(xy -0.254 -0.1778) (xy -0.254 0.1778)
					)
					(width 0)
					(fill yes)
				)
			)
		)
	)
	(footprint ""
		(layer "B.Cu")
		(at 2.667 17.4498)
		(property "Reference" "R377"
			(at -0.78867 3.1242 270)
			(unlocked yes)
			(layer "B.SilkS")
			(effects
				(font
					(size 0.7874 0.5842)
					(thickness 0.127)
				)
				(justify left mirror)
			)
		)
		(property "Value" "4.75K"
			(at 0.148158 1.3462 270)
			(unlocked yes)
			(layer "B.Fab")
			(hide yes)
			(effects
				(font
					(size 1.27 0.9652)
					(thickness 0.000001)
				)
				(justify left mirror)
			)
		)
		(property "Device Type" "REST4024"
			(at 0.148158 1.3462 270)
			(unlocked yes)
			(layer "B.Fab")
			(hide yes)
			(effects
				(font
					(size 1.27 0.9652)
					(thickness 0.000001)
				)
				(justify left mirror)
			)
		)
		(duplicate_pad_numbers_are_jumpers no)
		(fp_poly
			(pts
				(xy -0.635 1.0668) (xy -0.635 -1.0668) (xy 0.635 -1.0668) (xy 0.635 1.0668)
			)
			(stroke
				(width 0)
				(type default)
			)
			(fill no)
			(layer "B.CrtYd")
		)
		(fp_line
			(start -0.254 -0.508)
			(end -0.254 0.508)
			(stroke
				(width 0.0254)
				(type default)
			)
			(layer "B.Fab")
		)
		(fp_line
			(start -0.254 0.508)
			(end 0.254 0.508)
			(stroke
				(width 0.0254)
				(type default)
			)
			(layer "B.Fab")
		)
		(fp_line
			(start 0.254 -0.508)
			(end -0.254 -0.508)
			(stroke
				(width 0.0254)
				(type default)
			)
			(layer "B.Fab")
		)
		(fp_line
			(start 0.254 0.508)
			(end 0.254 -0.508)
			(stroke
				(width 0.0254)
				(type default)
			)
			(layer "B.Fab")
		)
		(pad "1" smd rect
			(at 0 -0.4191 180)
			(size 0.508 0.5334)
			(layers "B.Cu" "B.Mask" "B.Paste")
			(net "NWK0_I2C_SCL")
		)
		(pad "2" smd rect
			(at 0 0.4191 180)
			(size 0.508 0.5334)
			(layers "B.Cu" "B.Mask" "B.Paste")
			(net "EXT_3.3V")
		)
		(zone
			(layer "B.Cu")
			(hatch none 0.5)
			(connect_pads
				(clearance 0)
			)
			(min_thickness 0.25)
			(keepout
				(tracks not_allowed)
				(vias allowed)
				(pads allowed)
				(copperpour not_allowed)
				(footprints allowed)
			)
			(placement
				(enabled no)
				(sheetname "")
			)
			(fill
				(thermal_gap 0.5)
				(thermal_bridge_width 0.5)
				(island_removal_mode 0)
			)
			(polygon
				(pts
					(xy 2.6416 17.4244) (xy 2.6416 17.4752) (xy 2.6924 17.4752) (xy 2.6924 17.4244)
				)
			)
		)
	)
	(footprint ""
		(layer "B.Cu")
		(at 5.2578 9.7028)
		(property "Reference" "TP28"
			(at 1.82753 1.9812 270)
			(unlocked yes)
			(layer "B.SilkS")
			(effects
				(font
					(size 0.7874 0.5842)
					(thickness 0.127)
				)
				(justify left mirror)
			)
		)
		(property "Value" "*"
			(at 0.4826 -0.14732 0)
			(unlocked yes)
			(layer "B.Fab")
			(hide yes)
			(effects
				(font
					(size 1.27 0.9652)
					(thickness 0.000001)
				)
				(justify left mirror)
			)
		)
		(property "Device Type" "TP_SMALL"
			(at 0.4826 -0.14732 0)
			(unlocked yes)
			(layer "B.Fab")
			(hide yes)
			(effects
				(font
					(size 1.27 0.9652)
					(thickness 0.000001)
				)
				(justify left mirror)
			)
		)
		(duplicate_pad_numbers_are_jumpers no)
		(fp_line
			(start -0.8636 -0.8636)
			(end 0.8636 -0.8636)
			(stroke
				(width 0.1524)
				(type default)
			)
			(layer "B.SilkS")
		)
		(fp_line
			(start -0.8636 0.8636)
			(end -0.8636 -0.8636)
			(stroke
				(width 0.1524)
				(type default)
			)
			(layer "B.SilkS")
		)
		(fp_line
			(start 0.8636 -0.8636)
			(end 0.8636 0.8636)
			(stroke
				(width 0.1524)
				(type default)
			)
			(layer "B.SilkS")
		)
		(fp_line
			(start 0.8636 0.8636)
			(end -0.8636 0.8636)
			(stroke
				(width 0.1524)
				(type default)
			)
			(layer "B.SilkS")
		)
		(fp_poly
			(pts
				(xy 0.635 -0.635) (xy 0.635 0.635) (xy -0.635 0.635) (xy -0.635 -0.635)
			)
			(stroke
				(width 0)
				(type default)
			)
			(fill no)
			(layer "B.CrtYd")
		)
		(pad "1" smd rect
			(at 0 0 180)
			(size 1.27 1.27)
			(layers "B.Cu" "B.Mask" "B.Paste")
			(net "PGRM_JTAG_TDI")
		)
	)
	(footprint ""
		(layer "B.Cu")
		(at 53.237003 19.541998 180)
		(property "Reference" "C44"
			(at 0.050673 -2.556002 270)
			(unlocked yes)
			(layer "B.SilkS")
			(effects
				(font
					(size 0.7874 0.5842)
					(thickness 0.127)
				)
				(justify mirror)
			)
		)
		(property "Value" ""
			(at 0 0 0)
			(layer "B.Fab")
			(effects
				(font
					(size 1.27 1.27)
				)
				(justify mirror)
			)
		)
		(duplicate_pad_numbers_are_jumpers no)
		(fp_circle
			(center 0 0)
			(end -0.104648 0)
			(stroke
				(width 0.1016)
				(type default)
			)
			(fill no)
			(layer "B.SilkS")
		)
		(fp_poly
			(pts
				(xy 0.381 -0.889) (xy 0.381 0.889) (xy -0.381 0.889) (xy -0.381 -0.889)
			)
			(stroke
				(width 0)
				(type default)
			)
			(fill no)
			(layer "B.CrtYd")
		)
		(fp_line
			(start 0.508 1.016)
			(end 0.508 -1.016)
			(stroke
				(width 0.0254)
				(type default)
			)
			(layer "B.Fab")
		)
		(fp_line
			(start 0.508 -1.016)
			(end 0.254 -1.016)
			(stroke
				(width 0.0254)
				(type default)
			)
			(layer "B.Fab")
		)
		(fp_line
			(start 0.254 -1.016)
			(end -0.508 -1.016)
			(stroke
				(width 0.0254)
				(type default)
			)
			(layer "B.Fab")
		)
		(fp_line
			(start -0.508 1.016)
			(end 0.508 1.016)
			(stroke
				(width 0.0254)
				(type default)
			)
			(layer "B.Fab")
		)
		(fp_line
			(start -0.508 -1.016)
			(end -0.508 1.016)
			(stroke
				(width 0.0254)
				(type default)
			)
			(layer "B.Fab")
		)
		(pad "1" smd custom
			(at 0 -0.500126)
			(size 0.127 0.127)
			(layers "B.Cu" "B.Mask" "B.Paste")
			(net "VDDA_DDR0_32A")
			(options
				(clearance outline)
				(anchor circle)
			)
			(primitives
				(gr_poly
					(pts
						(xy -0.1778 0.254) (xy 0.1778 0.254) (xy 0.254 0.1778) (xy 0.254 -0.1778) (xy 0.1778 -0.254) (xy -0.1778 -0.254)
						(xy -0.254 -0.1778) (xy -0.254 0.1778)
					)
					(width 0)
					(fill yes)
				)
			)
		)
		(pad "2" smd custom
			(at 0 0.500126)
			(size 0.127 0.127)
			(layers "B.Cu" "B.Mask" "B.Paste")
			(net "GND")
			(options
				(clearance outline)
				(anchor circle)
			)
			(primitives
				(gr_poly
					(pts
						(xy -0.1778 0.254) (xy 0.1778 0.254) (xy 0.254 0.1778) (xy 0.254 -0.1778) (xy 0.1778 -0.254) (xy -0.1778 -0.254)
						(xy -0.254 -0.1778) (xy -0.254 0.1778)
					)
					(width 0)
					(fill yes)
				)
			)
		)
	)
	(footprint ""
		(layer "B.Cu")
		(at 79.450997 25.813004)
		(property "Reference" "V3_A-CAS"
			(at 0 0 0)
			(layer "B.SilkS")
			(hide yes)
			(effects
				(font
					(size 1.27 1.27)
				)
				(justify mirror)
			)
		)
		(property "Value" ""
			(at 0 0 0)
			(layer "B.Fab")
			(effects
				(font
					(size 1.27 1.27)
				)
				(justify mirror)
			)
		)
		(duplicate_pad_numbers_are_jumpers no)
		(pad "1" thru_hole circle
			(at 0 0 180)
			(size 0.4572 0.4572)
			(drill 0.20574)
			(layers "*.Cu" "*.Mask")
			(remove_unused_layers no)
			(net "DDR0_32A_CAS_L")
			(clearance 0.1143)
			(thermal_gap 0.1143)
		)
	)
	(footprint ""
		(layer "B.Cu")
		(at 80.250995 6.698996)
		(property "Reference" "V1_A-A10"
			(at 0 0 0)
			(layer "B.SilkS")
			(hide yes)
			(effects
				(font
					(size 1.27 1.27)
				)
				(justify mirror)
			)
		)
		(property "Value" ""
			(at 0 0 0)
			(layer "B.Fab")
			(effects
				(font
					(size 1.27 1.27)
				)
				(justify mirror)
			)
		)
		(duplicate_pad_numbers_are_jumpers no)
		(pad "1" thru_hole circle
			(at 0 0 180)
			(size 0.4572 0.4572)
			(drill 0.20574)
			(layers "*.Cu" "*.Mask")
			(remove_unused_layers no)
			(net "DDR0_32A_A10")
			(clearance 0.1143)
			(thermal_gap 0.1143)
		)
	)
	(footprint ""
		(layer "B.Cu")
		(at 82.65099 13.456006)
		(property "Reference" "V2_A-A05"
			(at 0 0 0)
			(layer "B.SilkS")
			(hide yes)
			(effects
				(font
					(size 1.27 1.27)
				)
				(justify mirror)
			)
		)
		(property "Value" ""
			(at 0 0 0)
			(layer "B.Fab")
			(effects
				(font
					(size 1.27 1.27)
				)
				(justify mirror)
			)
		)
		(duplicate_pad_numbers_are_jumpers no)
		(pad "1" thru_hole circle
			(at 0 0 180)
			(size 0.4572 0.4572)
			(drill 0.20574)
			(layers "*.Cu" "*.Mask")
			(remove_unused_layers no)
			(net "DDR0_32A_A5")
			(clearance 0.1143)
			(thermal_gap 0.1143)
		)
	)
	(footprint ""
		(layer "B.Cu")
		(at 62.357 6.604 90)
		(property "Reference" "C278"
			(at -0.02667 4.318 0)
			(unlocked yes)
			(layer "B.SilkS")
			(effects
				(font
					(size 0.7874 0.5842)
					(thickness 0.127)
				)
				(justify left mirror)
			)
		)
		(property "Value" "22UF"
			(at 0.148158 1.7526 0)
			(unlocked yes)
			(layer "B.Fab")
			(hide yes)
			(effects
				(font
					(size 1.27 0.9652)
					(thickness 0.000001)
				)
				(justify left mirror)
			)
		)
		(property "Device Type" "CAPC0063"
			(at 0.148158 1.7526 0)
			(unlocked yes)
			(layer "B.Fab")
			(hide yes)
			(effects
				(font
					(size 1.27 0.9652)
					(thickness 0.000001)
				)
				(justify left mirror)
			)
		)
		(duplicate_pad_numbers_are_jumpers no)
		(fp_circle
			(center 0 0)
			(end 0 0.127)
			(stroke
				(width 0.2032)
				(type default)
			)
			(fill no)
			(layer "B.SilkS")
		)
		(fp_poly
			(pts
				(xy -0.7874 -1.6637) (xy 0.7874 -1.6637) (xy 0.7874 1.6637) (xy -0.7874 1.6637)
			)
			(stroke
				(width 0)
				(type default)
			)
			(fill no)
			(layer "B.CrtYd")
		)
		(fp_line
			(start 0.4064 -0.7874)
			(end -0.4064 -0.7874)
			(stroke
				(width 0.0254)
				(type default)
			)
			(layer "B.Fab")
		)
		(fp_line
			(start -0.4064 -0.7874)
			(end -0.4064 0.8128)
			(stroke
				(width 0.0254)
				(type default)
			)
			(layer "B.Fab")
		)
		(fp_line
			(start 0.4064 0.8128)
			(end 0.4064 -0.7874)
			(stroke
				(width 0.0254)
				(type default)
			)
			(layer "B.Fab")
		)
		(fp_line
			(start -0.4064 0.8128)
			(end 0.4064 0.8128)
			(stroke
				(width 0.0254)
				(type default)
			)
			(layer "B.Fab")
		)
		(pad "1" smd rect
			(at 0 -0.8001 270)
			(size 0.8636 0.9652)
			(layers "B.Cu" "B.Mask" "B.Paste")
			(net "VDDA_PCIE0")
		)
		(pad "2" smd rect
			(at 0 0.8001 270)
			(size 0.8636 0.9652)
			(layers "B.Cu" "B.Mask" "B.Paste")
			(net "GND")
		)
		(zone
			(layer "B.Cu")
			(hatch none 0.5)
			(connect_pads
				(clearance 0)
			)
			(min_thickness 0.25)
			(keepout
				(tracks not_allowed)
				(vias allowed)
				(pads allowed)
				(copperpour not_allowed)
				(footprints allowed)
			)
			(placement
				(enabled no)
				(sheetname "")
			)
			(fill
				(thermal_gap 0.5)
				(thermal_bridge_width 0.5)
				(island_removal_mode 0)
			)
			(polygon
				(pts
					(xy 62.103 6.5405) (xy 62.103 6.6675) (xy 62.611 6.6675) (xy 62.611 6.5405)
				)
			)
		)
	)
	(footprint ""
		(layer "B.Cu")
		(at 77.051002 29.812996)
		(property "Reference" "V_A-CB1"
			(at 0 0 0)
			(layer "B.SilkS")
			(hide yes)
			(effects
				(font
					(size 1.27 1.27)
				)
				(justify mirror)
			)
		)
		(property "Value" ""
			(at 0 0 0)
			(layer "B.Fab")
			(effects
				(font
					(size 1.27 1.27)
				)
				(justify mirror)
			)
		)
		(duplicate_pad_numbers_are_jumpers no)
		(pad "1" thru_hole circle
			(at 0 0 180)
			(size 0.4572 0.4572)
			(drill 0.20574)
			(layers "*.Cu" "*.Mask")
			(remove_unused_layers no)
			(net "DDR0_32A_CB1")
			(clearance 0.1143)
			(thermal_gap 0.1143)
		)
	)
	(footprint ""
		(layer "B.Cu")
		(at 61.736986 22.041993 90)
		(property "Reference" "R187"
			(at 0 0 90)
			(layer "B.SilkS")
			(hide yes)
			(effects
				(font
					(size 1.27 1.27)
				)
				(justify mirror)
			)
		)
		(property "Value" ""
			(at 0 0 90)
			(layer "B.Fab")
			(effects
				(font
					(size 1.27 1.27)
				)
				(justify mirror)
			)
		)
		(duplicate_pad_numbers_are_jumpers no)
		(fp_circle
			(center 0 0)
			(end 0 0.104648)
			(stroke
				(width 0.1016)
				(type default)
			)
			(fill no)
			(layer "B.SilkS")
		)
		(fp_poly
			(pts
				(xy 0.381 -0.889) (xy 0.381 0.889) (xy -0.381 0.889) (xy -0.381 -0.889)
			)
			(stroke
				(width 0)
				(type default)
			)
			(fill no)
			(layer "B.CrtYd")
		)
		(fp_line
			(start 0.508 -1.016)
			(end 0.254 -1.016)
			(stroke
				(width 0.0254)
				(type default)
			)
			(layer "B.Fab")
		)
		(fp_line
			(start 0.254 -1.016)
			(end -0.508 -1.016)
			(stroke
				(width 0.0254)
				(type default)
			)
			(layer "B.Fab")
		)
		(fp_line
			(start -0.508 -1.016)
			(end -0.508 1.016)
			(stroke
				(width 0.0254)
				(type default)
			)
			(layer "B.Fab")
		)
		(fp_line
			(start 0.508 1.016)
			(end 0.508 -1.016)
			(stroke
				(width 0.0254)
				(type default)
			)
			(layer "B.Fab")
		)
		(fp_line
			(start -0.508 1.016)
			(end 0.508 1.016)
			(stroke
				(width 0.0254)
				(type default)
			)
			(layer "B.Fab")
		)
		(pad "1" smd custom
			(at 0 -0.500126 270)
			(size 0.127 0.127)
			(layers "B.Cu" "B.Mask" "B.Paste")
			(net "GND")
			(options
				(clearance outline)
				(anchor circle)
			)
			(primitives
				(gr_poly
					(pts
						(xy -0.1778 0.254) (xy 0.1778 0.254) (xy 0.254 0.1778) (xy 0.254 -0.1778) (xy 0.1778 -0.254) (xy -0.1778 -0.254)
						(xy -0.254 -0.1778) (xy -0.254 0.1778)
					)
					(width 0)
					(fill yes)
				)
			)
		)
		(pad "2" smd custom
			(at 0 0.500126 270)
			(size 0.127 0.127)
			(layers "B.Cu" "B.Mask" "B.Paste")
			(net "A_DZQ0")
			(options
				(clearance outline)
				(anchor circle)
			)
			(primitives
				(gr_poly
					(pts
						(xy -0.1778 0.254) (xy 0.1778 0.254) (xy 0.254 0.1778) (xy 0.254 -0.1778) (xy 0.1778 -0.254) (xy -0.1778 -0.254)
						(xy -0.254 -0.1778) (xy -0.254 0.1778)
					)
					(width 0)
					(fill yes)
				)
			)
		)
	)
	(footprint ""
		(layer "B.Cu")
		(at 21.336 13.589)
		(property "Reference" "R30"
			(at -0.15367 -0.889 270)
			(unlocked yes)
			(layer "B.SilkS")
			(effects
				(font
					(size 0.7874 0.5842)
					(thickness 0.127)
				)
				(justify left mirror)
			)
		)
		(property "Value" "4.75K"
			(at 0.148158 1.3462 270)
			(unlocked yes)
			(layer "B.Fab")
			(hide yes)
			(effects
				(font
					(size 1.27 0.9652)
					(thickness 0.000001)
				)
				(justify left mirror)
			)
		)
		(property "Device Type" "REST4024"
			(at 0.148158 1.3462 270)
			(unlocked yes)
			(layer "B.Fab")
			(hide yes)
			(effects
				(font
					(size 1.27 0.9652)
					(thickness 0.000001)
				)
				(justify left mirror)
			)
		)
		(duplicate_pad_numbers_are_jumpers no)
		(fp_poly
			(pts
				(xy -0.635 1.0668) (xy -0.635 -1.0668) (xy 0.635 -1.0668) (xy 0.635 1.0668)
			)
			(stroke
				(width 0)
				(type default)
			)
			(fill no)
			(layer "B.CrtYd")
		)
		(fp_line
			(start -0.254 -0.508)
			(end -0.254 0.508)
			(stroke
				(width 0.0254)
				(type default)
			)
			(layer "B.Fab")
		)
		(fp_line
			(start -0.254 0.508)
			(end 0.254 0.508)
			(stroke
				(width 0.0254)
				(type default)
			)
			(layer "B.Fab")
		)
		(fp_line
			(start 0.254 -0.508)
			(end -0.254 -0.508)
			(stroke
				(width 0.0254)
				(type default)
			)
			(layer "B.Fab")
		)
		(fp_line
			(start 0.254 0.508)
			(end 0.254 -0.508)
			(stroke
				(width 0.0254)
				(type default)
			)
			(layer "B.Fab")
		)
		(pad "1" smd rect
			(at 0 -0.4191 180)
			(size 0.508 0.5334)
			(layers "B.Cu" "B.Mask" "B.Paste")
			(net "VDD_3.3V")
		)
		(pad "2" smd rect
			(at 0 0.4191 180)
			(size 0.508 0.5334)
			(layers "B.Cu" "B.Mask" "B.Paste")
			(net "NFP_CFG_SPI_FLASH_SEL")
		)
		(zone
			(layer "B.Cu")
			(hatch none 0.5)
			(connect_pads
				(clearance 0)
			)
			(min_thickness 0.25)
			(keepout
				(tracks not_allowed)
				(vias allowed)
				(pads allowed)
				(copperpour not_allowed)
				(footprints allowed)
			)
			(placement
				(enabled no)
				(sheetname "")
			)
			(fill
				(thermal_gap 0.5)
				(thermal_bridge_width 0.5)
				(island_removal_mode 0)
			)
			(polygon
				(pts
					(xy 21.3106 13.5636) (xy 21.3106 13.6144) (xy 21.3614 13.6144) (xy 21.3614 13.5636)
				)
			)
		)
	)
	(footprint ""
		(layer "B.Cu")
		(at 30.099 32.639)
		(property "Reference" "R95"
			(at -0.02667 3.683 270)
			(unlocked yes)
			(layer "B.SilkS")
			(effects
				(font
					(size 0.7874 0.5842)
					(thickness 0.127)
				)
				(justify left mirror)
			)
		)
		(property "Value" "4.75K"
			(at 0.148158 1.3462 270)
			(unlocked yes)
			(layer "B.Fab")
			(hide yes)
			(effects
				(font
					(size 1.27 0.9652)
					(thickness 0.000001)
				)
				(justify left mirror)
			)
		)
		(property "Device Type" "REST4024"
			(at 0.148158 1.3462 270)
			(unlocked yes)
			(layer "B.Fab")
			(hide yes)
			(effects
				(font
					(size 1.27 0.9652)
					(thickness 0.000001)
				)
				(justify left mirror)
			)
		)
		(duplicate_pad_numbers_are_jumpers no)
		(fp_poly
			(pts
				(xy -0.635 1.0668) (xy -0.635 -1.0668) (xy 0.635 -1.0668) (xy 0.635 1.0668)
			)
			(stroke
				(width 0)
				(type default)
			)
			(fill no)
			(layer "B.CrtYd")
		)
		(fp_line
			(start -0.254 -0.508)
			(end -0.254 0.508)
			(stroke
				(width 0.0254)
				(type default)
			)
			(layer "B.Fab")
		)
		(fp_line
			(start -0.254 0.508)
			(end 0.254 0.508)
			(stroke
				(width 0.0254)
				(type default)
			)
			(layer "B.Fab")
		)
		(fp_line
			(start 0.254 -0.508)
			(end -0.254 -0.508)
			(stroke
				(width 0.0254)
				(type default)
			)
			(layer "B.Fab")
		)
		(fp_line
			(start 0.254 0.508)
			(end 0.254 -0.508)
			(stroke
				(width 0.0254)
				(type default)
			)
			(layer "B.Fab")
		)
		(pad "1" smd rect
			(at 0 -0.4191 180)
			(size 0.508 0.5334)
			(layers "B.Cu" "B.Mask" "B.Paste")
			(net "GND")
		)
		(pad "2" smd rect
			(at 0 0.4191 180)
			(size 0.508 0.5334)
			(layers "B.Cu" "B.Mask" "B.Paste")
			(net "_NFP_CORE_VID3")
		)
		(zone
			(layer "B.Cu")
			(hatch none 0.5)
			(connect_pads
				(clearance 0)
			)
			(min_thickness 0.25)
			(keepout
				(tracks not_allowed)
				(vias allowed)
				(pads allowed)
				(copperpour not_allowed)
				(footprints allowed)
			)
			(placement
				(enabled no)
				(sheetname "")
			)
			(fill
				(thermal_gap 0.5)
				(thermal_bridge_width 0.5)
				(island_removal_mode 0)
			)
			(polygon
				(pts
					(xy 30.0736 32.6136) (xy 30.0736 32.6644) (xy 30.1244 32.6644) (xy 30.1244 32.6136)
				)
			)
		)
	)
	(footprint ""
		(layer "B.Cu")
		(at 81.1022 42.799 90)
		(property "Reference" "C128"
			(at -0.78867 1.3208 0)
			(unlocked yes)
			(layer "B.SilkS")
			(effects
				(font
					(size 0.7874 0.5842)
					(thickness 0.127)
				)
				(justify left mirror)
			)
		)
		(property "Value" "0.1UF"
			(at 0.091846 0.2921 0)
			(unlocked yes)
			(layer "B.Fab")
			(hide yes)
			(effects
				(font
					(size 0.7874 0.5842)
					(thickness 0.2032)
				)
				(justify left mirror)
			)
		)
		(property "Device Type" "CAPC0073"
			(at 0.091846 0.2921 0)
			(unlocked yes)
			(layer "B.Fab")
			(hide yes)
			(effects
				(font
					(size 0.7874 0.5842)
					(thickness 0.2032)
				)
				(justify left mirror)
			)
		)
		(duplicate_pad_numbers_are_jumpers no)
		(fp_poly
			(pts
				(xy -0.635 1.0668) (xy -0.635 -1.0668) (xy 0.635 -1.0668) (xy 0.635 1.0668)
			)
			(stroke
				(width 0)
				(type default)
			)
			(fill no)
			(layer "B.CrtYd")
		)
		(fp_line
			(start 0.254 -0.508)
			(end -0.254 -0.508)
			(stroke
				(width 0.0254)
				(type default)
			)
			(layer "B.Fab")
		)
		(fp_line
			(start -0.254 -0.508)
			(end -0.254 0.508)
			(stroke
				(width 0.0254)
				(type default)
			)
			(layer "B.Fab")
		)
		(fp_line
			(start 0.254 0.508)
			(end 0.254 -0.508)
			(stroke
				(width 0.0254)
				(type default)
			)
			(layer "B.Fab")
		)
		(fp_line
			(start -0.254 0.508)
			(end 0.254 0.508)
			(stroke
				(width 0.0254)
				(type default)
			)
			(layer "B.Fab")
		)
		(pad "1" smd rect
			(at 0 -0.4191 270)
			(size 0.508 0.5334)
			(layers "B.Cu" "B.Mask" "B.Paste")
			(net "11N2152")
		)
		(pad "2" smd rect
			(at 0 0.4191 270)
			(size 0.508 0.5334)
			(layers "B.Cu" "B.Mask" "B.Paste")
			(net "GND")
		)
		(zone
			(layer "B.Cu")
			(hatch none 0.5)
			(connect_pads
				(clearance 0)
			)
			(min_thickness 0.25)
			(keepout
				(tracks not_allowed)
				(vias allowed)
				(pads allowed)
				(copperpour not_allowed)
				(footprints allowed)
			)
			(placement
				(enabled no)
				(sheetname "")
			)
			(fill
				(thermal_gap 0.5)
				(thermal_bridge_width 0.5)
				(island_removal_mode 0)
			)
			(polygon
				(pts
					(xy 81.0768 42.8244) (xy 81.1276 42.8244) (xy 81.1276 42.7736) (xy 81.0768 42.7736)
				)
			)
		)
	)
	(footprint ""
		(layer "B.Cu")
		(at 51.737006 10.042017 90)
		(property "Reference" "C43"
			(at 0 0 90)
			(layer "B.SilkS")
			(hide yes)
			(effects
				(font
					(size 1.27 1.27)
				)
				(justify mirror)
			)
		)
		(property "Value" ""
			(at 0 0 90)
			(layer "B.Fab")
			(effects
				(font
					(size 1.27 1.27)
				)
				(justify mirror)
			)
		)
		(duplicate_pad_numbers_are_jumpers no)
		(fp_circle
			(center 0 0)
			(end 0 0.104648)
			(stroke
				(width 0.1016)
				(type default)
			)
			(fill no)
			(layer "B.SilkS")
		)
		(fp_poly
			(pts
				(xy 0.381 -0.889) (xy 0.381 0.889) (xy -0.381 0.889) (xy -0.381 -0.889)
			)
			(stroke
				(width 0)
				(type default)
			)
			(fill no)
			(layer "B.CrtYd")
		)
		(fp_line
			(start 0.508 -1.016)
			(end 0.254 -1.016)
			(stroke
				(width 0.0254)
				(type default)
			)
			(layer "B.Fab")
		)
		(fp_line
			(start 0.254 -1.016)
			(end -0.508 -1.016)
			(stroke
				(width 0.0254)
				(type default)
			)
			(layer "B.Fab")
		)
		(fp_line
			(start -0.508 -1.016)
			(end -0.508 1.016)
			(stroke
				(width 0.0254)
				(type default)
			)
			(layer "B.Fab")
		)
		(fp_line
			(start 0.508 1.016)
			(end 0.508 -1.016)
			(stroke
				(width 0.0254)
				(type default)
			)
			(layer "B.Fab")
		)
		(fp_line
			(start -0.508 1.016)
			(end 0.508 1.016)
			(stroke
				(width 0.0254)
				(type default)
			)
			(layer "B.Fab")
		)
		(pad "1" smd custom
			(at 0 -0.500126 270)
			(size 0.127 0.127)
			(layers "B.Cu" "B.Mask" "B.Paste")
			(net "VDDAH_SERDES")
			(options
				(clearance outline)
				(anchor circle)
			)
			(primitives
				(gr_poly
					(pts
						(xy -0.1778 0.254) (xy 0.1778 0.254) (xy 0.254 0.1778) (xy 0.254 -0.1778) (xy 0.1778 -0.254) (xy -0.1778 -0.254)
						(xy -0.254 -0.1778) (xy -0.254 0.1778)
					)
					(width 0)
					(fill yes)
				)
			)
		)
		(pad "2" smd custom
			(at 0 0.500126 270)
			(size 0.127 0.127)
			(layers "B.Cu" "B.Mask" "B.Paste")
			(net "GND")
			(options
				(clearance outline)
				(anchor circle)
			)
			(primitives
				(gr_poly
					(pts
						(xy -0.1778 0.254) (xy 0.1778 0.254) (xy 0.254 0.1778) (xy 0.254 -0.1778) (xy 0.1778 -0.254) (xy -0.1778 -0.254)
						(xy -0.254 -0.1778) (xy -0.254 0.1778)
					)
					(width 0)
					(fill yes)
				)
			)
		)
	)
	(footprint ""
		(layer "B.Cu")
		(at 20.32 13.589 180)
		(property "Reference" "R18"
			(at 1.16967 -0.635 270)
			(unlocked yes)
			(layer "B.SilkS")
			(effects
				(font
					(size 0.7874 0.5842)
					(thickness 0.127)
				)
				(justify left mirror)
			)
		)
		(property "Value" "4.75K"
			(at 0.148158 1.3462 90)
			(unlocked yes)
			(layer "B.Fab")
			(hide yes)
			(effects
				(font
					(size 1.27 0.9652)
					(thickness 0.000001)
				)
				(justify left mirror)
			)
		)
		(property "Device Type" "REST4024"
			(at 0.148158 1.3462 90)
			(unlocked yes)
			(layer "B.Fab")
			(hide yes)
			(effects
				(font
					(size 1.27 0.9652)
					(thickness 0.000001)
				)
				(justify left mirror)
			)
		)
		(duplicate_pad_numbers_are_jumpers no)
		(fp_poly
			(pts
				(xy -0.635 1.0668) (xy -0.635 -1.0668) (xy 0.635 -1.0668) (xy 0.635 1.0668)
			)
			(stroke
				(width 0)
				(type default)
			)
			(fill no)
			(layer "B.CrtYd")
		)
		(fp_line
			(start 0.254 0.508)
			(end 0.254 -0.508)
			(stroke
				(width 0.0254)
				(type default)
			)
			(layer "B.Fab")
		)
		(fp_line
			(start 0.254 -0.508)
			(end -0.254 -0.508)
			(stroke
				(width 0.0254)
				(type default)
			)
			(layer "B.Fab")
		)
		(fp_line
			(start -0.254 0.508)
			(end 0.254 0.508)
			(stroke
				(width 0.0254)
				(type default)
			)
			(layer "B.Fab")
		)
		(fp_line
			(start -0.254 -0.508)
			(end -0.254 0.508)
			(stroke
				(width 0.0254)
				(type default)
			)
			(layer "B.Fab")
		)
		(pad "1" smd rect
			(at 0 -0.4191)
			(size 0.508 0.5334)
			(layers "B.Cu" "B.Mask" "B.Paste")
			(net "NFP_CFG_SPI_FLASH_SEL")
		)
		(pad "2" smd rect
			(at 0 0.4191)
			(size 0.508 0.5334)
			(layers "B.Cu" "B.Mask" "B.Paste")
			(net "GND")
		)
		(zone
			(layer "B.Cu")
			(hatch none 0.5)
			(connect_pads
				(clearance 0)
			)
			(min_thickness 0.25)
			(keepout
				(tracks not_allowed)
				(vias allowed)
				(pads allowed)
				(copperpour not_allowed)
				(footprints allowed)
			)
			(placement
				(enabled no)
				(sheetname "")
			)
			(fill
				(thermal_gap 0.5)
				(thermal_bridge_width 0.5)
				(island_removal_mode 0)
			)
			(polygon
				(pts
					(xy 20.3454 13.6144) (xy 20.3454 13.5636) (xy 20.2946 13.5636) (xy 20.2946 13.6144)
				)
			)
		)
	)
	(footprint ""
		(layer "B.Cu")
		(at 48.237013 8.54202 180)
		(property "Reference" "C40"
			(at 0 0 0)
			(layer "B.SilkS")
			(hide yes)
			(effects
				(font
					(size 1.27 1.27)
				)
				(justify mirror)
			)
		)
		(property "Value" ""
			(at 0 0 0)
			(layer "B.Fab")
			(effects
				(font
					(size 1.27 1.27)
				)
				(justify mirror)
			)
		)
		(duplicate_pad_numbers_are_jumpers no)
		(fp_circle
			(center 0 0)
			(end -0.104648 0)
			(stroke
				(width 0.1016)
				(type default)
			)
			(fill no)
			(layer "B.SilkS")
		)
		(fp_poly
			(pts
				(xy 0.381 -0.889) (xy 0.381 0.889) (xy -0.381 0.889) (xy -0.381 -0.889)
			)
			(stroke
				(width 0)
				(type default)
			)
			(fill no)
			(layer "B.CrtYd")
		)
		(fp_line
			(start 0.508 1.016)
			(end 0.508 -1.016)
			(stroke
				(width 0.0254)
				(type default)
			)
			(layer "B.Fab")
		)
		(fp_line
			(start 0.508 -1.016)
			(end 0.254 -1.016)
			(stroke
				(width 0.0254)
				(type default)
			)
			(layer "B.Fab")
		)
		(fp_line
			(start 0.254 -1.016)
			(end -0.508 -1.016)
			(stroke
				(width 0.0254)
				(type default)
			)
			(layer "B.Fab")
		)
		(fp_line
			(start -0.508 1.016)
			(end 0.508 1.016)
			(stroke
				(width 0.0254)
				(type default)
			)
			(layer "B.Fab")
		)
		(fp_line
			(start -0.508 -1.016)
			(end -0.508 1.016)
			(stroke
				(width 0.0254)
				(type default)
			)
			(layer "B.Fab")
		)
		(pad "1" smd custom
			(at 0 -0.500126)
			(size 0.127 0.127)
			(layers "B.Cu" "B.Mask" "B.Paste")
			(net "VDDA_SERDES")
			(options
				(clearance outline)
				(anchor circle)
			)
			(primitives
				(gr_poly
					(pts
						(xy -0.1778 0.254) (xy 0.1778 0.254) (xy 0.254 0.1778) (xy 0.254 -0.1778) (xy 0.1778 -0.254) (xy -0.1778 -0.254)
						(xy -0.254 -0.1778) (xy -0.254 0.1778)
					)
					(width 0)
					(fill yes)
				)
			)
		)
		(pad "2" smd custom
			(at 0 0.500126)
			(size 0.127 0.127)
			(layers "B.Cu" "B.Mask" "B.Paste")
			(net "GND")
			(options
				(clearance outline)
				(anchor circle)
			)
			(primitives
				(gr_poly
					(pts
						(xy -0.1778 0.254) (xy 0.1778 0.254) (xy 0.254 0.1778) (xy 0.254 -0.1778) (xy 0.1778 -0.254) (xy -0.1778 -0.254)
						(xy -0.254 -0.1778) (xy -0.254 0.1778)
					)
					(width 0)
					(fill yes)
				)
			)
		)
	)
	(footprint ""
		(layer "B.Cu")
		(at 64.236981 13.54201 180)
		(property "Reference" "C194"
			(at 0 0 0)
			(layer "B.SilkS")
			(hide yes)
			(effects
				(font
					(size 1.27 1.27)
				)
				(justify mirror)
			)
		)
		(property "Value" ""
			(at 0 0 0)
			(layer "B.Fab")
			(effects
				(font
					(size 1.27 1.27)
				)
				(justify mirror)
			)
		)
		(duplicate_pad_numbers_are_jumpers no)
		(fp_circle
			(center 0 0)
			(end -0.104648 0)
			(stroke
				(width 0.1016)
				(type default)
			)
			(fill no)
			(layer "B.SilkS")
		)
		(fp_poly
			(pts
				(xy 0.381 -0.889) (xy 0.381 0.889) (xy -0.381 0.889) (xy -0.381 -0.889)
			)
			(stroke
				(width 0)
				(type default)
			)
			(fill no)
			(layer "B.CrtYd")
		)
		(fp_line
			(start 0.508 1.016)
			(end 0.508 -1.016)
			(stroke
				(width 0.0254)
				(type default)
			)
			(layer "B.Fab")
		)
		(fp_line
			(start 0.508 -1.016)
			(end 0.254 -1.016)
			(stroke
				(width 0.0254)
				(type default)
			)
			(layer "B.Fab")
		)
		(fp_line
			(start 0.254 -1.016)
			(end -0.508 -1.016)
			(stroke
				(width 0.0254)
				(type default)
			)
			(layer "B.Fab")
		)
		(fp_line
			(start -0.508 1.016)
			(end 0.508 1.016)
			(stroke
				(width 0.0254)
				(type default)
			)
			(layer "B.Fab")
		)
		(fp_line
			(start -0.508 -1.016)
			(end -0.508 1.016)
			(stroke
				(width 0.0254)
				(type default)
			)
			(layer "B.Fab")
		)
		(pad "1" smd custom
			(at 0 -0.500126)
			(size 0.127 0.127)
			(layers "B.Cu" "B.Mask" "B.Paste")
			(net "DDR_VDDQ")
			(options
				(clearance outline)
				(anchor circle)
			)
			(primitives
				(gr_poly
					(pts
						(xy -0.1778 0.254) (xy 0.1778 0.254) (xy 0.254 0.1778) (xy 0.254 -0.1778) (xy 0.1778 -0.254) (xy -0.1778 -0.254)
						(xy -0.254 -0.1778) (xy -0.254 0.1778)
					)
					(width 0)
					(fill yes)
				)
			)
		)
		(pad "2" smd custom
			(at 0 0.500126)
			(size 0.127 0.127)
			(layers "B.Cu" "B.Mask" "B.Paste")
			(net "GND")
			(options
				(clearance outline)
				(anchor circle)
			)
			(primitives
				(gr_poly
					(pts
						(xy -0.1778 0.254) (xy 0.1778 0.254) (xy 0.254 0.1778) (xy 0.254 -0.1778) (xy 0.1778 -0.254) (xy -0.1778 -0.254)
						(xy -0.254 -0.1778) (xy -0.254 0.1778)
					)
					(width 0)
					(fill yes)
				)
			)
		)
	)
	(footprint ""
		(layer "B.Cu")
		(at 61.236987 33.54197)
		(property "Reference" "C80"
			(at 0.966343 -1.53797 270)
			(unlocked yes)
			(layer "B.SilkS")
			(effects
				(font
					(size 0.7874 0.5842)
					(thickness 0.127)
				)
				(justify mirror)
			)
		)
		(property "Value" ""
			(at 0 0 0)
			(layer "B.Fab")
			(effects
				(font
					(size 1.27 1.27)
				)
				(justify mirror)
			)
		)
		(duplicate_pad_numbers_are_jumpers no)
		(fp_circle
			(center 0 0)
			(end 0.104648 0)
			(stroke
				(width 0.1016)
				(type default)
			)
			(fill no)
			(layer "B.SilkS")
		)
		(fp_poly
			(pts
				(xy 0.381 -0.889) (xy 0.381 0.889) (xy -0.381 0.889) (xy -0.381 -0.889)
			)
			(stroke
				(width 0)
				(type default)
			)
			(fill no)
			(layer "B.CrtYd")
		)
		(fp_line
			(start -0.508 -1.016)
			(end -0.508 1.016)
			(stroke
				(width 0.0254)
				(type default)
			)
			(layer "B.Fab")
		)
		(fp_line
			(start -0.508 1.016)
			(end 0.508 1.016)
			(stroke
				(width 0.0254)
				(type default)
			)
			(layer "B.Fab")
		)
		(fp_line
			(start 0.254 -1.016)
			(end -0.508 -1.016)
			(stroke
				(width 0.0254)
				(type default)
			)
			(layer "B.Fab")
		)
		(fp_line
			(start 0.508 -1.016)
			(end 0.254 -1.016)
			(stroke
				(width 0.0254)
				(type default)
			)
			(layer "B.Fab")
		)
		(fp_line
			(start 0.508 1.016)
			(end 0.508 -1.016)
			(stroke
				(width 0.0254)
				(type default)
			)
			(layer "B.Fab")
		)
		(pad "1" smd custom
			(at 0 -0.500126 180)
			(size 0.127 0.127)
			(layers "B.Cu" "B.Mask" "B.Paste")
			(net "VDD_CORE")
			(options
				(clearance outline)
				(anchor circle)
			)
			(primitives
				(gr_poly
					(pts
						(xy -0.1778 0.254) (xy 0.1778 0.254) (xy 0.254 0.1778) (xy 0.254 -0.1778) (xy 0.1778 -0.254) (xy -0.1778 -0.254)
						(xy -0.254 -0.1778) (xy -0.254 0.1778)
					)
					(width 0)
					(fill yes)
				)
			)
		)
		(pad "2" smd custom
			(at 0 0.500126 180)
			(size 0.127 0.127)
			(layers "B.Cu" "B.Mask" "B.Paste")
			(net "GND")
			(options
				(clearance outline)
				(anchor circle)
			)
			(primitives
				(gr_poly
					(pts
						(xy -0.1778 0.254) (xy 0.1778 0.254) (xy 0.254 0.1778) (xy 0.254 -0.1778) (xy 0.1778 -0.254) (xy -0.1778 -0.254)
						(xy -0.254 -0.1778) (xy -0.254 0.1778)
					)
					(width 0)
					(fill yes)
				)
			)
		)
	)
	(footprint ""
		(layer "B.Cu")
		(at 12.8524 15.8369 -90)
		(property "Reference" "J4"
			(at -15.81023 -6.1976 0)
			(unlocked yes)
			(layer "B.SilkS")
			(effects
				(font
					(size 0.7874 0.5842)
					(thickness 0.127)
				)
				(justify left mirror)
			)
		)
		(property "Value" "VAL"
			(at -0.181864 1.64592 270)
			(unlocked yes)
			(layer "B.Fab")
			(hide yes)
			(effects
				(font
					(size 1.27 0.9652)
					(thickness 0.1524)
				)
				(justify mirror)
			)
		)
		(property "User Part Number" "PN"
			(at -0.181864 -4.06908 270)
			(unlocked yes)
			(layer "Cmts.User")
			(hide yes)
			(effects
				(font
					(size 1.27 0.9652)
					(thickness 0.1524)
				)
				(justify mirror)
			)
		)
		(property "Device Type" "CONM0071"
			(at -0.181864 -2.16408 270)
			(unlocked yes)
			(layer "B.Fab")
			(hide yes)
			(effects
				(font
					(size 1.27 0.9652)
					(thickness 0.1524)
				)
				(justify mirror)
			)
		)
		(property "Tolerance" "TOL"
			(at -0.181864 3.55092 270)
			(unlocked yes)
			(layer "Cmts.User")
			(hide yes)
			(effects
				(font
					(size 1.27 0.9652)
					(thickness 0.1524)
				)
				(justify mirror)
			)
		)
		(duplicate_pad_numbers_are_jumpers no)
		(fp_line
			(start -15.1892 6.1341)
			(end -12.954 6.1341)
			(stroke
				(width 0.1524)
				(type default)
			)
			(layer "B.SilkS")
		)
		(fp_line
			(start 12.954 6.1341)
			(end 15.1892 6.1341)
			(stroke
				(width 0.1524)
				(type default)
			)
			(layer "B.SilkS")
		)
		(fp_line
			(start 15.1892 6.1341)
			(end 15.1892 4.064)
			(stroke
				(width 0.1524)
				(type default)
			)
			(layer "B.SilkS")
		)
		(fp_line
			(start -15.1892 4.064)
			(end -15.1892 6.1341)
			(stroke
				(width 0.1524)
				(type default)
			)
			(layer "B.SilkS")
		)
		(fp_line
			(start -16.2941 0.762)
			(end -15.3035 0.762)
			(stroke
				(width 0.1524)
				(type default)
			)
			(layer "B.SilkS")
		)
		(fp_line
			(start -16.2941 -0.762)
			(end -16.2941 0.762)
			(stroke
				(width 0.1524)
				(type default)
			)
			(layer "B.SilkS")
		)
		(fp_line
			(start -15.3035 -0.762)
			(end -16.2941 -0.762)
			(stroke
				(width 0.1524)
				(type default)
			)
			(layer "B.SilkS")
		)
		(fp_line
			(start 15.1892 -4.064)
			(end 15.1892 -6.1341)
			(stroke
				(width 0.1524)
				(type default)
			)
			(layer "B.SilkS")
		)
		(fp_line
			(start -15.1892 -6.1341)
			(end -15.1892 -4.191)
			(stroke
				(width 0.1524)
				(type default)
			)
			(layer "B.SilkS")
		)
		(fp_line
			(start -12.954 -6.1341)
			(end -15.1892 -6.1341)
			(stroke
				(width 0.1524)
				(type default)
			)
			(layer "B.SilkS")
		)
		(fp_line
			(start 15.1892 -6.1341)
			(end 12.954 -6.1341)
			(stroke
				(width 0.1524)
				(type default)
			)
			(layer "B.SilkS")
		)
		(fp_poly
			(pts
				(xy 2.8321 11.2141) (xy -10.4902 11.2141) (xy -13.8049 7.8994) (xy -15.7099 7.8994) (xy -15.7099 -11.2141)
				(xy 17.8181 -11.2141) (xy 17.8181 4.5974) (xy 2.8321 4.5974)
			)
			(stroke
				(width 0)
				(type default)
			)
			(fill no)
			(layer "B.CrtYd")
		)
		(fp_line
			(start -15.1892 6.1341)
			(end 15.1892 6.1341)
			(stroke
				(width 0.0254)
				(type default)
			)
			(layer "B.Fab")
		)
		(fp_line
			(start 15.1892 6.1341)
			(end 15.1892 -6.1341)
			(stroke
				(width 0.0254)
				(type default)
			)
			(layer "B.Fab")
		)
		(fp_line
			(start -16.2941 0.762)
			(end -15.2019 0.762)
			(stroke
				(width 0.0254)
				(type default)
			)
			(layer "B.Fab")
		)
		(fp_line
			(start -16.2941 -0.762)
			(end -16.2941 0.762)
			(stroke
				(width 0.0254)
				(type default)
			)
			(layer "B.Fab")
		)
		(fp_line
			(start -15.2019 -0.762)
			(end -16.2941 -0.762)
			(stroke
				(width 0.0254)
				(type default)
			)
			(layer "B.Fab")
		)
		(fp_line
			(start -15.1892 -6.1341)
			(end -15.1892 6.1341)
			(stroke
				(width 0.0254)
				(type default)
			)
			(layer "B.Fab")
		)
		(fp_line
			(start 15.1892 -6.1341)
			(end -15.1892 -6.1341)
			(stroke
				(width 0.0254)
				(type default)
			)
			(layer "B.Fab")
		)
		(fp_text user "160"
			(at 16.9291 4.62407 270)
			(unlocked yes)
			(layer "B.SilkS")
			(effects
				(font
					(size 0.7874 0.5842)
					(thickness 0.127)
				)
				(justify mirror)
			)
		)
		(fp_text user "8"
			(at -17.24533 4.572 0)
			(unlocked yes)
			(layer "B.SilkS")
			(effects
				(font
					(size 0.7874 0.5842)
					(thickness 0.127)
				)
				(justify mirror)
			)
		)
		(fp_text user "7"
			(at -17.24533 3.302 0)
			(unlocked yes)
			(layer "B.SilkS")
			(effects
				(font
					(size 0.7874 0.5842)
					(thickness 0.127)
				)
				(justify mirror)
			)
		)
		(fp_text user "159"
			(at 17.145 3.20167 270)
			(unlocked yes)
			(layer "B.SilkS")
			(effects
				(font
					(size 0.7874 0.5842)
					(thickness 0.127)
				)
				(justify mirror)
			)
		)
		(fp_text user "6"
			(at -17.24533 2.040382 0)
			(unlocked yes)
			(layer "B.SilkS")
			(effects
				(font
					(size 0.7874 0.5842)
					(thickness 0.127)
				)
				(justify mirror)
			)
		)
		(fp_text user "158"
			(at 17.145 1.940052 270)
			(unlocked yes)
			(layer "B.SilkS")
			(effects
				(font
					(size 0.7874 0.5842)
					(thickness 0.127)
				)
				(justify mirror)
			)
		)
		(fp_text user "157"
			(at 17.0561 0.94107 270)
			(unlocked yes)
			(layer "B.SilkS")
			(effects
				(font
					(size 0.7874 0.5842)
					(thickness 0.127)
				)
				(justify mirror)
			)
		)
		(fp_text user "5"
			(at -17.24533 0.762 0)
			(unlocked yes)
			(layer "B.SilkS")
			(effects
				(font
					(size 0.7874 0.5842)
					(thickness 0.127)
				)
				(justify mirror)
			)
		)
		(fp_text user "4"
			(at -17.24533 -0.508 0)
			(unlocked yes)
			(layer "B.SilkS")
			(effects
				(font
					(size 0.7874 0.5842)
					(thickness 0.127)
				)
				(justify mirror)
			)
		)
		(fp_text user "156"
			(at 17.145 -0.60833 270)
			(unlocked yes)
			(layer "B.SilkS")
			(effects
				(font
					(size 0.7874 0.5842)
					(thickness 0.127)
				)
				(justify mirror)
			)
		)
		(fp_text user "3"
			(at -17.24533 -1.778 0)
			(unlocked yes)
			(layer "B.SilkS")
			(effects
				(font
					(size 0.7874 0.5842)
					(thickness 0.127)
				)
				(justify mirror)
			)
		)
		(fp_text user "155"
			(at 18.923 -1.87833 270)
			(unlocked yes)
			(layer "B.SilkS")
			(effects
				(font
					(size 0.7874 0.5842)
					(thickness 0.127)
				)
				(justify mirror)
			)
		)
		(fp_text user "2"
			(at -17.24533 -3.048 0)
			(unlocked yes)
			(layer "B.SilkS")
			(effects
				(font
					(size 0.7874 0.5842)
					(thickness 0.127)
				)
				(justify mirror)
			)
		)
		(fp_text user "154"
			(at 18.923 -3.14833 270)
			(unlocked yes)
			(layer "B.SilkS")
			(effects
				(font
					(size 0.7874 0.5842)
					(thickness 0.127)
				)
				(justify mirror)
			)
		)
		(fp_text user "1"
			(at -17.24533 -4.309618 0)
			(unlocked yes)
			(layer "B.SilkS")
			(effects
				(font
					(size 0.7874 0.5842)
					(thickness 0.127)
				)
				(justify mirror)
			)
		)
		(fp_text user "153"
			(at 18.923 -4.409948 270)
			(unlocked yes)
			(layer "B.SilkS")
			(effects
				(font
					(size 0.7874 0.5842)
					(thickness 0.127)
				)
				(justify mirror)
			)
		)
		(fp_text user "8"
			(at -16.99133 4.572 0)
			(unlocked yes)
			(layer "B.Fab")
			(effects
				(font
					(size 0.7874 0.5842)
					(thickness 0.127)
				)
				(justify mirror)
			)
		)
		(fp_text user "160"
			(at 16.51 4.47167 270)
			(unlocked yes)
			(layer "B.Fab")
			(effects
				(font
					(size 0.7874 0.5842)
					(thickness 0.127)
				)
				(justify mirror)
			)
		)
		(fp_text user "7"
			(at -16.99133 3.302 0)
			(unlocked yes)
			(layer "B.Fab")
			(effects
				(font
					(size 0.7874 0.5842)
					(thickness 0.127)
				)
				(justify mirror)
			)
		)
		(fp_text user "159"
			(at 16.51 3.20167 270)
			(unlocked yes)
			(layer "B.Fab")
			(effects
				(font
					(size 0.7874 0.5842)
					(thickness 0.127)
				)
				(justify mirror)
			)
		)
		(fp_text user "6"
			(at -16.99133 2.040382 0)
			(unlocked yes)
			(layer "B.Fab")
			(effects
				(font
					(size 0.7874 0.5842)
					(thickness 0.127)
				)
				(justify mirror)
			)
		)
		(fp_text user "158"
			(at 16.51 1.940052 270)
			(unlocked yes)
			(layer "B.Fab")
			(effects
				(font
					(size 0.7874 0.5842)
					(thickness 0.127)
				)
				(justify mirror)
			)
		)
		(fp_text user "5"
			(at -16.99133 0.762 0)
			(unlocked yes)
			(layer "B.Fab")
			(effects
				(font
					(size 0.7874 0.5842)
					(thickness 0.127)
				)
				(justify mirror)
			)
		)
		(fp_text user "157"
			(at 16.51 0.66167 270)
			(unlocked yes)
			(layer "B.Fab")
			(effects
				(font
					(size 0.7874 0.5842)
					(thickness 0.127)
				)
				(justify mirror)
			)
		)
		(fp_text user "4"
			(at -16.99133 -0.508 0)
			(unlocked yes)
			(layer "B.Fab")
			(effects
				(font
					(size 0.7874 0.5842)
					(thickness 0.127)
				)
				(justify mirror)
			)
		)
		(fp_text user "156"
			(at 16.51 -0.60833 270)
			(unlocked yes)
			(layer "B.Fab")
			(effects
				(font
					(size 0.7874 0.5842)
					(thickness 0.127)
				)
				(justify mirror)
			)
		)
		(fp_text user "3"
			(at -16.99133 -1.778 0)
			(unlocked yes)
			(layer "B.Fab")
			(effects
				(font
					(size 0.7874 0.5842)
					(thickness 0.127)
				)
				(justify mirror)
			)
		)
		(fp_text user "155"
			(at 16.51 -1.87833 270)
			(unlocked yes)
			(layer "B.Fab")
			(effects
				(font
					(size 0.7874 0.5842)
					(thickness 0.127)
				)
				(justify mirror)
			)
		)
		(fp_text user "2"
			(at -16.99133 -3.048 0)
			(unlocked yes)
			(layer "B.Fab")
			(effects
				(font
					(size 0.7874 0.5842)
					(thickness 0.127)
				)
				(justify mirror)
			)
		)
		(fp_text user "154"
			(at 16.51 -3.14833 270)
			(unlocked yes)
			(layer "B.Fab")
			(effects
				(font
					(size 0.7874 0.5842)
					(thickness 0.127)
				)
				(justify mirror)
			)
		)
		(fp_text user "1"
			(at -16.99133 -4.309618 0)
			(unlocked yes)
			(layer "B.Fab")
			(effects
				(font
					(size 0.7874 0.5842)
					(thickness 0.127)
				)
				(justify mirror)
			)
		)
		(fp_text user "153"
			(at 16.51 -4.409948 270)
			(unlocked yes)
			(layer "B.Fab")
			(effects
				(font
					(size 0.7874 0.5842)
					(thickness 0.127)
				)
				(justify mirror)
			)
		)
		(pad "" np_thru_hole circle
			(at -14.4907 0 90)
			(size 1.778 1.778)
			(drill 1.27)
			(layers "*.Cu" "*.Mask")
			(padstack
				(mode front_inner_back)
				(layer "Inner"
					(shape circle)
					(size 1.778 1.778)
					(clearance 0.127)
				)
				(layer "B.Cu"
					(shape circle)
					(size 1.778 1.778)
					(thermal_gap 0.127)
				)
			)
		)
		(pad "" np_thru_hole circle
			(at 14.4907 3.048 90)
			(size 1.778 1.778)
			(drill 1.27)
			(layers "*.Cu" "*.Mask")
			(padstack
				(mode front_inner_back)
				(layer "Inner"
					(shape circle)
					(size 1.778 1.778)
					(clearance 0.127)
				)
				(layer "B.Cu"
					(shape circle)
					(size 1.778 1.778)
					(thermal_gap 0.127)
				)
			)
		)
		(pad "1" smd circle
			(at -12.065 -4.445 90)
			(size 0.635 0.635)
			(layers "B.Cu" "B.Mask" "B.Paste")
			(net "GND")
		)
		(pad "2" smd circle
			(at -12.065 -3.175 90)
			(size 0.635 0.635)
			(layers "B.Cu" "B.Mask" "B.Paste")
			(net "PCIE0_RST_L")
		)
		(pad "3" smd circle
			(at -12.065 -1.905 90)
			(size 0.635 0.635)
			(layers "B.Cu" "B.Mask" "B.Paste")
			(net "GND")
		)
		(pad "4" smd circle
			(at -12.065 -0.635 90)
			(size 0.635 0.635)
			(layers "B.Cu" "B.Mask" "B.Paste")
			(net "PCIE0_WAKE_L")
		)
		(pad "5" smd circle
			(at -12.065 0.635 90)
			(size 0.635 0.635)
			(layers "B.Cu" "B.Mask" "B.Paste")
			(net "CPLD_NIC_MEZZ_ID0")
		)
		(pad "6" smd circle
			(at -12.065 1.905 90)
			(size 0.635 0.635)
			(layers "B.Cu" "B.Mask" "B.Paste")
			(net "SMBUS_ALERT_L")
		)
		(pad "7" smd circle
			(at -12.065 3.175 90)
			(size 0.635 0.635)
			(layers "B.Cu" "B.Mask" "B.Paste")
			(net "GND")
		)
		(pad "8" smd circle
			(at -12.065 4.445 90)
			(size 0.635 0.635)
			(layers "B.Cu" "B.Mask" "B.Paste")
			(net "PCIE0_REFCLK_P")
		)
		(pad "9" smd circle
			(at -10.795 -4.445 90)
			(size 0.635 0.635)
			(layers "B.Cu" "B.Mask" "B.Paste")
			(net "NFP_PCIE0_PET0_P")
		)
		(pad "10" smd circle
			(at -10.795 -3.175 90)
			(size 0.635 0.635)
			(layers "B.Cu" "B.Mask" "B.Paste")
			(net "GND")
		)
		(pad "11" smd circle
			(at -10.795 -1.905 90)
			(size 0.635 0.635)
			(layers "B.Cu" "B.Mask" "B.Paste")
			(net "NFP_PCIE0_PER7_P")
		)
		(pad "12" smd circle
			(at -10.795 -0.635 90)
			(size 0.635 0.635)
			(layers "B.Cu" "B.Mask" "B.Paste")
			(net "GND")
		)
		(pad "13" smd circle
			(at -10.795 0.635 90)
			(size 0.635 0.635)
			(layers "B.Cu" "B.Mask" "B.Paste")
			(net "SMBUS_SCL")
		)
		(pad "14" smd circle
			(at -10.795 1.905 90)
			(size 0.635 0.635)
			(layers "B.Cu" "B.Mask" "B.Paste")
			(net "NWK1_MOD_PRES_L")
		)
		(pad "15" smd circle
			(at -10.795 3.175 90)
			(size 0.635 0.635)
			(layers "B.Cu" "B.Mask" "B.Paste")
			(net "GND")
		)
		(pad "16" smd circle
			(at -10.795 4.445 90)
			(size 0.635 0.635)
			(layers "B.Cu" "B.Mask" "B.Paste")
			(net "PCIE0_REFCLK_N")
		)
		(pad "17" smd circle
			(at -9.525 -4.445 90)
			(size 0.635 0.635)
			(layers "B.Cu" "B.Mask" "B.Paste")
			(net "NFP_PCIE0_PET0_N")
		)
		(pad "18" smd circle
			(at -9.525 -3.175 90)
			(size 0.635 0.635)
			(layers "B.Cu" "B.Mask" "B.Paste")
			(net "GND")
		)
		(pad "19" smd circle
			(at -9.525 -1.905 90)
			(size 0.635 0.635)
			(layers "B.Cu" "B.Mask" "B.Paste")
			(net "NFP_PCIE0_PER7_N")
		)
		(pad "20" smd circle
			(at -9.525 -0.635 90)
			(size 0.635 0.635)
			(layers "B.Cu" "B.Mask" "B.Paste")
			(net "GND")
		)
		(pad "21" smd circle
			(at -9.525 0.635 90)
			(size 0.635 0.635)
			(layers "B.Cu" "B.Mask" "B.Paste")
			(net "SMBUS_SDA")
		)
		(pad "22" smd circle
			(at -9.525 1.905 90)
			(size 0.635 0.635)
			(layers "B.Cu" "B.Mask" "B.Paste")
			(net "GND")
		)
		(pad "23" smd circle
			(at -9.525 3.175 90)
			(size 0.635 0.635)
			(layers "B.Cu" "B.Mask" "B.Paste")
			(net "GND")
		)
		(pad "24" smd circle
			(at -9.525 4.445 90)
			(size 0.635 0.635)
			(layers "B.Cu" "B.Mask" "B.Paste")
			(net "GND")
		)
		(pad "25" smd circle
			(at -8.255 -4.445 90)
			(size 0.635 0.635)
			(layers "B.Cu" "B.Mask" "B.Paste")
			(net "GND")
		)
		(pad "26" smd circle
			(at -8.255 -3.175 90)
			(size 0.635 0.635)
			(layers "B.Cu" "B.Mask" "B.Paste")
			(net "NFP_PCIE0_PET1_P")
		)
		(pad "27" smd circle
			(at -8.255 -1.905 90)
			(size 0.635 0.635)
			(layers "B.Cu" "B.Mask" "B.Paste")
			(net "GND")
		)
		(pad "28" smd circle
			(at -8.255 -0.635 90)
			(size 0.635 0.635)
			(layers "B.Cu" "B.Mask" "B.Paste")
			(net "NFP_PCIE0_PER6_P")
		)
		(pad "29" smd circle
			(at -8.255 0.635 90)
			(size 0.635 0.635)
			(layers "B.Cu" "B.Mask" "B.Paste")
			(net "GND")
		)
		(pad "30" smd circle
			(at -8.255 1.905 90)
			(size 0.635 0.635)
			(layers "B.Cu" "B.Mask" "B.Paste")
			(net "_NC_NCSI_TXD_0")
		)
		(pad "31" smd circle
			(at -8.255 3.175 90)
			(size 0.635 0.635)
			(layers "B.Cu" "B.Mask" "B.Paste")
			(net "GND")
		)
		(pad "32" smd circle
			(at -8.255 4.445 90)
			(size 0.635 0.635)
			(layers "B.Cu" "B.Mask" "B.Paste")
			(net "NFP_SERDES1_TX0_P")
		)
		(pad "33" smd circle
			(at -6.985 -4.445 90)
			(size 0.635 0.635)
			(layers "B.Cu" "B.Mask" "B.Paste")
			(net "GND")
		)
		(pad "34" smd circle
			(at -6.985 -3.175 90)
			(size 0.635 0.635)
			(layers "B.Cu" "B.Mask" "B.Paste")
			(net "NFP_PCIE0_PET1_N")
		)
		(pad "35" smd circle
			(at -6.985 -1.905 90)
			(size 0.635 0.635)
			(layers "B.Cu" "B.Mask" "B.Paste")
			(net "GND")
		)
		(pad "36" smd circle
			(at -6.985 -0.635 90)
			(size 0.635 0.635)
			(layers "B.Cu" "B.Mask" "B.Paste")
			(net "NFP_PCIE0_PER6_N")
		)
		(pad "37" smd circle
			(at -6.985 0.635 90)
			(size 0.635 0.635)
			(layers "B.Cu" "B.Mask" "B.Paste")
			(net "GND")
		)
		(pad "38" smd circle
			(at -6.985 1.905 90)
			(size 0.635 0.635)
			(layers "B.Cu" "B.Mask" "B.Paste")
			(net "_NC_NCSI_TXD_1")
		)
		(pad "39" smd circle
			(at -6.985 3.175 90)
			(size 0.635 0.635)
			(layers "B.Cu" "B.Mask" "B.Paste")
			(net "GND")
		)
		(pad "40" smd circle
			(at -6.985 4.445 90)
			(size 0.635 0.635)
			(layers "B.Cu" "B.Mask" "B.Paste")
			(net "NFP_SERDES1_TX0_N")
		)
		(pad "41" smd circle
			(at -5.715 -4.445 90)
			(size 0.635 0.635)
			(layers "B.Cu" "B.Mask" "B.Paste")
			(net "NFP_PCIE0_PET2_P")
		)
		(pad "42" smd circle
			(at -5.715 -3.175 90)
			(size 0.635 0.635)
			(layers "B.Cu" "B.Mask" "B.Paste")
			(net "GND")
		)
		(pad "43" smd circle
			(at -5.715 -1.905 90)
			(size 0.635 0.635)
			(layers "B.Cu" "B.Mask" "B.Paste")
			(net "NFP_PCIE0_PER5_P")
		)
		(pad "44" smd circle
			(at -5.715 -0.635 90)
			(size 0.635 0.635)
			(layers "B.Cu" "B.Mask" "B.Paste")
			(net "GND")
		)
		(pad "45" smd circle
			(at -5.715 0.635 90)
			(size 0.635 0.635)
			(layers "B.Cu" "B.Mask" "B.Paste")
			(net "_NC_NCSI_RXD_0")
		)
		(pad "46" smd circle
			(at -5.715 1.905 90)
			(size 0.635 0.635)
			(layers "B.Cu" "B.Mask" "B.Paste")
			(net "GND")
		)
		(pad "47" smd circle
			(at -5.715 3.175 90)
			(size 0.635 0.635)
			(layers "B.Cu" "B.Mask" "B.Paste")
			(net "NFP_SERDES1_TX1_P")
		)
		(pad "48" smd circle
			(at -5.715 4.445 90)
			(size 0.635 0.635)
			(layers "B.Cu" "B.Mask" "B.Paste")
			(net "GND")
		)
		(pad "49" smd circle
			(at -4.445 -4.445 90)
			(size 0.635 0.635)
			(layers "B.Cu" "B.Mask" "B.Paste")
			(net "NFP_PCIE0_PET2_N")
		)
		(pad "50" smd circle
			(at -4.445 -3.175 90)
			(size 0.635 0.635)
			(layers "B.Cu" "B.Mask" "B.Paste")
			(net "GND")
		)
		(pad "51" smd circle
			(at -4.445 -1.905 90)
			(size 0.635 0.635)
			(layers "B.Cu" "B.Mask" "B.Paste")
			(net "NFP_PCIE0_PER5_N")
		)
		(pad "52" smd circle
			(at -4.445 -0.635 90)
			(size 0.635 0.635)
			(layers "B.Cu" "B.Mask" "B.Paste")
			(net "GND")
		)
		(pad "53" smd circle
			(at -4.445 0.635 90)
			(size 0.635 0.635)
			(layers "B.Cu" "B.Mask" "B.Paste")
			(net "_NC_NCSI_RXD_1")
		)
		(pad "54" smd circle
			(at -4.445 1.905 90)
			(size 0.635 0.635)
			(layers "B.Cu" "B.Mask" "B.Paste")
			(net "GND")
		)
		(pad "55" smd circle
			(at -4.445 3.175 90)
			(size 0.635 0.635)
			(layers "B.Cu" "B.Mask" "B.Paste")
			(net "NFP_SERDES1_TX1_N")
		)
		(pad "56" smd circle
			(at -4.445 4.445 90)
			(size 0.635 0.635)
			(layers "B.Cu" "B.Mask" "B.Paste")
			(net "GND")
		)
		(pad "57" smd circle
			(at -3.175 -4.445 90)
			(size 0.635 0.635)
			(layers "B.Cu" "B.Mask" "B.Paste")
			(net "GND")
		)
		(pad "58" smd circle
			(at -3.175 -3.175 90)
			(size 0.635 0.635)
			(layers "B.Cu" "B.Mask" "B.Paste")
			(net "NFP_PCIE0_PET3_P")
		)
		(pad "59" smd circle
			(at -3.175 -1.905 90)
			(size 0.635 0.635)
			(layers "B.Cu" "B.Mask" "B.Paste")
			(net "GND")
		)
		(pad "60" smd circle
			(at -3.175 -0.635 90)
			(size 0.635 0.635)
			(layers "B.Cu" "B.Mask" "B.Paste")
			(net "NFP_PCIE0_PER4_P")
		)
		(pad "61" smd circle
			(at -3.175 0.635 90)
			(size 0.635 0.635)
			(layers "B.Cu" "B.Mask" "B.Paste")
			(net "GND")
		)
		(pad "62" smd circle
			(at -3.175 1.905 90)
			(size 0.635 0.635)
			(layers "B.Cu" "B.Mask" "B.Paste")
			(net "_NC_NCSI_TX_EN")
		)
		(pad "63" smd circle
			(at -3.175 3.175 90)
			(size 0.635 0.635)
			(layers "B.Cu" "B.Mask" "B.Paste")
			(net "GND")
		)
		(pad "64" smd circle
			(at -3.175 4.445 90)
			(size 0.635 0.635)
			(layers "B.Cu" "B.Mask" "B.Paste")
			(net "NFP_SERDES1_TX2_P")
		)
		(pad "65" smd circle
			(at -1.905 -4.445 90)
			(size 0.635 0.635)
			(layers "B.Cu" "B.Mask" "B.Paste")
			(net "GND")
		)
		(pad "66" smd circle
			(at -1.905 -3.175 90)
			(size 0.635 0.635)
			(layers "B.Cu" "B.Mask" "B.Paste")
			(net "NFP_PCIE0_PET3_N")
		)
		(pad "67" smd circle
			(at -1.905 -1.905 90)
			(size 0.635 0.635)
			(layers "B.Cu" "B.Mask" "B.Paste")
			(net "GND")
		)
		(pad "68" smd circle
			(at -1.905 -0.635 90)
			(size 0.635 0.635)
			(layers "B.Cu" "B.Mask" "B.Paste")
			(net "NFP_PCIE0_PER4_N")
		)
		(pad "69" smd circle
			(at -1.905 0.635 90)
			(size 0.635 0.635)
			(layers "B.Cu" "B.Mask" "B.Paste")
			(net "GND")
		)
		(pad "70" smd circle
			(at -1.905 1.905 90)
			(size 0.635 0.635)
			(layers "B.Cu" "B.Mask" "B.Paste")
			(net "_NC_NCSI_CLK_IN")
		)
		(pad "71" smd circle
			(at -1.905 3.175 90)
			(size 0.635 0.635)
			(layers "B.Cu" "B.Mask" "B.Paste")
			(net "GND")
		)
		(pad "72" smd circle
			(at -1.905 4.445 90)
			(size 0.635 0.635)
			(layers "B.Cu" "B.Mask" "B.Paste")
			(net "NFP_SERDES1_TX2_N")
		)
		(pad "73" smd circle
			(at -0.635 -4.445 90)
			(size 0.635 0.635)
			(layers "B.Cu" "B.Mask" "B.Paste")
			(net "NFP_PCIE0_PET4_P")
		)
		(pad "74" smd circle
			(at -0.635 -3.175 90)
			(size 0.635 0.635)
			(layers "B.Cu" "B.Mask" "B.Paste")
			(net "GND")
		)
		(pad "75" smd circle
			(at -0.635 -1.905 90)
			(size 0.635 0.635)
			(layers "B.Cu" "B.Mask" "B.Paste")
			(net "NFP_PCIE0_PER0_P")
		)
		(pad "76" smd circle
			(at -0.635 -0.635 90)
			(size 0.635 0.635)
			(layers "B.Cu" "B.Mask" "B.Paste")
			(net "GND")
		)
		(pad "77" smd circle
			(at -0.635 0.635 90)
			(size 0.635 0.635)
			(layers "B.Cu" "B.Mask" "B.Paste")
			(net "_NC_NCSI_CRS_DV")
		)
		(pad "78" smd circle
			(at -0.635 1.905 90)
			(size 0.635 0.635)
			(layers "B.Cu" "B.Mask" "B.Paste")
			(net "GND")
		)
		(pad "79" smd circle
			(at -0.635 3.175 90)
			(size 0.635 0.635)
			(layers "B.Cu" "B.Mask" "B.Paste")
			(net "NFP_SERDES1_TX3_P")
		)
		(pad "80" smd circle
			(at -0.635 4.445 90)
			(size 0.635 0.635)
			(layers "B.Cu" "B.Mask" "B.Paste")
			(net "GND")
		)
		(pad "81" smd circle
			(at 0.635 -4.445 90)
			(size 0.635 0.635)
			(layers "B.Cu" "B.Mask" "B.Paste")
			(net "NFP_PCIE0_PET4_N")
		)
		(pad "82" smd circle
			(at 0.635 -3.175 90)
			(size 0.635 0.635)
			(layers "B.Cu" "B.Mask" "B.Paste")
			(net "GND")
		)
		(pad "83" smd circle
			(at 0.635 -1.905 90)
			(size 0.635 0.635)
			(layers "B.Cu" "B.Mask" "B.Paste")
			(net "NFP_PCIE0_PER0_N")
		)
		(pad "84" smd circle
			(at 0.635 -0.635 90)
			(size 0.635 0.635)
			(layers "B.Cu" "B.Mask" "B.Paste")
			(net "GND")
		)
		(pad "85" smd circle
			(at 0.635 0.635 90)
			(size 0.635 0.635)
			(layers "B.Cu" "B.Mask" "B.Paste")
			(net "_NC_NCSI_RX_ER")
		)
		(pad "86" smd circle
			(at 0.635 1.905 90)
			(size 0.635 0.635)
			(layers "B.Cu" "B.Mask" "B.Paste")
			(net "GND")
		)
		(pad "87" smd circle
			(at 0.635 3.175 90)
			(size 0.635 0.635)
			(layers "B.Cu" "B.Mask" "B.Paste")
			(net "NFP_SERDES1_TX3_N")
		)
		(pad "88" smd circle
			(at 0.635 4.445 90)
			(size 0.635 0.635)
			(layers "B.Cu" "B.Mask" "B.Paste")
			(net "GND")
		)
		(pad "89" smd circle
			(at 1.905 -4.445 90)
			(size 0.635 0.635)
			(layers "B.Cu" "B.Mask" "B.Paste")
			(net "GND")
		)
		(pad "90" smd circle
			(at 1.905 -3.175 90)
			(size 0.635 0.635)
			(layers "B.Cu" "B.Mask" "B.Paste")
			(net "NFP_PCIE0_PET5_P")
		)
		(pad "91" smd circle
			(at 1.905 -1.905 90)
			(size 0.635 0.635)
			(layers "B.Cu" "B.Mask" "B.Paste")
			(net "GND")
		)
		(pad "92" smd circle
			(at 1.905 -0.635 90)
			(size 0.635 0.635)
			(layers "B.Cu" "B.Mask" "B.Paste")
			(net "NFP_PCIE0_PER1_P")
		)
		(pad "93" smd circle
			(at 1.905 0.635 90)
			(size 0.635 0.635)
			(layers "B.Cu" "B.Mask" "B.Paste")
			(net "GND")
		)
		(pad "94" smd circle
			(at 1.905 1.905 90)
			(size 0.635 0.635)
			(layers "B.Cu" "B.Mask" "B.Paste")
			(net "NWK0_LED_ACT_G_L")
		)
		(pad "95" smd circle
			(at 1.905 3.175 90)
			(size 0.635 0.635)
			(layers "B.Cu" "B.Mask" "B.Paste")
			(net "GND")
		)
		(pad "96" smd circle
			(at 1.905 4.445 90)
			(size 0.635 0.635)
			(layers "B.Cu" "B.Mask" "B.Paste")
			(net "NFP_SERDES1_RX0_P")
		)
		(pad "97" smd circle
			(at 3.175 -4.445 90)
			(size 0.635 0.635)
			(layers "B.Cu" "B.Mask" "B.Paste")
			(net "GND")
		)
		(pad "98" smd circle
			(at 3.175 -3.175 90)
			(size 0.635 0.635)
			(layers "B.Cu" "B.Mask" "B.Paste")
			(net "NFP_PCIE0_PET5_N")
		)
		(pad "99" smd circle
			(at 3.175 -1.905 90)
			(size 0.635 0.635)
			(layers "B.Cu" "B.Mask" "B.Paste")
			(net "GND")
		)
		(pad "100" smd circle
			(at 3.175 -0.635 90)
			(size 0.635 0.635)
			(layers "B.Cu" "B.Mask" "B.Paste")
			(net "NFP_PCIE0_PER1_N")
		)
		(pad "101" smd circle
			(at 3.175 0.635 90)
			(size 0.635 0.635)
			(layers "B.Cu" "B.Mask" "B.Paste")
			(net "GND")
		)
		(pad "102" smd circle
			(at 3.175 1.905 90)
			(size 0.635 0.635)
			(layers "B.Cu" "B.Mask" "B.Paste")
			(net "NWK0_LED_LINK_G_L")
		)
		(pad "103" smd circle
			(at 3.175 3.175 90)
			(size 0.635 0.635)
			(layers "B.Cu" "B.Mask" "B.Paste")
			(net "GND")
		)
		(pad "104" smd circle
			(at 3.175 4.445 90)
			(size 0.635 0.635)
			(layers "B.Cu" "B.Mask" "B.Paste")
			(net "NFP_SERDES1_RX0_N")
		)
		(pad "105" smd circle
			(at 4.445 -4.445 90)
			(size 0.635 0.635)
			(layers "B.Cu" "B.Mask" "B.Paste")
			(net "NFP_PCIE0_PET6_P")
		)
		(pad "106" smd circle
			(at 4.445 -3.175 90)
			(size 0.635 0.635)
			(layers "B.Cu" "B.Mask" "B.Paste")
			(net "GND")
		)
		(pad "107" smd circle
			(at 4.445 -1.905 90)
			(size 0.635 0.635)
			(layers "B.Cu" "B.Mask" "B.Paste")
			(net "NFP_PCIE0_PER2_P")
		)
		(pad "108" smd circle
			(at 4.445 -0.635 90)
			(size 0.635 0.635)
			(layers "B.Cu" "B.Mask" "B.Paste")
			(net "GND")
		)
		(pad "109" smd circle
			(at 4.445 0.635 90)
			(size 0.635 0.635)
			(layers "B.Cu" "B.Mask" "B.Paste")
			(net "NWK1_LED_ACT_G_L")
		)
		(pad "110" smd circle
			(at 4.445 1.905 90)
			(size 0.635 0.635)
			(layers "B.Cu" "B.Mask" "B.Paste")
			(net "GND")
		)
		(pad "111" smd circle
			(at 4.445 3.175 90)
			(size 0.635 0.635)
			(layers "B.Cu" "B.Mask" "B.Paste")
			(net "NFP_SERDES1_RX1_N")
		)
		(pad "112" smd circle
			(at 4.445 4.445 90)
			(size 0.635 0.635)
			(layers "B.Cu" "B.Mask" "B.Paste")
			(net "GND")
		)
		(pad "113" smd circle
			(at 5.715 -4.445 90)
			(size 0.635 0.635)
			(layers "B.Cu" "B.Mask" "B.Paste")
			(net "NFP_PCIE0_PET6_N")
		)
		(pad "114" smd circle
			(at 5.715 -3.175 90)
			(size 0.635 0.635)
			(layers "B.Cu" "B.Mask" "B.Paste")
			(net "GND")
		)
		(pad "115" smd circle
			(at 5.715 -1.905 90)
			(size 0.635 0.635)
			(layers "B.Cu" "B.Mask" "B.Paste")
			(net "NFP_PCIE0_PER2_N")
		)
		(pad "116" smd circle
			(at 5.715 -0.635 90)
			(size 0.635 0.635)
			(layers "B.Cu" "B.Mask" "B.Paste")
			(net "GND")
		)
		(pad "117" smd circle
			(at 5.715 0.635 90)
			(size 0.635 0.635)
			(layers "B.Cu" "B.Mask" "B.Paste")
			(net "NWK1_LED_LINK_G_L")
		)
		(pad "118" smd circle
			(at 5.715 1.905 90)
			(size 0.635 0.635)
			(layers "B.Cu" "B.Mask" "B.Paste")
			(net "GND")
		)
		(pad "119" smd circle
			(at 5.715 3.175 90)
			(size 0.635 0.635)
			(layers "B.Cu" "B.Mask" "B.Paste")
			(net "NFP_SERDES1_RX1_P")
		)
		(pad "120" smd circle
			(at 5.715 4.445 90)
			(size 0.635 0.635)
			(layers "B.Cu" "B.Mask" "B.Paste")
			(net "GND")
		)
		(pad "121" smd circle
			(at 6.985 -4.445 90)
			(size 0.635 0.635)
			(layers "B.Cu" "B.Mask" "B.Paste")
			(net "GND")
		)
		(pad "122" smd circle
			(at 6.985 -3.175 90)
			(size 0.635 0.635)
			(layers "B.Cu" "B.Mask" "B.Paste")
			(net "NFP_PCIE0_PET7_P")
		)
		(pad "123" smd circle
			(at 6.985 -1.905 90)
			(size 0.635 0.635)
			(layers "B.Cu" "B.Mask" "B.Paste")
			(net "GND")
		)
		(pad "124" smd circle
			(at 6.985 -0.635 90)
			(size 0.635 0.635)
			(layers "B.Cu" "B.Mask" "B.Paste")
			(net "NFP_PCIE0_PER3_P")
		)
		(pad "125" smd circle
			(at 6.985 0.635 90)
			(size 0.635 0.635)
			(layers "B.Cu" "B.Mask" "B.Paste")
			(net "GND")
		)
		(pad "126" smd circle
			(at 6.985 1.905 90)
			(size 0.635 0.635)
			(layers "B.Cu" "B.Mask" "B.Paste")
			(net "NFP_SERDES0_TX0_P")
		)
		(pad "127" smd circle
			(at 6.985 3.175 90)
			(size 0.635 0.635)
			(layers "B.Cu" "B.Mask" "B.Paste")
			(net "GND")
		)
		(pad "128" smd circle
			(at 6.985 4.445 90)
			(size 0.635 0.635)
			(layers "B.Cu" "B.Mask" "B.Paste")
			(net "NFP_SERDES1_RX2_N")
		)
		(pad "129" smd circle
			(at 8.255 -4.445 90)
			(size 0.635 0.635)
			(layers "B.Cu" "B.Mask" "B.Paste")
			(net "NWK1_I2C_SDA")
		)
		(pad "130" smd circle
			(at 8.255 -3.175 90)
			(size 0.635 0.635)
			(layers "B.Cu" "B.Mask" "B.Paste")
			(net "NFP_PCIE0_PET7_N")
		)
		(pad "131" smd circle
			(at 8.255 -1.905 90)
			(size 0.635 0.635)
			(layers "B.Cu" "B.Mask" "B.Paste")
			(net "GND")
		)
		(pad "132" smd circle
			(at 8.255 -0.635 90)
			(size 0.635 0.635)
			(layers "B.Cu" "B.Mask" "B.Paste")
			(net "NFP_PCIE0_PER3_N")
		)
		(pad "133" smd circle
			(at 8.255 0.635 90)
			(size 0.635 0.635)
			(layers "B.Cu" "B.Mask" "B.Paste")
			(net "GND")
		)
		(pad "134" smd circle
			(at 8.255 1.905 90)
			(size 0.635 0.635)
			(layers "B.Cu" "B.Mask" "B.Paste")
			(net "NFP_SERDES0_TX0_N")
		)
		(pad "135" smd circle
			(at 8.255 3.175 90)
			(size 0.635 0.635)
			(layers "B.Cu" "B.Mask" "B.Paste")
			(net "GND")
		)
		(pad "136" smd circle
			(at 8.255 4.445 90)
			(size 0.635 0.635)
			(layers "B.Cu" "B.Mask" "B.Paste")
			(net "NFP_SERDES1_RX2_P")
		)
		(pad "137" smd circle
			(at 9.525 -4.445 90)
			(size 0.635 0.635)
			(layers "B.Cu" "B.Mask" "B.Paste")
			(net "NWK1_I2C_SCL")
		)
		(pad "138" smd circle
			(at 9.525 -3.175 90)
			(size 0.635 0.635)
			(layers "B.Cu" "B.Mask" "B.Paste")
			(net "GND")
		)
		(pad "139" smd circle
			(at 9.525 -1.905 90)
			(size 0.635 0.635)
			(layers "B.Cu" "B.Mask" "B.Paste")
			(net "CPLD_NIC_MEZZ_ID1")
		)
		(pad "140" smd circle
			(at 9.525 -0.635 90)
			(size 0.635 0.635)
			(layers "B.Cu" "B.Mask" "B.Paste")
			(net "GND")
		)
		(pad "141" smd circle
			(at 9.525 0.635 90)
			(size 0.635 0.635)
			(layers "B.Cu" "B.Mask" "B.Paste")
			(net "NFP_SERDES0_RX0_P")
		)
		(pad "142" smd circle
			(at 9.525 1.905 90)
			(size 0.635 0.635)
			(layers "B.Cu" "B.Mask" "B.Paste")
			(net "GND")
		)
		(pad "143" smd circle
			(at 9.525 3.175 90)
			(size 0.635 0.635)
			(layers "B.Cu" "B.Mask" "B.Paste")
			(net "NFP_SERDES1_RX3_N")
		)
		(pad "144" smd circle
			(at 9.525 4.445 90)
			(size 0.635 0.635)
			(layers "B.Cu" "B.Mask" "B.Paste")
			(net "GND")
		)
		(pad "145" smd circle
			(at 10.795 -4.445 90)
			(size 0.635 0.635)
			(layers "B.Cu" "B.Mask" "B.Paste")
			(net "EXT_12.0V")
		)
		(pad "146" smd circle
			(at 10.795 -3.175 90)
			(size 0.635 0.635)
			(layers "B.Cu" "B.Mask" "B.Paste")
			(net "EXT_3.3V")
		)
		(pad "147" smd circle
			(at 10.795 -1.905 90)
			(size 0.635 0.635)
			(layers "B.Cu" "B.Mask" "B.Paste")
			(net "MAIN_3.3V")
		)
		(pad "148" smd circle
			(at 10.795 -0.635 90)
			(size 0.635 0.635)
			(layers "B.Cu" "B.Mask" "B.Paste")
			(net "GND")
		)
		(pad "149" smd circle
			(at 10.795 0.635 90)
			(size 0.635 0.635)
			(layers "B.Cu" "B.Mask" "B.Paste")
			(net "NFP_SERDES0_RX0_N")
		)
		(pad "150" smd circle
			(at 10.795 1.905 90)
			(size 0.635 0.635)
			(layers "B.Cu" "B.Mask" "B.Paste")
			(net "GND")
		)
		(pad "151" smd circle
			(at 10.795 3.175 90)
			(size 0.635 0.635)
			(layers "B.Cu" "B.Mask" "B.Paste")
			(net "NFP_SERDES1_RX3_P")
		)
		(pad "152" smd circle
			(at 10.795 4.445 90)
			(size 0.635 0.635)
			(layers "B.Cu" "B.Mask" "B.Paste")
			(net "NWK0_I2C_SDA")
		)
		(pad "153" smd circle
			(at 12.065 -4.445 90)
			(size 0.635 0.635)
			(layers "B.Cu" "B.Mask" "B.Paste")
			(net "EXT_12.0V")
		)
		(pad "154" smd circle
			(at 12.065 -3.175 90)
			(size 0.635 0.635)
			(layers "B.Cu" "B.Mask" "B.Paste")
			(net "EXT_3.3V")
		)
		(pad "155" smd circle
			(at 12.065 -1.905 90)
			(size 0.635 0.635)
			(layers "B.Cu" "B.Mask" "B.Paste")
			(net "MAIN_3.3V")
		)
		(pad "156" smd circle
			(at 12.065 -0.635 90)
			(size 0.635 0.635)
			(layers "B.Cu" "B.Mask" "B.Paste")
			(net "MAIN_3.3V")
		)
		(pad "157" smd circle
			(at 12.065 0.635 90)
			(size 0.635 0.635)
			(layers "B.Cu" "B.Mask" "B.Paste")
			(net "GND")
		)
		(pad "158" smd circle
			(at 12.065 1.905 90)
			(size 0.635 0.635)
			(layers "B.Cu" "B.Mask" "B.Paste")
			(net "NWK0_MOD_PRES_L")
		)
		(pad "159" smd circle
			(at 12.065 3.175 90)
			(size 0.635 0.635)
			(layers "B.Cu" "B.Mask" "B.Paste")
			(net "GND")
		)
		(pad "160" smd circle
			(at 12.065 4.445 90)
			(size 0.635 0.635)
			(layers "B.Cu" "B.Mask" "B.Paste")
			(net "NWK0_I2C_SCL")
		)
	)
	(footprint ""
		(layer "B.Cu")
		(at 84.250987 14.256004)
		(property "Reference" "V2_A-A13"
			(at 0 0 0)
			(layer "B.SilkS")
			(hide yes)
			(effects
				(font
					(size 1.27 1.27)
				)
				(justify mirror)
			)
		)
		(property "Value" ""
			(at 0 0 0)
			(layer "B.Fab")
			(effects
				(font
					(size 1.27 1.27)
				)
				(justify mirror)
			)
		)
		(duplicate_pad_numbers_are_jumpers no)
		(pad "1" thru_hole circle
			(at 0 0 180)
			(size 0.4572 0.4572)
			(drill 0.20574)
			(layers "*.Cu" "*.Mask")
			(remove_unused_layers no)
			(net "DDR0_32A_A13")
			(clearance 0.1143)
			(thermal_gap 0.1143)
		)
	)
	(footprint ""
		(layer "B.Cu")
		(at 27.432 32.639)
		(property "Reference" "R97"
			(at -0.28067 4.826 270)
			(unlocked yes)
			(layer "B.SilkS")
			(effects
				(font
					(size 0.7874 0.5842)
					(thickness 0.127)
				)
				(justify left mirror)
			)
		)
		(property "Value" "4.75K"
			(at 0.148158 1.3462 270)
			(unlocked yes)
			(layer "B.Fab")
			(hide yes)
			(effects
				(font
					(size 1.27 0.9652)
					(thickness 0.000001)
				)
				(justify left mirror)
			)
		)
		(property "Device Type" "REST4024"
			(at 0.148158 1.3462 270)
			(unlocked yes)
			(layer "B.Fab")
			(hide yes)
			(effects
				(font
					(size 1.27 0.9652)
					(thickness 0.000001)
				)
				(justify left mirror)
			)
		)
		(duplicate_pad_numbers_are_jumpers no)
		(fp_poly
			(pts
				(xy -0.635 1.0668) (xy -0.635 -1.0668) (xy 0.635 -1.0668) (xy 0.635 1.0668)
			)
			(stroke
				(width 0)
				(type default)
			)
			(fill no)
			(layer "B.CrtYd")
		)
		(fp_line
			(start -0.254 -0.508)
			(end -0.254 0.508)
			(stroke
				(width 0.0254)
				(type default)
			)
			(layer "B.Fab")
		)
		(fp_line
			(start -0.254 0.508)
			(end 0.254 0.508)
			(stroke
				(width 0.0254)
				(type default)
			)
			(layer "B.Fab")
		)
		(fp_line
			(start 0.254 -0.508)
			(end -0.254 -0.508)
			(stroke
				(width 0.0254)
				(type default)
			)
			(layer "B.Fab")
		)
		(fp_line
			(start 0.254 0.508)
			(end 0.254 -0.508)
			(stroke
				(width 0.0254)
				(type default)
			)
			(layer "B.Fab")
		)
		(pad "1" smd rect
			(at 0 -0.4191 180)
			(size 0.508 0.5334)
			(layers "B.Cu" "B.Mask" "B.Paste")
			(net "GND")
		)
		(pad "2" smd rect
			(at 0 0.4191 180)
			(size 0.508 0.5334)
			(layers "B.Cu" "B.Mask" "B.Paste")
			(net "_NFP_CORE_VID1")
		)
		(zone
			(layer "B.Cu")
			(hatch none 0.5)
			(connect_pads
				(clearance 0)
			)
			(min_thickness 0.25)
			(keepout
				(tracks not_allowed)
				(vias allowed)
				(pads allowed)
				(copperpour not_allowed)
				(footprints allowed)
			)
			(placement
				(enabled no)
				(sheetname "")
			)
			(fill
				(thermal_gap 0.5)
				(thermal_bridge_width 0.5)
				(island_removal_mode 0)
			)
			(polygon
				(pts
					(xy 27.4066 32.6136) (xy 27.4066 32.6644) (xy 27.4574 32.6644) (xy 27.4574 32.6136)
				)
			)
		)
	)
	(footprint ""
		(layer "B.Cu")
		(at 77.051002 18.255996)
		(property "Reference" "V_A-DQ23"
			(at 0 0 0)
			(layer "B.SilkS")
			(hide yes)
			(effects
				(font
					(size 1.27 1.27)
				)
				(justify mirror)
			)
		)
		(property "Value" ""
			(at 0 0 0)
			(layer "B.Fab")
			(effects
				(font
					(size 1.27 1.27)
				)
				(justify mirror)
			)
		)
		(duplicate_pad_numbers_are_jumpers no)
		(pad "1" thru_hole circle
			(at 0 0 180)
			(size 0.4572 0.4572)
			(drill 0.20574)
			(layers "*.Cu" "*.Mask")
			(remove_unused_layers no)
			(net "DDR0_32A_DQ23")
			(clearance 0.1143)
			(thermal_gap 0.1143)
		)
	)
	(footprint ""
		(layer "B.Cu")
		(at 53.4289 40.386 90)
		(property "Reference" "C180"
			(at -7.239 -0.87757 270)
			(unlocked yes)
			(layer "B.SilkS")
			(effects
				(font
					(size 0.7874 0.5842)
					(thickness 0.127)
				)
				(justify left mirror)
			)
		)
		(property "Value" ""
			(at 0 0 90)
			(layer "B.Fab")
			(effects
				(font
					(size 1.27 1.27)
				)
				(justify mirror)
			)
		)
		(duplicate_pad_numbers_are_jumpers no)
		(fp_circle
			(center 0 0)
			(end 0 0.508)
			(stroke
				(width 0.2032)
				(type default)
			)
			(fill no)
			(layer "B.SilkS")
		)
		(fp_poly
			(pts
				(xy 2.286 1.778) (xy 2.286 -1.778) (xy -2.286 -1.778) (xy -2.286 1.778)
			)
			(stroke
				(width 0)
				(type default)
			)
			(fill no)
			(layer "B.CrtYd")
		)
		(fp_line
			(start 1.524 -1.27)
			(end -1.524 -1.27)
			(stroke
				(width 0.0254)
				(type default)
			)
			(layer "B.Fab")
		)
		(fp_line
			(start -1.524 -1.27)
			(end -1.524 1.27)
			(stroke
				(width 0.0254)
				(type default)
			)
			(layer "B.Fab")
		)
		(fp_line
			(start 1.524 1.27)
			(end 1.524 -1.27)
			(stroke
				(width 0.0254)
				(type default)
			)
			(layer "B.Fab")
		)
		(fp_line
			(start -1.524 1.27)
			(end 1.524 1.27)
			(stroke
				(width 0.0254)
				(type default)
			)
			(layer "B.Fab")
		)
		(pad "1" smd rect
			(at 1.4224 0 180)
			(size 2.7432 1.3716)
			(layers "B.Cu" "B.Mask" "B.Paste")
			(net "EXT_12.0V")
		)
		(pad "2" smd rect
			(at -1.4224 0 180)
			(size 2.7432 1.3716)
			(layers "B.Cu" "B.Mask" "B.Paste")
			(net "GND")
		)
	)
	(footprint ""
		(layer "B.Cu")
		(at 45.3009 35.687)
		(property "Reference" "R74"
			(at 0 0 0)
			(layer "B.SilkS")
			(hide yes)
			(effects
				(font
					(size 1.27 1.27)
				)
				(justify mirror)
			)
		)
		(property "Value" "4.75K"
			(at 0.148158 1.3462 270)
			(unlocked yes)
			(layer "B.Fab")
			(hide yes)
			(effects
				(font
					(size 1.27 0.9652)
					(thickness 0.000001)
				)
				(justify left mirror)
			)
		)
		(property "Device Type" "REST4024"
			(at 0.148158 1.3462 270)
			(unlocked yes)
			(layer "B.Fab")
			(hide yes)
			(effects
				(font
					(size 1.27 0.9652)
					(thickness 0.000001)
				)
				(justify left mirror)
			)
		)
		(duplicate_pad_numbers_are_jumpers no)
		(fp_poly
			(pts
				(xy -0.635 1.0668) (xy -0.635 -1.0668) (xy 0.635 -1.0668) (xy 0.635 1.0668)
			)
			(stroke
				(width 0)
				(type default)
			)
			(fill no)
			(layer "B.CrtYd")
		)
		(fp_line
			(start -0.254 -0.508)
			(end -0.254 0.508)
			(stroke
				(width 0.0254)
				(type default)
			)
			(layer "B.Fab")
		)
		(fp_line
			(start -0.254 0.508)
			(end 0.254 0.508)
			(stroke
				(width 0.0254)
				(type default)
			)
			(layer "B.Fab")
		)
		(fp_line
			(start 0.254 -0.508)
			(end -0.254 -0.508)
			(stroke
				(width 0.0254)
				(type default)
			)
			(layer "B.Fab")
		)
		(fp_line
			(start 0.254 0.508)
			(end 0.254 -0.508)
			(stroke
				(width 0.0254)
				(type default)
			)
			(layer "B.Fab")
		)
		(pad "1" smd rect
			(at 0 -0.4191 180)
			(size 0.508 0.5334)
			(layers "B.Cu" "B.Mask" "B.Paste")
			(net "VDD_5.0V")
		)
		(pad "2" smd rect
			(at 0 0.4191 180)
			(size 0.508 0.5334)
			(layers "B.Cu" "B.Mask" "B.Paste")
			(net "10N2256")
		)
		(zone
			(layer "B.Cu")
			(hatch none 0.5)
			(connect_pads
				(clearance 0)
			)
			(min_thickness 0.25)
			(keepout
				(tracks not_allowed)
				(vias allowed)
				(pads allowed)
				(copperpour not_allowed)
				(footprints allowed)
			)
			(placement
				(enabled no)
				(sheetname "")
			)
			(fill
				(thermal_gap 0.5)
				(thermal_bridge_width 0.5)
				(island_removal_mode 0)
			)
			(polygon
				(pts
					(xy 45.2755 35.6616) (xy 45.2755 35.7124) (xy 45.3263 35.7124) (xy 45.3263 35.6616)
				)
			)
		)
	)
	(footprint ""
		(layer "B.Cu")
		(at 23.876 4.699 180)
		(property "Reference" "R369"
			(at 0.254 -1.04267 0)
			(unlocked yes)
			(layer "B.SilkS")
			(effects
				(font
					(size 0.7874 0.5842)
					(thickness 0.127)
				)
				(justify left mirror)
			)
		)
		(property "Value" "4.75K"
			(at 0.148158 1.3462 90)
			(unlocked yes)
			(layer "B.Fab")
			(hide yes)
			(effects
				(font
					(size 1.27 0.9652)
					(thickness 0.000001)
				)
				(justify left mirror)
			)
		)
		(property "Device Type" "REST4024"
			(at 0.148158 1.3462 90)
			(unlocked yes)
			(layer "B.Fab")
			(hide yes)
			(effects
				(font
					(size 1.27 0.9652)
					(thickness 0.000001)
				)
				(justify left mirror)
			)
		)
		(duplicate_pad_numbers_are_jumpers no)
		(fp_poly
			(pts
				(xy -0.635 1.0668) (xy -0.635 -1.0668) (xy 0.635 -1.0668) (xy 0.635 1.0668)
			)
			(stroke
				(width 0)
				(type default)
			)
			(fill no)
			(layer "B.CrtYd")
		)
		(fp_line
			(start 0.254 0.508)
			(end 0.254 -0.508)
			(stroke
				(width 0.0254)
				(type default)
			)
			(layer "B.Fab")
		)
		(fp_line
			(start 0.254 -0.508)
			(end -0.254 -0.508)
			(stroke
				(width 0.0254)
				(type default)
			)
			(layer "B.Fab")
		)
		(fp_line
			(start -0.254 0.508)
			(end 0.254 0.508)
			(stroke
				(width 0.0254)
				(type default)
			)
			(layer "B.Fab")
		)
		(fp_line
			(start -0.254 -0.508)
			(end -0.254 0.508)
			(stroke
				(width 0.0254)
				(type default)
			)
			(layer "B.Fab")
		)
		(pad "1" smd rect
			(at 0 -0.4191)
			(size 0.508 0.5334)
			(layers "B.Cu" "B.Mask" "B.Paste")
			(net "NFP_SMBUS_SDA")
		)
		(pad "2" smd rect
			(at 0 0.4191)
			(size 0.508 0.5334)
			(layers "B.Cu" "B.Mask" "B.Paste")
			(net "EXT_3.3V")
		)
		(zone
			(layer "B.Cu")
			(hatch none 0.5)
			(connect_pads
				(clearance 0)
			)
			(min_thickness 0.25)
			(keepout
				(tracks not_allowed)
				(vias allowed)
				(pads allowed)
				(copperpour not_allowed)
				(footprints allowed)
			)
			(placement
				(enabled no)
				(sheetname "")
			)
			(fill
				(thermal_gap 0.5)
				(thermal_bridge_width 0.5)
				(island_removal_mode 0)
			)
			(polygon
				(pts
					(xy 23.9014 4.7244) (xy 23.9014 4.6736) (xy 23.8506 4.6736) (xy 23.8506 4.7244)
				)
			)
		)
	)
	(footprint ""
		(layer "B.Cu")
		(at 74.168 35.052 90)
		(property "Reference" "R119"
			(at 0.10033 4.572 0)
			(unlocked yes)
			(layer "B.SilkS")
			(effects
				(font
					(size 0.7874 0.5842)
					(thickness 0.127)
				)
				(justify left mirror)
			)
		)
		(property "Value" "2.2"
			(at 0.148158 1.7526 0)
			(unlocked yes)
			(layer "B.Fab")
			(hide yes)
			(effects
				(font
					(size 1.27 0.9652)
					(thickness 0.000001)
				)
				(justify left mirror)
			)
		)
		(property "Device Type" "REST0145"
			(at 0.148158 1.7526 0)
			(unlocked yes)
			(layer "B.Fab")
			(hide yes)
			(effects
				(font
					(size 1.27 0.9652)
					(thickness 0.000001)
				)
				(justify left mirror)
			)
		)
		(duplicate_pad_numbers_are_jumpers no)
		(fp_circle
			(center 0 0)
			(end 0 0.127)
			(stroke
				(width 0.2032)
				(type default)
			)
			(fill no)
			(layer "B.SilkS")
		)
		(fp_poly
			(pts
				(xy -0.7874 -1.6637) (xy 0.7874 -1.6637) (xy 0.7874 1.6637) (xy -0.7874 1.6637)
			)
			(stroke
				(width 0)
				(type default)
			)
			(fill no)
			(layer "B.CrtYd")
		)
		(fp_line
			(start 0.4064 -0.8128)
			(end -0.4064 -0.8128)
			(stroke
				(width 0.0254)
				(type default)
			)
			(layer "B.Fab")
		)
		(fp_line
			(start -0.4064 -0.8128)
			(end -0.4064 0.8128)
			(stroke
				(width 0.0254)
				(type default)
			)
			(layer "B.Fab")
		)
		(fp_line
			(start 0.4064 0.8128)
			(end 0.4064 -0.8128)
			(stroke
				(width 0.0254)
				(type default)
			)
			(layer "B.Fab")
		)
		(fp_line
			(start -0.4064 0.8128)
			(end 0.4064 0.8128)
			(stroke
				(width 0.0254)
				(type default)
			)
			(layer "B.Fab")
		)
		(pad "1" smd rect
			(at 0 -0.8001 270)
			(size 0.762 0.9652)
			(layers "B.Cu" "B.Mask" "B.Paste")
			(net "10N2228")
		)
		(pad "2" smd rect
			(at 0 0.8001 270)
			(size 0.762 0.9652)
			(layers "B.Cu" "B.Mask" "B.Paste")
			(net "10N2262")
		)
		(zone
			(layer "B.Cu")
			(hatch none 0.5)
			(connect_pads
				(clearance 0)
			)
			(min_thickness 0.25)
			(keepout
				(tracks not_allowed)
				(vias allowed)
				(pads allowed)
				(copperpour not_allowed)
				(footprints allowed)
			)
			(placement
				(enabled no)
				(sheetname "")
			)
			(fill
				(thermal_gap 0.5)
				(thermal_bridge_width 0.5)
				(island_removal_mode 0)
			)
			(polygon
				(pts
					(xy 73.914 34.9885) (xy 73.914 35.1155) (xy 74.422 35.1155) (xy 74.422 34.9885)
				)
			)
		)
	)
	(footprint ""
		(layer "B.Cu")
		(at 0.6096 17.4498)
		(property "Reference" "R373"
			(at -1.01727 2.3622 270)
			(unlocked yes)
			(layer "B.SilkS")
			(effects
				(font
					(size 0.7874 0.5842)
					(thickness 0.127)
				)
				(justify left mirror)
			)
		)
		(property "Value" "4.75K"
			(at 0.148158 1.3462 270)
			(unlocked yes)
			(layer "B.Fab")
			(hide yes)
			(effects
				(font
					(size 1.27 0.9652)
					(thickness 0.000001)
				)
				(justify left mirror)
			)
		)
		(property "Device Type" "REST4024"
			(at 0.148158 1.3462 270)
			(unlocked yes)
			(layer "B.Fab")
			(hide yes)
			(effects
				(font
					(size 1.27 0.9652)
					(thickness 0.000001)
				)
				(justify left mirror)
			)
		)
		(duplicate_pad_numbers_are_jumpers no)
		(fp_poly
			(pts
				(xy -0.635 1.0668) (xy -0.635 -1.0668) (xy 0.635 -1.0668) (xy 0.635 1.0668)
			)
			(stroke
				(width 0)
				(type default)
			)
			(fill no)
			(layer "B.CrtYd")
		)
		(fp_line
			(start -0.254 -0.508)
			(end -0.254 0.508)
			(stroke
				(width 0.0254)
				(type default)
			)
			(layer "B.Fab")
		)
		(fp_line
			(start -0.254 0.508)
			(end 0.254 0.508)
			(stroke
				(width 0.0254)
				(type default)
			)
			(layer "B.Fab")
		)
		(fp_line
			(start 0.254 -0.508)
			(end -0.254 -0.508)
			(stroke
				(width 0.0254)
				(type default)
			)
			(layer "B.Fab")
		)
		(fp_line
			(start 0.254 0.508)
			(end 0.254 -0.508)
			(stroke
				(width 0.0254)
				(type default)
			)
			(layer "B.Fab")
		)
		(pad "1" smd rect
			(at 0 -0.4191 180)
			(size 0.508 0.5334)
			(layers "B.Cu" "B.Mask" "B.Paste")
			(net "NWK0_I2C_SDA")
		)
		(pad "2" smd rect
			(at 0 0.4191 180)
			(size 0.508 0.5334)
			(layers "B.Cu" "B.Mask" "B.Paste")
			(net "EXT_3.3V")
		)
		(zone
			(layer "B.Cu")
			(hatch none 0.5)
			(connect_pads
				(clearance 0)
			)
			(min_thickness 0.25)
			(keepout
				(tracks not_allowed)
				(vias allowed)
				(pads allowed)
				(copperpour not_allowed)
				(footprints allowed)
			)
			(placement
				(enabled no)
				(sheetname "")
			)
			(fill
				(thermal_gap 0.5)
				(thermal_bridge_width 0.5)
				(island_removal_mode 0)
			)
			(polygon
				(pts
					(xy 0.5842 17.4244) (xy 0.5842 17.4752) (xy 0.635 17.4752) (xy 0.635 17.4244)
				)
			)
		)
	)
	(footprint ""
		(layer "B.Cu")
		(at 5.08 4.699 90)
		(property "Reference" "R276"
			(at 0 0 90)
			(layer "B.SilkS")
			(hide yes)
			(effects
				(font
					(size 1.27 1.27)
				)
				(justify mirror)
			)
		)
		(property "Value" "240"
			(at 0.148158 1.3462 0)
			(unlocked yes)
			(layer "B.Fab")
			(hide yes)
			(effects
				(font
					(size 1.27 0.9652)
					(thickness 0.000001)
				)
				(justify left mirror)
			)
		)
		(property "Device Type" "REST0009"
			(at 0.148158 1.3462 0)
			(unlocked yes)
			(layer "B.Fab")
			(hide yes)
			(effects
				(font
					(size 1.27 0.9652)
					(thickness 0.000001)
				)
				(justify left mirror)
			)
		)
		(duplicate_pad_numbers_are_jumpers no)
		(fp_poly
			(pts
				(xy -0.635 1.0668) (xy -0.635 -1.0668) (xy 0.635 -1.0668) (xy 0.635 1.0668)
			)
			(stroke
				(width 0)
				(type default)
			)
			(fill no)
			(layer "B.CrtYd")
		)
		(fp_line
			(start 0.254 -0.508)
			(end -0.254 -0.508)
			(stroke
				(width 0.0254)
				(type default)
			)
			(layer "B.Fab")
		)
		(fp_line
			(start -0.254 -0.508)
			(end -0.254 0.508)
			(stroke
				(width 0.0254)
				(type default)
			)
			(layer "B.Fab")
		)
		(fp_line
			(start 0.254 0.508)
			(end 0.254 -0.508)
			(stroke
				(width 0.0254)
				(type default)
			)
			(layer "B.Fab")
		)
		(fp_line
			(start -0.254 0.508)
			(end 0.254 0.508)
			(stroke
				(width 0.0254)
				(type default)
			)
			(layer "B.Fab")
		)
		(pad "1" smd rect
			(at 0 -0.4191 270)
			(size 0.508 0.5334)
			(layers "B.Cu" "B.Mask" "B.Paste")
			(net "CPLD_NFP_RST_LED_L")
		)
		(pad "2" smd rect
			(at 0 0.4191 270)
			(size 0.508 0.5334)
			(layers "B.Cu" "B.Mask" "B.Paste")
			(net "9N2152")
		)
		(zone
			(layer "B.Cu")
			(hatch none 0.5)
			(connect_pads
				(clearance 0)
			)
			(min_thickness 0.25)
			(keepout
				(tracks not_allowed)
				(vias allowed)
				(pads allowed)
				(copperpour not_allowed)
				(footprints allowed)
			)
			(placement
				(enabled no)
				(sheetname "")
			)
			(fill
				(thermal_gap 0.5)
				(thermal_bridge_width 0.5)
				(island_removal_mode 0)
			)
			(polygon
				(pts
					(xy 5.0546 4.7244) (xy 5.1054 4.7244) (xy 5.1054 4.6736) (xy 5.0546 4.6736)
				)
			)
		)
	)
	(footprint ""
		(layer "B.Cu")
		(at 61.849 41.91)
		(property "Reference" "C15"
			(at 0.98933 3.683 270)
			(unlocked yes)
			(layer "B.SilkS")
			(effects
				(font
					(size 0.7874 0.5842)
					(thickness 0.127)
				)
				(justify left mirror)
			)
		)
		(property "Value" "22UF"
			(at 0.148158 1.7526 270)
			(unlocked yes)
			(layer "B.Fab")
			(hide yes)
			(effects
				(font
					(size 1.27 0.9652)
					(thickness 0.000001)
				)
				(justify left mirror)
			)
		)
		(property "Device Type" "CAPC0063"
			(at 0.148158 1.7526 270)
			(unlocked yes)
			(layer "B.Fab")
			(hide yes)
			(effects
				(font
					(size 1.27 0.9652)
					(thickness 0.000001)
				)
				(justify left mirror)
			)
		)
		(duplicate_pad_numbers_are_jumpers no)
		(fp_circle
			(center 0 0)
			(end 0.127 0)
			(stroke
				(width 0.2032)
				(type default)
			)
			(fill no)
			(layer "B.SilkS")
		)
		(fp_poly
			(pts
				(xy -0.7874 -1.6637) (xy 0.7874 -1.6637) (xy 0.7874 1.6637) (xy -0.7874 1.6637)
			)
			(stroke
				(width 0)
				(type default)
			)
			(fill no)
			(layer "B.CrtYd")
		)
		(fp_line
			(start -0.4064 -0.7874)
			(end -0.4064 0.8128)
			(stroke
				(width 0.0254)
				(type default)
			)
			(layer "B.Fab")
		)
		(fp_line
			(start -0.4064 0.8128)
			(end 0.4064 0.8128)
			(stroke
				(width 0.0254)
				(type default)
			)
			(layer "B.Fab")
		)
		(fp_line
			(start 0.4064 -0.7874)
			(end -0.4064 -0.7874)
			(stroke
				(width 0.0254)
				(type default)
			)
			(layer "B.Fab")
		)
		(fp_line
			(start 0.4064 0.8128)
			(end 0.4064 -0.7874)
			(stroke
				(width 0.0254)
				(type default)
			)
			(layer "B.Fab")
		)
		(pad "1" smd rect
			(at 0 -0.8001 180)
			(size 0.8636 0.9652)
			(layers "B.Cu" "B.Mask" "B.Paste")
			(net "VDD_CORE")
		)
		(pad "2" smd rect
			(at 0 0.8001 180)
			(size 0.8636 0.9652)
			(layers "B.Cu" "B.Mask" "B.Paste")
			(net "GND")
		)
		(zone
			(layer "B.Cu")
			(hatch none 0.5)
			(connect_pads
				(clearance 0)
			)
			(min_thickness 0.25)
			(keepout
				(tracks not_allowed)
				(vias allowed)
				(pads allowed)
				(copperpour not_allowed)
				(footprints allowed)
			)
			(placement
				(enabled no)
				(sheetname "")
			)
			(fill
				(thermal_gap 0.5)
				(thermal_bridge_width 0.5)
				(island_removal_mode 0)
			)
			(polygon
				(pts
					(xy 61.9125 41.656) (xy 61.7855 41.656) (xy 61.7855 42.164) (xy 61.9125 42.164)
				)
			)
		)
	)
	(footprint ""
		(layer "B.Cu")
		(at 76.251003 1.899006)
		(property "Reference" "V_A-DQ01"
			(at 0 0 0)
			(layer "B.SilkS")
			(hide yes)
			(effects
				(font
					(size 1.27 1.27)
				)
				(justify mirror)
			)
		)
		(property "Value" ""
			(at 0 0 0)
			(layer "B.Fab")
			(effects
				(font
					(size 1.27 1.27)
				)
				(justify mirror)
			)
		)
		(duplicate_pad_numbers_are_jumpers no)
		(pad "1" thru_hole circle
			(at 0 0 180)
			(size 0.4572 0.4572)
			(drill 0.20574)
			(layers "*.Cu" "*.Mask")
			(remove_unused_layers no)
			(net "DDR0_32A_DQ1")
			(clearance 0.1143)
			(thermal_gap 0.1143)
		)
	)
	(footprint ""
		(layer "B.Cu")
		(at 61.736986 25.041987 90)
		(property "Reference" "R186"
			(at 0.885317 -0.141986 0)
			(unlocked yes)
			(layer "B.SilkS")
			(effects
				(font
					(size 0.7874 0.5842)
					(thickness 0.127)
				)
				(justify mirror)
			)
		)
		(property "Value" ""
			(at 0 0 90)
			(layer "B.Fab")
			(effects
				(font
					(size 1.27 1.27)
				)
				(justify mirror)
			)
		)
		(duplicate_pad_numbers_are_jumpers no)
		(fp_circle
			(center 0 0)
			(end 0 0.104648)
			(stroke
				(width 0.1016)
				(type default)
			)
			(fill no)
			(layer "B.SilkS")
		)
		(fp_poly
			(pts
				(xy 0.381 -0.889) (xy 0.381 0.889) (xy -0.381 0.889) (xy -0.381 -0.889)
			)
			(stroke
				(width 0)
				(type default)
			)
			(fill no)
			(layer "B.CrtYd")
		)
		(fp_line
			(start 0.508 -1.016)
			(end 0.254 -1.016)
			(stroke
				(width 0.0254)
				(type default)
			)
			(layer "B.Fab")
		)
		(fp_line
			(start 0.254 -1.016)
			(end -0.508 -1.016)
			(stroke
				(width 0.0254)
				(type default)
			)
			(layer "B.Fab")
		)
		(fp_line
			(start -0.508 -1.016)
			(end -0.508 1.016)
			(stroke
				(width 0.0254)
				(type default)
			)
			(layer "B.Fab")
		)
		(fp_line
			(start 0.508 1.016)
			(end 0.508 -1.016)
			(stroke
				(width 0.0254)
				(type default)
			)
			(layer "B.Fab")
		)
		(fp_line
			(start -0.508 1.016)
			(end 0.508 1.016)
			(stroke
				(width 0.0254)
				(type default)
			)
			(layer "B.Fab")
		)
		(pad "1" smd custom
			(at 0 -0.500126 270)
			(size 0.127 0.127)
			(layers "B.Cu" "B.Mask" "B.Paste")
			(net "GND")
			(options
				(clearance outline)
				(anchor circle)
			)
			(primitives
				(gr_poly
					(pts
						(xy -0.1778 0.254) (xy 0.1778 0.254) (xy 0.254 0.1778) (xy 0.254 -0.1778) (xy 0.1778 -0.254) (xy -0.1778 -0.254)
						(xy -0.254 -0.1778) (xy -0.254 0.1778)
					)
					(width 0)
					(fill yes)
				)
			)
		)
		(pad "2" smd custom
			(at 0 0.500126 270)
			(size 0.127 0.127)
			(layers "B.Cu" "B.Mask" "B.Paste")
			(net "A_DZQ1")
			(options
				(clearance outline)
				(anchor circle)
			)
			(primitives
				(gr_poly
					(pts
						(xy -0.1778 0.254) (xy 0.1778 0.254) (xy 0.254 0.1778) (xy 0.254 -0.1778) (xy 0.1778 -0.254) (xy -0.1778 -0.254)
						(xy -0.254 -0.1778) (xy -0.254 0.1778)
					)
					(width 0)
					(fill yes)
				)
			)
		)
	)
	(gr_poly
		(pts
			(xy 9.398 45.339) (xy 7.112 45.339) (xy 7.112 41.783) (xy 9.398 41.783)
		)
		(stroke
			(width 0)
			(type solid)
		)
		(fill yes)
		(layer "F.Cu")
		(net "VDD_1.5V")
	)
	(gr_poly
		(pts
			(xy 16.889298 39.496949) (xy 16.033547 39.496949) (xy 16.033547 39.170204) (xy 16.889298 39.170204)
		)
		(stroke
			(width 0)
			(type solid)
		)
		(fill yes)
		(layer "F.Cu")
		(net "11N1971")
	)
	(gr_poly
		(pts
			(xy 12.922453 35.271354) (xy 12.681433 35.271354) (xy 12.665532 35.255454) (xy 12.445644 35.255454)
			(xy 12.445644 34.865818) (xy 12.922453 34.865818)
		)
		(stroke
			(width 0)
			(type solid)
		)
		(fill yes)
		(layer "F.Cu")
		(net "11N1970")
	)
	(gr_poly
		(pts
			(xy 12.922453 39.560475) (xy 12.117121 39.560475) (xy 12.117121 39.166546) (xy 12.665532 39.166546)
			(xy 12.680747 39.151331) (xy 12.922453 39.151331)
		)
		(stroke
			(width 0)
			(type solid)
		)
		(fill yes)
		(layer "F.Cu")
		(net "11N1968")
	)
	(gr_poly
		(pts
			(xy 16.002 42.672) (xy 15.113 42.672) (xy 15.113 41.903701) (xy 15.176551 41.84015) (xy 15.176551 40.513)
			(xy 16.002 40.513)
		)
		(stroke
			(width 0)
			(type solid)
		)
		(fill yes)
		(layer "F.Cu")
		(net "GND")
	)
	(gr_poly
		(pts
			(xy 13.462 32.004) (xy 13.462 34.417) (xy 12.7 34.417) (xy 12.319 34.036) (xy 12.319 32.004) (xy 12.446 31.877)
			(xy 13.335 31.877)
		)
		(stroke
			(width 0)
			(type solid)
		)
		(fill yes)
		(layer "F.Cu")
		(net "VDD_5.0V")
	)
	(gr_poly
		(pts
			(xy 20.066 40.513) (xy 20.574 40.513) (xy 20.574 41.275) (xy 18.503951 41.275) (xy 18.503951 40.424049)
			(xy 18.796 40.132) (xy 19.685 40.132)
		)
		(stroke
			(width 0)
			(type solid)
		)
		(fill yes)
		(layer "F.Cu")
		(net "GND")
	)
	(gr_poly
		(pts
			(xy 16.764 32.651649) (xy 16.319449 32.651649) (xy 16.319449 32.766) (xy 16.192551 32.766) (xy 16.192551 32.651649)
			(xy 15.24 32.651649) (xy 15.24 30.353) (xy 16.764 30.353)
		)
		(stroke
			(width 0)
			(type solid)
		)
		(fill yes)
		(layer "F.Cu")
		(net "11N2296")
	)
	(gr_poly
		(pts
			(xy 18.415 41.783) (xy 19.177 41.783) (xy 19.177 44.196) (xy 17.907 44.196) (xy 17.907 42.887951)
			(xy 17.919751 42.887951) (xy 17.919751 41.656) (xy 18.288 41.656)
		)
		(stroke
			(width 0)
			(type solid)
		)
		(fill yes)
		(layer "F.Cu")
		(net "11N1971")
	)
	(gr_poly
		(pts
			(xy 14.605 42.418) (xy 14.351 42.672) (xy 14.351 45.339) (xy 12.319 45.339) (xy 12.319 42.799) (xy 12.636449 42.481551)
			(xy 13.525449 42.481551) (xy 14.427149 41.579851) (xy 14.605 41.579851)
		)
		(stroke
			(width 0)
			(type solid)
		)
		(fill yes)
		(layer "F.Cu")
		(net "11N1937")
	)
	(gr_poly
		(pts
			(xy 10.922 39.757299) (xy 10.858449 39.82085) (xy 10.858449 41.275) (xy 9.652 41.275) (xy 9.398 41.021)
			(xy 8.636 41.021) (xy 8.636 39.878) (xy 9.906 39.878) (xy 10.668 39.116) (xy 10.922 39.116)
		)
		(stroke
			(width 0)
			(type solid)
		)
		(fill yes)
		(layer "F.Cu")
		(net "GND")
	)
	(gr_poly
		(pts
			(xy 11.366449 34.734551) (xy 11.049 35.052) (xy 10.922 35.052) (xy 10.401351 34.531351) (xy 10.401351 34.480449)
			(xy 10.350449 34.480449) (xy 9.906 34.036) (xy 9.398 34.036) (xy 9.398 33.02) (xy 11.366449 33.02)
		)
		(stroke
			(width 0)
			(type solid)
		)
		(fill yes)
		(layer "F.Cu")
		(net "GND")
	)
	(gr_poly
		(pts
			(xy 11.429949 41.655949) (xy 11.429949 42.291051) (xy 11.557051 42.291051) (xy 11.938 42.672) (xy 11.938 45.339)
			(xy 10.795 45.339) (xy 10.795 41.783) (xy 10.998149 41.579851) (xy 11.239551 41.579851) (xy 11.239551 41.554248)
			(xy 11.302263 41.528263)
		)
		(stroke
			(width 0)
			(type solid)
		)
		(fill yes)
		(layer "F.Cu")
		(net "11N1968")
	)
	(gr_poly
		(pts
			(xy 14.122349 40.025396) (xy 14.223949 40.126996) (xy 14.223949 40.25392) (xy 14.224 40.253971) (xy 14.224 41.423717)
			(xy 13.610742 42.036975) (xy 12.954 42.036975) (xy 12.954 41.021) (xy 13.716 40.259) (xy 13.716 40.005)
			(xy 14.122349 40.005)
		)
		(stroke
			(width 0)
			(type solid)
		)
		(fill yes)
		(layer "F.Cu")
		(net "VDD_5.0V")
	)
	(gr_poly
		(pts
			(xy 16.438804 34.998279) (xy 16.161918 35.275164) (xy 16.033547 35.275164) (xy 16.033547 34.841383)
			(xy 16.081832 34.793098)
			(arc
				(start 16.081832 34.528049)
				(mid 16.13443 34.44282)
				(end 16.169284 34.348928)
			)
			(xy 16.179241 34.311031) (xy 16.438804 34.311031)
		)
		(stroke
			(width 0)
			(type solid)
		)
		(fill yes)
		(layer "F.Cu")
		(net "11N2296")
	)
	(gr_poly
		(pts
			(xy 10.922 36.576) (xy 11.557 36.576) (xy 11.557 37.076837) (xy 11.422888 37.210949) (xy 10.495661 37.210949)
			(xy 10.36861 37.338) (xy 10.096551 37.338) (xy 10.096551 37.337949) (xy 9.969449 37.337949) (xy 9.969449 37.338)
			(xy 7.874 37.338) (xy 7.874 36.322) (xy 10.668 36.322)
		)
		(stroke
			(width 0)
			(type solid)
		)
		(fill yes)
		(layer "F.Cu")
		(net "VDD_5.0V")
	)
	(gr_poly
		(pts
			(xy 17.271949 33.020051) (xy 18.669 33.020051) (xy 18.669 33.909) (xy 17.907 33.909) (xy 17.399 34.417)
			(xy 17.399 34.671) (xy 16.764 34.671) (xy 16.764 34.163) (xy 16.700551 34.099551) (xy 16.700551 33.020051)
			(xy 17.018051 33.020051) (xy 17.018051 33.02) (xy 17.271949 33.02)
		)
		(stroke
			(width 0)
			(type solid)
		)
		(fill yes)
		(layer "F.Cu")
		(net "GND")
	)
	(gr_poly
		(pts
			(arc
				(start 16.433546 39.90119)
				(mid 16.465511 39.827207)
				(end 16.541293 39.799768)
			)
			(xy 16.568217 39.800581) (xy 16.900601 39.800581) (xy 17.614849 40.514829) (xy 17.614849 41.275)
			(xy 16.383 41.275) (xy 16.383 39.992351) (xy 16.433546 39.992351)
		)
		(stroke
			(width 0)
			(type solid)
		)
		(fill yes)
		(layer "F.Cu")
		(net "VDD_5.0V")
	)
	(gr_poly
		(pts
			(xy 12.522454 39.992351) (xy 13.322351 39.992351) (xy 13.335 40.005) (xy 13.335 40.132) (xy 12.7 40.767)
			(xy 12.7 41.656) (xy 12.319 42.037) (xy 11.684 42.037) (xy 11.684 41.885438)
			(arc
				(start 11.690528 41.873856)
				(mid 11.733064 41.768599)
				(end 11.747551 41.656)
			)
			(xy 11.747551 40.322449) (xy 12.192 39.878) (xy 12.522454 39.878)
		)
		(stroke
			(width 0)
			(type solid)
		)
		(fill yes)
		(layer "F.Cu")
		(net "VDD_5.0V")
	)
	(gr_poly
		(pts
			(xy 9.029649 34.353551) (xy 9.144 34.353551) (xy 9.144 34.671) (xy 9.651949 34.671) (xy 9.651949 34.671051)
			(xy 9.779051 34.671051) (xy 9.779051 34.671) (xy 10.16 34.671) (xy 11.303 35.814) (xy 11.303 36.068)
			(xy 10.773283 36.068) (xy 10.773232 36.067949) (xy 10.718851 36.067949) (xy 10.718851 36.055249)
			(xy 9.347149 36.055249) (xy 9.347149 36.067949) (xy 7.619949 36.067949) (xy 7.619949 36.068) (xy 6.604051 36.068)
			(xy 6.604051 36.067949) (xy 5.842 36.067949) (xy 5.842 32.893) (xy 9.029649 32.893)
		)
		(stroke
			(width 0)
			(type solid)
		)
		(fill yes)
		(layer "F.Cu")
		(net "VDD_1.2V")
	)
	(gr_poly
		(pts
			(arc
				(start 9.333179 31.369)
				(mid 9.8044 31.47065)
				(end 10.275621 31.369)
			)
			(xy 12.065 31.369) (xy 12.065 31.898717) (xy 12.064949 31.898768) (xy 12.064949 32.842149) (xy 11.874449 32.842149)
			(xy 11.874449 33.02) (xy 11.747551 33.02) (xy 11.747551 32.842149) (xy 11.684051 32.842149) (xy 11.684051 32.765949)
			(xy 11.429949 32.765949) (xy 11.049 32.385) (xy 5.842 32.385) (xy 5.842 31.369)
		)
		(stroke
			(width 0)
			(type solid)
		)
		(fill yes)
		(layer "F.Cu")
		(net "11N1970")
	)
	(gr_poly
		(pts
			(xy 19.939 30.734) (xy 19.939 34.747149) (xy 19.684949 34.747149)
			(arc
				(start 19.684949 34.937675)
				(mid 19.583344 35.2425)
				(end 19.684949 35.547325)
			)
			(xy 19.684949 35.560051) (xy 18.923 36.322) (xy 18.878448 36.322) (xy 18.878398 36.321949) (xy 17.779949 36.321949)
			(xy 17.272 35.814) (xy 17.907 35.179) (xy 17.907 34.544) (xy 18.287949 34.544) (xy 18.287949 34.582151)
			(xy 18.415051 34.582151) (xy 18.415051 34.544) (xy 19.05 34.544) (xy 19.05 32.766) (xy 17.792751 32.766)
			(xy 17.792751 32.651649) (xy 17.526 32.651649) (xy 17.526 30.353) (xy 19.558 30.353)
		)
		(stroke
			(width 0)
			(type solid)
		)
		(fill yes)
		(layer "F.Cu")
		(net "VDD_3.3V")
	)
	(gr_poly
		(pts
			(xy 14.985949 33.020051) (xy 15.811449 33.020051) (xy 15.811449 33.909)
			(arc
				(start 15.365755 33.909)
				(mid 14.990479 33.731271)
				(end 14.607972 33.892846)
			)
			(xy 14.59291 33.909) (xy 14.46469 33.909)
			(arc
				(start 14.449628 33.892846)
				(mid 14.182995 33.742137)
				(end 13.878179 33.772069)
			)
			(xy 13.846581 33.785581) (xy 13.716 33.655) (xy 13.716 33.02) (xy 14.985949 33.02)
		)
		(stroke
			(width 0)
			(type solid)
		)
		(fill yes)
		(layer "F.Cu")
		(net "VDD_5.0V")
	)
	(gr_poly
		(pts
			(xy 19.7072 38.2492)
			(arc
				(start 19.710984 38.260579)
				(mid 19.833747 38.459253)
				(end 20.032421 38.582016)
			)
			(xy 20.0438 38.5858) (xy 20.066 38.608) (xy 20.186472 38.608) (xy 20.199528 38.608) (xy 21.628049 38.608)
			(xy 21.628049 40.538451) (xy 21.717 40.538451) (xy 21.717 41.503549) (xy 21.628049 41.503549) (xy 21.628049 43.383251)
			(xy 21.717 43.383251) (xy 21.717 44.069) (xy 20.447 44.069) (xy 20.193 43.815) (xy 20.193 41.668751)
			(xy 20.878851 41.668751) (xy 20.878851 40.195449) (xy 20.828 40.195449) (xy 20.828 39.751) (xy 19.00649 39.751)
			(arc
				(start 18.012258 38.756742)
				(mid 17.915068 38.680754)
				(end 17.802428 38.630428)
			)
			(xy 17.78 38.608) (xy 17.78 38.213081) (xy 19.671081 38.213081)
		)
		(stroke
			(width 0)
			(type solid)
		)
		(fill yes)
		(layer "F.Cu")
		(net "DDR_1.8V")
	)
	(gr_poly
		(pts
			(arc
				(start 17.615433 41.958184)
				(mid 17.625858 42.033722)
				(end 17.649038 42.106367)
			)
			(xy 17.652949 42.11574) (xy 17.652949 44.450051) (xy 17.653 44.450051) (xy 17.653 44.958) (xy 18.288 45.593)
			(xy 18.288 46.228)
			(arc
				(start 15.810128 46.228)
				(mid 15.726543 46.184122)
				(end 15.715132 46.090408)
			)
			(arc
				(start 15.715132 46.090408)
				(mid 15.527526 45.491602)
				(end 14.901316 45.531786)
			)
			(arc
				(start 14.901316 45.531786)
				(mid 14.792124 45.548791)
				(end 14.732 45.456069)
			)
			(xy 14.732 43.053) (xy 16.383 43.053) (xy 16.637 42.799) (xy 16.637 42.265651) (xy 16.637051 42.265651)
			(xy 16.637051 42.138549) (xy 16.637 42.138549) (xy 16.637 41.91) (xy 17.61297 41.91)
		)
		(stroke
			(width 0)
			(type solid)
		)
		(fill yes)
		(layer "F.Cu")
		(net "VDD_1.8V")
	)
	(gr_poly
		(pts
			(arc
				(start 14.418386 36.321187)
				(mid 14.5796 36.347444)
				(end 14.740814 36.321187)
			)
			(xy 14.748662 36.318571) (xy 15.312238 36.318571) (xy 15.320086 36.321187) (xy 15.32161 36.321695)
			(xy 15.356434 36.333227) (xy 15.356434 37.12939) (xy 16.040049 37.12939) (xy 16.040049 37.301856)
			(xy 15.360472 37.301856)
			(arc
				(start 15.360472 37.973254)
				(mid 15.331837 38.043955)
				(end 15.262073 38.074803)
			)
			(arc
				(start 15.262073 38.074803)
				(mid 15.179991 38.084113)
				(end 15.100503 38.106604)
			)
			(xy 15.091918 38.109804) (xy 13.864082 38.109804)
			(arc
				(start 13.855497 38.106604)
				(mid 13.770219 38.083014)
				(end 13.682142 38.074575)
			)
			(arc
				(start 13.682142 38.074575)
				(mid 13.61084 38.044523)
				(end 13.58138 37.972975)
			)
			(xy 13.58138 37.301856) (xy 12.915951 37.301856) (xy 12.915951 37.12939) (xy 13.58138 37.12939) (xy 13.58138 36.703178)
			(arc
				(start 13.584377 36.694847)
				(mid 13.611284 36.579247)
				(end 13.610641 36.460557)
			)
			(arc
				(start 13.610641 36.460557)
				(mid 13.633549 36.382948)
				(end 13.705891 36.346689)
			)
			(arc
				(start 13.705891 36.346689)
				(mid 13.773358 36.338406)
				(end 13.839114 36.321187)
			)
			(xy 13.846962 36.318571) (xy 14.410538 36.318571)
		)
		(stroke
			(width 0)
			(type solid)
		)
		(fill yes)
		(layer "F.Cu")
		(net "GND")
	)
	(gr_poly
		(pts
			(arc
				(start 62.865 37.875896)
				(mid 62.610945 38.3159)
				(end 62.865 38.755904)
			)
			(xy 62.865 45.339) (xy 58.928 45.339) (xy 58.928 45.669149) (xy 58.864449 45.669149) (xy 58.864449 46.355)
			(xy 55.499 46.355) (xy 55.499 55.372) (xy 53.975051 55.372) (xy 53.975051 53.746349) (xy 53.975 53.746349)
			(xy 53.975 52.806651) (xy 53.975051 52.806651) (xy 53.975051 51.231749) (xy 53.975 51.231749) (xy 53.975 50.292051)
			(xy 53.975051 50.292051) (xy 53.975051 48.717149) (xy 53.975 48.717149) (xy 53.975 47.777451) (xy 53.975051 47.777451)
			(xy 53.975051 46.202549) (xy 53.975 46.202549) (xy 53.975 45.085) (xy 54.61 45.085) (xy 54.61 43.800293)
			(arc
				(start 54.644646 43.78866)
				(mid 54.991061 43.307)
				(end 54.644646 42.82534)
			)
			(xy 54.61 42.813707)
			(arc
				(start 54.61 39.379296)
				(mid 54.825961 38.9636)
				(end 54.61 38.547904)
			)
			(arc
				(start 54.61 38.328524)
				(mid 54.639016 38.257431)
				(end 54.709492 38.226949)
			)
			(arc
				(start 54.709492 38.226949)
				(mid 55.04533 38.090633)
				(end 55.204843 37.765177)
			)
			(xy 55.209059 37.719) (xy 62.224844 37.719) (xy 62.235156 37.719) (xy 62.865 37.719)
		)
		(stroke
			(width 0)
			(type solid)
		)
		(fill yes)
		(layer "F.Cu")
		(net "VDD_CORE")
	)
	(gr_poly
		(pts
			(xy 50.2539 42.799) (xy 46.5709 42.799) (xy 46.5709 44.831) (xy 43.1419 44.831) (xy 43.1419 43.939409)
			(xy 46.052257 43.939409) (xy 46.354035 43.939409) (xy 46.354035 43.23522) (xy 46.052257 43.23522)
			(xy 46.052257 43.939409) (xy 43.1419 43.939409) (xy 43.1419 42.85295) (xy 44.945681 42.85295) (xy 45.619695 42.85295)
			(xy 45.619695 42.510913) (xy 44.945681 42.510913) (xy 44.945681 42.85295) (xy 43.1419 42.85295) (xy 43.1419 42.279545)
			(xy 44.955739 42.279545) (xy 45.609637 42.279545) (xy 45.609637 41.987826) (xy 44.955739 41.987826)
			(xy 44.955739 42.279545) (xy 43.1419 42.279545) (xy 43.1419 41.756432) (xy 44.965798 41.756432) (xy 45.609637 41.756432)
			(xy 45.609637 41.504946) (xy 44.965798 41.504946) (xy 44.965798 41.756432) (xy 43.1419 41.756432)
			(xy 43.1419 41.397631) (xy 43.142314 41.387605) (xy 43.14998 41.369077) (xy 43.164154 41.354894)
			(xy 43.182679 41.347219) (xy 43.20273 41.347221) (xy 43.221254 41.3549) (xy 43.228616 41.361716)
			(xy 43.2689 41.402) (xy 44.0309 41.402) (xy 44.1579 41.275) (xy 44.1579 41.263494) (xy 44.935623 41.263494)
			(xy 45.629754 41.263494) (xy 45.629754 41.00195) (xy 44.935623 41.00195) (xy 44.935623 41.263494)
			(xy 44.1579 41.263494) (xy 44.1579 41.021051) (xy 44.157951 41.021051) (xy 44.157951 40.992908) (xy 44.158423 40.978315)
			(xy 44.166668 40.950318) (xy 44.182489 40.925792) (xy 44.204596 40.906737) (xy 44.231187 40.894705)
			(xy 44.260094 40.890678) (xy 44.274588 40.892425) (xy 44.304547 40.896469) (xy 44.364976 40.89826)
			(xy 44.42519 40.892868) (xy 44.48434 40.880369) (xy 44.541588 40.860939) (xy 44.596126 40.834854)
			(xy 44.647184 40.802481) (xy 44.670904 40.783739) (xy 45.935951 40.783739) (xy 45.935951 40.64) (xy 50.2539 40.64)
		)
		(stroke
			(width 0)
			(type solid)
		)
		(fill yes)
		(layer "B.Cu")
		(net "L_2_CORE_PHASE")
	)
	(gr_poly
		(pts
			(xy 69.85 42.799) (xy 66.167 42.799) (xy 66.167 44.958) (xy 63.881 44.958) (xy 63.881 43.939409)
			(xy 65.648357 43.939409) (xy 65.950135 43.939409) (xy 65.950135 43.23522) (xy 65.648357 43.23522)
			(xy 65.648357 43.939409) (xy 63.881 43.939409) (xy 63.881 42.85295) (xy 64.541781 42.85295) (xy 65.215795 42.85295)
			(xy 65.215795 42.510913) (xy 64.541781 42.510913) (xy 64.541781 42.85295) (xy 63.881 42.85295) (xy 63.881 42.418)
			(xy 62.738 42.418) (xy 62.738 42.279545) (xy 64.551839 42.279545) (xy 65.205737 42.279545) (xy 65.205737 41.987826)
			(xy 64.551839 41.987826) (xy 64.551839 42.279545) (xy 62.738 42.279545) (xy 62.738 41.756432) (xy 64.561898 41.756432)
			(xy 65.205737 41.756432) (xy 65.205737 41.504946) (xy 64.561898 41.504946) (xy 64.561898 41.756432)
			(xy 62.738 41.756432) (xy 62.738 41.397631) (xy 62.738414 41.387605) (xy 62.74608 41.369077) (xy 62.760254 41.354894)
			(xy 62.778779 41.347219) (xy 62.79883 41.347221) (xy 62.817354 41.3549) (xy 62.824716 41.361716)
			(xy 62.865 41.402) (xy 63.627 41.402) (xy 63.754 41.275) (xy 63.754 41.263494) (xy 64.531723 41.263494)
			(xy 65.225854 41.263494) (xy 65.225854 41.00195) (xy 64.531723 41.00195) (xy 64.531723 41.263494)
			(xy 63.754 41.263494) (xy 63.754 41.021051) (xy 63.754051 41.021051) (xy 63.754051 40.992908) (xy 63.754523 40.978315)
			(xy 63.762768 40.950318) (xy 63.778589 40.925792) (xy 63.800696 40.906737) (xy 63.827287 40.894705)
			(xy 63.856194 40.890678) (xy 63.870688 40.892425) (xy 63.900647 40.896469) (xy 63.961076 40.89826)
			(xy 64.02129 40.892868) (xy 64.08044 40.880369) (xy 64.137688 40.860939) (xy 64.192226 40.834854)
			(xy 64.243284 40.802481) (xy 64.267004 40.783739) (xy 65.532051 40.783739) (xy 65.532051 40.64) (xy 69.85 40.64)
		)
		(stroke
			(width 0)
			(type solid)
		)
		(fill yes)
		(layer "B.Cu")
		(net "L_1_CORE_PHASE")
	)
	(gr_poly
		(pts
			(xy 74.549 40.005) (xy 71.424851 40.005) (xy 71.424851 39.996237) (xy 70.222237 39.996237) (xy 70.104 39.878)
			(xy 67.945 39.878) (xy 67.945 39.765935) (xy 70.411543 39.765935) (xy 71.126452 39.765935) (xy 71.126452 39.523594)
			(xy 70.411543 39.523594) (xy 70.411543 39.765935) (xy 67.945 39.765935) (xy 67.945 39.287298) (xy 70.393357 39.287298)
			(xy 71.114336 39.287298) (xy 71.114336 39.014679) (xy 70.393357 39.014679) (xy 70.393357 39.287298)
			(xy 67.945 39.287298) (xy 67.945 38.778383) (xy 70.429704 38.778383) (xy 71.108265 38.778383) (xy 71.108265 38.529997)
			(xy 70.429704 38.529997) (xy 70.429704 38.778383) (xy 67.945 38.778383) (xy 67.945 38.600786) (xy 67.949039 38.596748)
			(xy 67.949039 38.481) (xy 68.961 38.481) (xy 68.961 38.354051) (xy 68.961762 38.354051) (xy 68.961762 38.1)
			(xy 69.215 38.1) (xy 69.469 38.1) (xy 69.469 38.033198) (xy 69.654242 38.033198) (xy 69.938976 38.033198)
			(xy 69.938976 37.32436) (xy 69.654242 37.32436) (xy 69.654242 38.033198) (xy 69.469 38.033198) (xy 69.469 37.338)
			(xy 69.215 37.338) (xy 69.215 38.1) (xy 68.961762 38.1) (xy 68.961762 37.419686) (xy 69.288711 37.092738)
			(xy 69.288711 37.075364) (xy 69.336971 37.027104) (xy 69.336971 36.522711) (xy 71.628 36.522711)
			(xy 71.653235 36.522246) (xy 71.703109 36.514508) (xy 71.751206 36.499215) (xy 71.796391 36.476729)
			(xy 71.837593 36.447581) (xy 71.856041 36.430356) (xy 71.891809 36.438693) (xy 71.964659 36.448041)
			(xy 72.0381 36.448924) (xy 72.111153 36.441327) (xy 72.182841 36.425354) (xy 72.252209 36.401217)
			(xy 72.318329 36.369239) (xy 72.380318 36.329847) (xy 72.437348 36.283566) (xy 72.488659 36.231015)
			(xy 72.533565 36.172896) (xy 72.552966 36.141711) (xy 74.341838 36.141711) (xy 74.415548 36.068)
			(xy 74.549 36.068)
		)
		(stroke
			(width 0)
			(type solid)
		)
		(fill yes)
		(layer "B.Cu")
		(net "EXT_12.0V")
	)
	(gr_poly
		(pts
			(xy 54.952849 37.128298) (xy 54.9529 37.128348) (xy 54.9529 38.521005) (xy 54.925906 38.549463) (xy 54.87726 38.610999)
			(xy 54.835194 38.677207) (xy 54.800152 38.747386) (xy 54.772504 38.820794) (xy 54.752545 38.896653)
			(xy 54.740484 38.974162) (xy 54.736449 39.0525) (xy 54.740484 39.130838) (xy 54.752545 39.208347)
			(xy 54.772504 39.284206) (xy 54.800152 39.357614) (xy 54.835194 39.427793) (xy 54.87726 39.494001)
			(xy 54.925906 39.555537) (xy 54.9529 39.583995) (xy 54.9529 40.005) (xy 51.828751 40.005) (xy 51.828751 39.996237)
			(xy 50.626137 39.996237) (xy 50.5079 39.878) (xy 48.3489 39.878) (xy 48.3489 39.765935) (xy 50.815443 39.765935)
			(xy 51.530352 39.765935) (xy 51.530352 39.523594) (xy 50.815443 39.523594) (xy 50.815443 39.765935)
			(xy 48.3489 39.765935) (xy 48.3489 39.287298) (xy 50.797257 39.287298) (xy 51.518236 39.287298) (xy 51.518236 39.014679)
			(xy 50.797257 39.014679) (xy 50.797257 39.287298) (xy 48.3489 39.287298) (xy 48.3489 38.778383) (xy 50.833604 38.778383)
			(xy 51.512165 38.778383) (xy 51.512165 38.529997) (xy 50.833604 38.529997) (xy 50.833604 38.778383)
			(xy 48.3489 38.778383) (xy 48.3489 38.600786) (xy 48.352939 38.596748) (xy 48.352939 38.481) (xy 49.3649 38.481)
			(xy 49.3649 38.354051) (xy 49.365662 38.354051) (xy 49.365662 38.1) (xy 49.6189 38.1) (xy 49.8729 38.1)
			(xy 49.8729 38.033198) (xy 50.058142 38.033198) (xy 50.342876 38.033198) (xy 50.342876 37.32436)
			(xy 50.058142 37.32436) (xy 50.058142 38.033198) (xy 49.8729 38.033198) (xy 49.8729 37.338) (xy 49.6189 37.338)
			(xy 49.6189 38.1) (xy 49.365662 38.1) (xy 49.365662 37.419686) (xy 49.692611 37.092738) (xy 49.692611 36.522711)
			(xy 50.88603 36.522711) (xy 50.899689 36.523156) (xy 50.926027 36.53041) (xy 50.949498 36.54439)
			(xy 50.968419 36.564095) (xy 50.981436 36.588113) (xy 50.987616 36.614723) (xy 50.986517 36.64202)
			(xy 50.978216 36.668047) (xy 50.971171 36.679759) (xy 50.954061 36.706933) (xy 50.926079 36.764733)
			(xy 50.905603 36.825598) (xy 50.89296 36.888558) (xy 50.888353 36.952609) (xy 50.891854 37.016731)
			(xy 50.903407 37.079899) (xy 50.922829 37.141109) (xy 50.949809 37.199383) (xy 50.983918 37.253792)
			(xy 51.024612 37.30347) (xy 51.071242 37.347623) (xy 51.123063 37.385547) (xy 51.179251 37.41664)
			(xy 51.238909 37.440403) (xy 51.301087 37.456459) (xy 51.364792 37.464551) (xy 51.429008 37.464551)
			(xy 51.492713 37.456459) (xy 51.554891 37.440403) (xy 51.614549 37.41664) (xy 51.670737 37.385547)
			(xy 51.722558 37.347623) (xy 51.769188 37.30347) (xy 51.809882 37.253792) (xy 51.843991 37.199383)
			(xy 51.870971 37.141109) (xy 51.890393 37.079899) (xy 51.901946 37.016731) (xy 51.905447 36.952609)
			(xy 51.9032 36.921364) (xy 53.378548 36.921364) (xy 53.378548 36.992636) (xy 53.386528 37.063459)
			(xy 53.402388 37.132943) (xy 53.425927 37.200215) (xy 53.45685 37.264428) (xy 53.494769 37.324775)
			(xy 53.539206 37.380498) (xy 53.589602 37.430894) (xy 53.645325 37.475331) (xy 53.705672 37.51325)
			(xy 53.769885 37.544173) (xy 53.837157 37.567712) (xy 53.906641 37.583572) (xy 53.977464 37.591552)
			(xy 54.048736 37.591552) (xy 54.119559 37.583572) (xy 54.189043 37.567712) (xy 54.256315 37.544173)
			(xy 54.320528 37.51325) (xy 54.380875 37.475331) (xy 54.436598 37.430894) (xy 54.486994 37.380498)
			(xy 54.531431 37.324775) (xy 54.56935 37.264428) (xy 54.600273 37.200215) (xy 54.623812 37.132943)
			(xy 54.639672 37.063459) (xy 54.647652 36.992636) (xy 54.648151 36.957) (xy 54.647652 36.921364)
			(xy 54.639672 36.850541) (xy 54.623812 36.781057) (xy 54.600273 36.713785) (xy 54.56935 36.649572)
			(xy 54.531431 36.589225) (xy 54.486994 36.533502) (xy 54.436598 36.483106) (xy 54.380875 36.438669)
			(xy 54.320528 36.40075) (xy 54.256315 36.369827) (xy 54.189043 36.346288) (xy 54.119559 36.330428)
			(xy 54.048736 36.322448) (xy 53.977464 36.322448) (xy 53.906641 36.330428) (xy 53.837157 36.346288)
			(xy 53.769885 36.369827) (xy 53.705672 36.40075) (xy 53.645325 36.438669) (xy 53.589602 36.483106)
			(xy 53.539206 36.533502) (xy 53.494769 36.589225) (xy 53.45685 36.649572) (xy 53.425927 36.713785)
			(xy 53.402388 36.781057) (xy 53.386528 36.850541) (xy 53.378548 36.921364) (xy 51.9032 36.921364)
			(xy 51.90084 36.888558) (xy 51.888197 36.825598) (xy 51.867721 36.764733) (xy 51.839739 36.706933)
			(xy 51.822629 36.679759) (xy 51.815541 36.668067) (xy 51.807237 36.642028) (xy 51.806137 36.614719)
			(xy 51.81232 36.588096) (xy 51.825343 36.564067) (xy 51.844273 36.544353) (xy 51.867754 36.530366)
			(xy 51.894105 36.523109) (xy 51.90777 36.522711) (xy 52.075359 36.522711) (xy 52.546428 36.068) (xy 54.952849 36.068)
		)
		(stroke
			(width 0)
			(type solid)
		)
		(fill yes)
		(layer "B.Cu")
		(net "EXT_12.0V")
	)
	(gr_poly
		(pts
			(xy 54.9529 42.164) (xy 55.943449 42.164) (xy 55.943449 42.164051) (xy 56.070551 42.164051) (xy 56.070551 42.164)
			(xy 57.213449 42.164) (xy 57.213449 42.164051) (xy 57.340551 42.164051) (xy 57.340551 42.164) (xy 57.658 42.164)
			(xy 57.658 43.18) (xy 54.9529 43.18) (xy 54.9529 43.474005) (xy 54.925906 43.502463) (xy 54.87726 43.563999)
			(xy 54.835194 43.630207) (xy 54.800152 43.700386) (xy 54.772504 43.773794) (xy 54.752545 43.849653)
			(xy 54.740484 43.927162) (xy 54.736449 44.0055) (xy 54.740484 44.083838) (xy 54.752545 44.161347)
			(xy 54.772504 44.237206) (xy 54.800152 44.310614) (xy 54.835194 44.380793) (xy 54.87726 44.447001)
			(xy 54.925906 44.508537) (xy 54.9529 44.536995) (xy 54.9529 45.826045) (xy 54.823716 45.955229) (xy 54.816935 45.962605)
			(xy 54.809277 45.981105) (xy 54.809284 46.001127) (xy 54.816953 46.019622) (xy 54.831118 46.033773)
			(xy 54.84962 46.041425) (xy 54.859631 46.041945) (xy 54.864 46.041945) (xy 54.864 52.197) (xy 46.8249 52.197)
			(xy 46.8249 50.666879) (xy 46.848494 50.644602) (xy 46.854618 50.637364) (xy 47.371448 50.637364)
			(xy 47.371448 50.708636) (xy 47.379428 50.779459) (xy 47.395288 50.848943) (xy 47.418827 50.916215)
			(xy 47.44975 50.980428) (xy 47.487669 51.040775) (xy 47.532106 51.096498) (xy 47.582502 51.146894)
			(xy 47.638225 51.191331) (xy 47.698572 51.22925) (xy 47.762785 51.260173) (xy 47.830057 51.283712)
			(xy 47.899541 51.299572) (xy 47.970364 51.307552) (xy 48.041636 51.307552) (xy 48.112459 51.299572)
			(xy 48.181943 51.283712) (xy 48.249215 51.260173) (xy 48.313428 51.22925) (xy 48.373775 51.191331)
			(xy 48.429498 51.146894) (xy 48.479894 51.096498) (xy 48.524331 51.040775) (xy 48.56225 50.980428)
			(xy 48.593173 50.916215) (xy 48.616712 50.848943) (xy 48.632572 50.779459) (xy 48.640552 50.708636)
			(xy 48.641051 50.673) (xy 48.640552 50.637364) (xy 48.632572 50.566541) (xy 48.616712 50.497057)
			(xy 48.593173 50.429785) (xy 48.56225 50.365572) (xy 48.524331 50.305225) (xy 48.479894 50.249502)
			(xy 48.429498 50.199106) (xy 48.373775 50.154669) (xy 48.313428 50.11675) (xy 48.249215 50.085827)
			(xy 48.181943 50.062288) (xy 48.112459 50.046428) (xy 48.041636 50.038448) (xy 47.970364 50.038448)
			(xy 47.899541 50.046428) (xy 47.830057 50.062288) (xy 47.762785 50.085827) (xy 47.698572 50.11675)
			(xy 47.638225 50.154669) (xy 47.582502 50.199106) (xy 47.532106 50.249502) (xy 47.487669 50.305225)
			(xy 47.44975 50.365572) (xy 47.418827 50.429785) (xy 47.395288 50.497057) (xy 47.379428 50.566541)
			(xy 47.371448 50.637364) (xy 46.854618 50.637364) (xy 46.890409 50.595065) (xy 46.925675 50.540594)
			(xy 46.953718 50.482075) (xy 46.974081 50.420463) (xy 46.986433 50.356758) (xy 46.990573 50.292)
			(xy 46.986433 50.227242) (xy 46.974081 50.163537) (xy 46.953718 50.101925) (xy 46.925675 50.043406)
			(xy 46.890409 49.988935) (xy 46.848494 49.939398) (xy 46.8249 49.917121) (xy 46.8249 49.556518) (xy 46.854356 49.53705)
			(xy 46.909192 49.492567) (xy 46.958754 49.442275) (xy 47.002432 49.386796) (xy 47.039686 49.326814)
			(xy 47.070057 49.26307) (xy 47.093169 49.19635) (xy 47.108738 49.127478) (xy 47.11657 49.057305)
			(xy 47.11657 48.986695) (xy 47.108738 48.916522) (xy 47.093169 48.84765) (xy 47.070057 48.78093)
			(xy 47.039686 48.717186) (xy 47.002432 48.657204) (xy 46.958754 48.601725) (xy 46.909192 48.551433)
			(xy 46.854356 48.50695) (xy 46.8249 48.487482) (xy 46.8249 48.126879) (xy 46.848494 48.104602) (xy 46.890409 48.055065)
			(xy 46.925675 48.000594) (xy 46.953718 47.942075) (xy 46.974081 47.880463) (xy 46.986433 47.816758)
			(xy 46.990573 47.752) (xy 46.986433 47.687242) (xy 46.974081 47.623537) (xy 46.953718 47.561925)
			(xy 46.925675 47.503406) (xy 46.890409 47.448935) (xy 46.848494 47.399398) (xy 46.8249 47.377121)
			(xy 46.8249 46.577068) (xy 47.40955 46.577068) (xy 47.40955 46.640932) (xy 47.417554 46.704293) (xy 47.433437 46.766152)
			(xy 47.456947 46.825532) (xy 47.487714 46.881497) (xy 47.525253 46.933164) (xy 47.568971 46.97972)
			(xy 47.61818 47.020428) (xy 47.672102 47.054649) (xy 47.729889 47.081841) (xy 47.790628 47.101576)
			(xy 47.853361 47.113543) (xy 47.9171 47.117554) (xy 47.980839 47.113543) (xy 48.043572 47.101576)
			(xy 48.104311 47.081841) (xy 48.162098 47.054649) (xy 48.21602 47.020428) (xy 48.265229 46.97972)
			(xy 48.308947 46.933164) (xy 48.346486 46.881497) (xy 48.377253 46.825532) (xy 48.400763 46.766152)
			(xy 48.416646 46.704293) (xy 48.42465 46.640932) (xy 48.425151 46.609) (xy 48.42465 46.577068) (xy 48.416646 46.513707)
			(xy 48.400763 46.451848) (xy 48.377253 46.392468) (xy 48.346486 46.336503) (xy 48.308947 46.284836)
			(xy 48.265229 46.23828) (xy 48.21602 46.197572) (xy 48.162098 46.163351) (xy 48.104311 46.136159)
			(xy 48.043572 46.116424) (xy 47.980839 46.104457) (xy 47.9171 46.100447) (xy 47.853361 46.104457)
			(xy 47.790628 46.116424) (xy 47.729889 46.136159) (xy 47.672102 46.163351) (xy 47.61818 46.197572)
			(xy 47.568971 46.23828) (xy 47.525253 46.284836) (xy 47.487714 46.336503) (xy 47.456947 46.392468)
			(xy 47.433437 46.451848) (xy 47.417554 46.513707) (xy 47.40955 46.577068) (xy 46.8249 46.577068)
			(xy 46.8249 45.085051) (xy 46.824951 45.085051) (xy 46.824951 44.246851) (xy 50.865659 44.246851)
			(xy 50.865659 43.283759) (xy 51.828751 43.283759) (xy 51.828751 40.462149) (xy 51.9049 40.386) (xy 54.9529 40.386)
		)
		(stroke
			(width 0)
			(type solid)
		)
		(fill yes)
		(layer "B.Cu")
		(net "GND")
	)
	(gr_poly
		(pts
			(xy 74.549 44.069) (xy 75.387149 44.069) (xy 75.387149 45.224751) (xy 79.248 45.224751) (xy 79.248 45.466)
			(xy 79.883 46.101) (xy 81.653278 46.101) (xy 81.668722 46.101) (xy 84.455 46.101) (xy 84.709 46.355)
			(xy 84.709 48.768) (xy 83.566 49.911) (xy 83.013093 49.911) (xy 82.989832 49.891091) (xy 82.939382 49.8564)
			(xy 82.885127 49.828023) (xy 82.827856 49.806372) (xy 82.768397 49.791762) (xy 82.707614 49.784403)
			(xy 82.646386 49.784403) (xy 82.585603 49.791762) (xy 82.526144 49.806372) (xy 82.468873 49.828023)
			(xy 82.414618 49.8564) (xy 82.364168 49.891091) (xy 82.340907 49.911) (xy 81.743093 49.911) (xy 81.719832 49.891091)
			(xy 81.669382 49.8564) (xy 81.615127 49.828023) (xy 81.557856 49.806372) (xy 81.498397 49.791762)
			(xy 81.437614 49.784403) (xy 81.376386 49.784403) (xy 81.315603 49.791762) (xy 81.256144 49.806372)
			(xy 81.198873 49.828023) (xy 81.144618 49.8564) (xy 81.094168 49.891091) (xy 81.070907 49.911) (xy 77.089 49.911)
			(xy 76.917855 49.739855) (xy 76.929412 49.709172) (xy 76.940347 49.67872) (xy 76.955294 49.615765)
			(xy 76.962126 49.551422) (xy 76.960733 49.486732) (xy 76.951139 49.422743) (xy 76.933497 49.36049)
			(xy 76.908094 49.300981) (xy 76.87534 49.245178) (xy 76.835767 49.193986) (xy 76.790014 49.148233)
			(xy 76.738822 49.10866) (xy 76.683019 49.075906) (xy 76.62351 49.050503) (xy 76.561257 49.032861)
			(xy 76.497268 49.023267) (xy 76.432578 49.021874) (xy 76.368235 49.028706) (xy 76.30528 49.043653)
			(xy 76.274828 49.054588) (xy 76.244145 49.066145) (xy 74.974196 47.796196) (xy 74.915877 47.713948)
			(xy 74.823897 47.593068) (xy 75.43845 47.593068) (xy 75.43845 47.656932) (xy 75.446454 47.720293)
			(xy 75.462337 47.782152) (xy 75.485847 47.841532) (xy 75.516614 47.897497) (xy 75.554153 47.949164)
			(xy 75.597871 47.99572) (xy 75.64708 48.036428) (xy 75.701002 48.070649) (xy 75.758789 48.097841)
			(xy 75.819528 48.117576) (xy 75.882261 48.129543) (xy 75.946 48.133554) (xy 76.009739 48.129543)
			(xy 76.072472 48.117576) (xy 76.133211 48.097841) (xy 76.190998 48.070649) (xy 76.24492 48.036428)
			(xy 76.294129 47.99572) (xy 76.337847 47.949164) (xy 76.375386 47.897497) (xy 76.406153 47.841532)
			(xy 76.429663 47.782152) (xy 76.445546 47.720293) (xy 76.45355 47.656932) (xy 76.454051 47.625) (xy 76.45355 47.593068)
			(xy 76.445546 47.529707) (xy 76.429663 47.467848) (xy 76.406153 47.408468) (xy 76.375386 47.352503)
			(xy 76.337847 47.300836) (xy 76.294129 47.25428) (xy 76.24492 47.213572) (xy 76.190998 47.179351)
			(xy 76.133211 47.152159) (xy 76.072472 47.132424) (xy 76.009739 47.120457) (xy 75.946 47.116447)
			(xy 75.882261 47.120457) (xy 75.819528 47.132424) (xy 75.758789 47.152159) (xy 75.701002 47.179351)
			(xy 75.64708 47.213572) (xy 75.597871 47.25428) (xy 75.554153 47.300836) (xy 75.516614 47.352503)
			(xy 75.485847 47.408468) (xy 75.462337 47.467848) (xy 75.446454 47.529707) (xy 75.43845 47.593068)
			(xy 74.823897 47.593068) (xy 74.793769 47.553473) (xy 74.665585 47.39781) (xy 74.531514 47.247187)
			(xy 74.391754 47.101827) (xy 74.24651 46.961946) (xy 74.095999 46.82775) (xy 73.940441 46.699436)
			(xy 73.780068 46.577196) (xy 73.697871 46.518805) (xy 73.694265 46.516265) (xy 73.64459 46.46659)
			(xy 74.54869 46.46659) (xy 74.550703 46.529752) (xy 74.560535 46.592177) (xy 74.578033 46.652901)
			(xy 74.602927 46.710986) (xy 74.634833 46.765535) (xy 74.673258 46.815705) (xy 74.717609 46.860722)
			(xy 74.767201 46.899892) (xy 74.821268 46.932608) (xy 74.878975 46.958365) (xy 74.939431 46.976767)
			(xy 75.001703 46.987528) (xy 75.064828 46.990484) (xy 75.127833 46.985587) (xy 75.189744 46.972913)
			(xy 75.249605 46.952659) (xy 75.306492 46.925137) (xy 75.359526 46.890773) (xy 75.407888 46.850095)
			(xy 75.440708 46.814664) (xy 80.137448 46.814664) (xy 80.137448 46.885936) (xy 80.145428 46.956759)
			(xy 80.161288 47.026243) (xy 80.184827 47.093515) (xy 80.21575 47.157728) (xy 80.253669 47.218075)
			(xy 80.298106 47.273798) (xy 80.348502 47.324194) (xy 80.404225 47.368631) (xy 80.464572 47.40655)
			(xy 80.528785 47.437473) (xy 80.596057 47.461012) (xy 80.665541 47.476872) (xy 80.736364 47.484852)
			(xy 80.807636 47.484852) (xy 80.878459 47.476872) (xy 80.947943 47.461012) (xy 81.015215 47.437473)
			(xy 81.079428 47.40655) (xy 81.139775 47.368631) (xy 81.195498 47.324194) (xy 81.245894 47.273798)
			(xy 81.290331 47.218075) (xy 81.32825 47.157728) (xy 81.359173 47.093515) (xy 81.382712 47.026243)
			(xy 81.398572 46.956759) (xy 81.406552 46.885936) (xy 81.407051 46.8503) (xy 81.406552 46.814664)
			(xy 81.398572 46.743841) (xy 81.382712 46.674357) (xy 81.359173 46.607085) (xy 81.32825 46.542872)
			(xy 81.290331 46.482525) (xy 81.245894 46.426802) (xy 81.195498 46.376406) (xy 81.139775 46.331969)
			(xy 81.079428 46.29405) (xy 81.015215 46.263127) (xy 80.947943 46.239588) (xy 80.878459 46.223728)
			(xy 80.807636 46.215748) (xy 80.736364 46.215748) (xy 80.665541 46.223728) (xy 80.596057 46.239588)
			(xy 80.528785 46.263127) (xy 80.464572 46.29405) (xy 80.404225 46.331969) (xy 80.348502 46.376406)
			(xy 80.298106 46.426802) (xy 80.253669 46.482525) (xy 80.21575 46.542872) (xy 80.184827 46.607085)
			(xy 80.161288 46.674357) (xy 80.145428 46.743841) (xy 80.137448 46.814664) (xy 75.440708 46.814664)
			(xy 75.450832 46.803734) (xy 75.487695 46.752405) (xy 75.517907 46.6969) (xy 75.541001 46.638076)
			(xy 75.549277 46.607578) (xy 75.552968 46.594775) (xy 75.56601 46.571551) (xy 75.584618 46.552494)
			(xy 75.607524 46.538901) (xy 75.633168 46.531699) (xy 75.659801 46.531379) (xy 75.68561 46.537962)
			(xy 75.697436 46.544103) (xy 75.725237 46.559127) (xy 75.783761 46.58297) (xy 75.844791 46.599371)
			(xy 75.907383 46.608075) (xy 75.970572 46.60895) (xy 76.033381 46.60198) (xy 76.094841 46.587275)
			(xy 76.154002 46.56506) (xy 76.209952 46.53568) (xy 76.261825 46.499587) (xy 76.308822 46.457339)
			(xy 76.350216 46.409588) (xy 76.385367 46.357072) (xy 76.413735 46.300602) (xy 76.434879 46.24105)
			(xy 76.448474 46.179335) (xy 76.45431 46.11641) (xy 76.452297 46.053248) (xy 76.442465 45.990823)
			(xy 76.424967 45.930099) (xy 76.400073 45.872014) (xy 76.368167 45.817465) (xy 76.329742 45.767295)
			(xy 76.285391 45.722278) (xy 76.235799 45.683108) (xy 76.181732 45.650392) (xy 76.124025 45.624635)
			(xy 76.063569 45.606233) (xy 76.001297 45.595472) (xy 75.938172 45.592516) (xy 75.875167 45.597413)
			(xy 75.813256 45.610087) (xy 75.753395 45.630341) (xy 75.696508 45.657863) (xy 75.643474 45.692227)
			(xy 75.595112 45.732905) (xy 75.552168 45.779266) (xy 75.515305 45.830595) (xy 75.485093 45.8861)
			(xy 75.461999 45.944924) (xy 75.453723 45.975422) (xy 75.450032 45.988225) (xy 75.43699 46.011449)
			(xy 75.418382 46.030506) (xy 75.395476 46.044099) (xy 75.369832 46.051301) (xy 75.343199 46.051621)
			(xy 75.31739 46.045038) (xy 75.305564 46.038897) (xy 75.277763 46.023873) (xy 75.219239 46.00003)
			(xy 75.158209 45.983629) (xy 75.095617 45.974925) (xy 75.032428 45.97405) (xy 74.969619 45.98102)
			(xy 74.908159 45.995725) (xy 74.848998 46.01794) (xy 74.793048 46.04732) (xy 74.741175 46.083413)
			(xy 74.694178 46.125661) (xy 74.652784 46.173412) (xy 74.617633 46.225928) (xy 74.589265 46.282398)
			(xy 74.568121 46.34195) (xy 74.554526 46.403665) (xy 74.54869 46.46659) (xy 73.64459 46.46659) (xy 72.771 45.593)
			(xy 71.229982 45.593) (xy 71.22734 45.592721) (xy 71.1327 45.583235) (xy 70.942915 45.570279) (xy 70.847864 45.566813)
			(xy 70.847839 45.566813) (xy 70.845197 45.569454) (xy 70.805929 45.568768) (xy 70.704927 45.56746)
			(xy 70.50295 45.571608) (xy 70.30128 45.583472) (xy 70.200698 45.592771) (xy 70.198234 45.593) (xy 68.707 45.593)
			(xy 67.956582 46.343418) (xy 67.951452 46.346567) (xy 67.862508 46.401673) (xy 67.688551 46.517988)
			(xy 67.519336 46.6411) (xy 67.355129 46.770815) (xy 67.275329 46.838489) (xy 67.264488 46.847146)
			(xy 67.239341 46.858833) (xy 67.211976 46.86332) (xy 67.184413 46.860274) (xy 67.158688 46.84992)
			(xy 67.136699 46.833024) (xy 67.120071 46.810832) (xy 67.114547 46.798103) (xy 67.10115 46.764968)
			(xy 67.067948 46.701673) (xy 67.027849 46.642507) (xy 66.98136 46.588216) (xy 66.92907 46.539489)
			(xy 66.871639 46.496941) (xy 66.809795 46.46111) (xy 66.744318 46.432449) (xy 66.676037 46.411321)
			(xy 66.605816 46.397994) (xy 66.534543 46.392635) (xy 66.463118 46.395312) (xy 66.392446 46.405992)
			(xy 66.323419 46.424539) (xy 66.256912 46.450719) (xy 66.225115 46.467039) (xy 66.211331 46.473761)
			(xy 66.18121 46.479454) (xy 66.150756 46.475961) (xy 66.122706 46.463596) (xy 66.099584 46.44347)
			(xy 66.091105 46.430692) (xy 66.074034 46.404008) (xy 66.034276 46.354689) (xy 65.988695 46.310696)
			(xy 65.937999 46.272712) (xy 65.882974 46.241324) (xy 65.824473 46.217021) (xy 65.763405 46.20018)
			(xy 65.700716 46.191061) (xy 65.637381 46.189807) (xy 65.574381 46.196437) (xy 65.512694 46.210848)
			(xy 65.453277 46.232816) (xy 65.424939 46.246974) (xy 65.412774 46.252822) (xy 65.386406 46.258552)
			(xy 65.359458 46.257174) (xy 65.333812 46.248784) (xy 65.31126 46.233968) (xy 65.293378 46.213762)
			(xy 65.281414 46.189576) (xy 65.276204 46.163101) (xy 65.276781 46.149616) (xy 65.27856 46.117663)
			(xy 65.275031 46.053764) (xy 65.263505 45.990814) (xy 65.244166 45.92981) (xy 65.217317 45.871717)
			(xy 65.183386 45.817456) (xy 65.142909 45.767886) (xy 65.096527 45.723792) (xy 65.044975 45.685871)
			(xy 64.989069 45.654726) (xy 64.929694 45.630848) (xy 64.86779 45.614615) (xy 64.804338 45.606285)
			(xy 64.740342 45.60599) (xy 64.676815 45.613735) (xy 64.614765 45.629396) (xy 64.555172 45.652725)
			(xy 64.498981 45.683355) (xy 64.447081 45.720798) (xy 64.400295 45.764463) (xy 64.359363 45.813657)
			(xy 64.324933 45.867603) (xy 64.29755 45.925446) (xy 64.277648 45.986269) (xy 64.265543 46.049111)
			(xy 64.261425 46.112975) (xy 64.265361 46.17685) (xy 64.277287 46.239726) (xy 64.297015 46.300606)
			(xy 64.324232 46.358526) (xy 64.358508 46.41257) (xy 64.3993 46.461881) (xy 64.422299 46.484134)
			(xy 64.432083 46.493956) (xy 64.446444 46.517655) (xy 64.4539 46.544344) (xy 64.4539 46.572056) (xy 64.446444 46.598745)
			(xy 64.432083 46.622444) (xy 64.422299 46.632266) (xy 64.398744 46.655079) (xy 64.357103 46.705736)
			(xy 64.322326 46.761329) (xy 64.294992 46.820935) (xy 64.275553 46.883563) (xy 64.264334 46.948171)
			(xy 64.261521 47.013685) (xy 64.267161 47.079017) (xy 64.273659 47.111158) (xy 64.276231 47.125028)
			(xy 64.274502 47.153173) (xy 64.265144 47.179773) (xy 64.248868 47.202801) (xy 64.226915 47.220499)
			(xy 64.20096 47.231521) (xy 64.187019 47.233662) (xy 64.156918 47.237876) (xy 64.097936 47.252565)
			(xy 64.041128 47.274187) (xy 63.987306 47.302431) (xy 63.937238 47.336896) (xy 63.89164 47.377088)
			(xy 63.851163 47.422434) (xy 63.8334 47.447098) (xy 63.825036 47.458318) (xy 63.803406 47.476058)
			(xy 63.777774 47.487263) (xy 63.750063 47.491094) (xy 63.722352 47.487263) (xy 63.69672 47.476058)
			(xy 63.67509 47.458318) (xy 63.666726 47.447098) (xy 63.648696 47.422053) (xy 63.607512 47.376093)
			(xy 63.561064 47.335461) (xy 63.510035 47.300754) (xy 63.455178 47.272485) (xy 63.3973 47.251069)
			(xy 63.337255 47.236822) (xy 63.275926 47.229953) (xy 63.214216 47.230565) (xy 63.153035 47.238647)
			(xy 63.093283 47.254081) (xy 63.035841 47.27664) (xy 62.981555 47.305991) (xy 62.931224 47.341702)
			(xy 62.908053 47.362085) (xy 62.896861 47.371612) (xy 62.870404 47.384386) (xy 62.841405 47.389097)
			(xy 62.812264 47.385356) (xy 62.785395 47.373473) (xy 62.763021 47.354432) (xy 62.746996 47.329808)
			(xy 62.738644 47.301641) (xy 62.738051 47.286951) (xy 62.738051 46.735949) (xy 62.695734 46.735949)
			(xy 62.681485 46.735476) (xy 62.654096 46.727607) (xy 62.62995 46.712473) (xy 62.610929 46.691253)
			(xy 62.598515 46.665602) (xy 62.593677 46.637519) (xy 62.596791 46.609192) (xy 62.601729 46.595817)
			(xy 62.614758 46.562718) (xy 62.634208 46.494293) (xy 62.64589 46.424122) (xy 62.649657 46.353087)
			(xy 62.645462 46.282074) (xy 62.633358 46.211976) (xy 62.615838 46.151724) (xy 62.865448 46.151724)
			(xy 62.865448 46.222996) (xy 62.873428 46.293819) (xy 62.889288 46.363303) (xy 62.912827 46.430575)
			(xy 62.94375 46.494788) (xy 62.981669 46.555135) (xy 63.026106 46.610858) (xy 63.076502 46.661254)
			(xy 63.132225 46.705691) (xy 63.192572 46.74361) (xy 63.256785 46.774533) (xy 63.324057 46.798072)
			(xy 63.393541 46.813932) (xy 63.464364 46.821912) (xy 63.535636 46.821912) (xy 63.606459 46.813932)
			(xy 63.675943 46.798072) (xy 63.743215 46.774533) (xy 63.807428 46.74361) (xy 63.867775 46.705691)
			(xy 63.923498 46.661254) (xy 63.973894 46.610858) (xy 64.018331 46.555135) (xy 64.05625 46.494788)
			(xy 64.087173 46.430575) (xy 64.110712 46.363303) (xy 64.126572 46.293819) (xy 64.134552 46.222996)
			(xy 64.135051 46.18736) (xy 64.134552 46.151724) (xy 64.126572 46.080901) (xy 64.110712 46.011417)
			(xy 64.087173 45.944145) (xy 64.05625 45.879932) (xy 64.018331 45.819585) (xy 63.973894 45.763862)
			(xy 63.923498 45.713466) (xy 63.867775 45.669029) (xy 63.807428 45.63111) (xy 63.743215 45.600187)
			(xy 63.675943 45.576648) (xy 63.606459 45.560788) (xy 63.535636 45.552808) (xy 63.464364 45.552808)
			(xy 63.393541 45.560788) (xy 63.324057 45.576648) (xy 63.256785 45.600187) (xy 63.192572 45.63111)
			(xy 63.132225 45.669029) (xy 63.076502 45.713466) (xy 63.026106 45.763862) (xy 62.981669 45.819585)
			(xy 62.94375 45.879932) (xy 62.912827 45.944145) (xy 62.889288 46.011417) (xy 62.873428 46.080901)
			(xy 62.865448 46.151724) (xy 62.615838 46.151724) (xy 62.613496 46.143669) (xy 62.586125 46.07801)
			(xy 62.551589 46.015821) (xy 62.510318 45.95788) (xy 62.462832 45.904915) (xy 62.409724 45.857588)
			(xy 62.35166 45.816493) (xy 62.289367 45.782143) (xy 62.223625 45.75497) (xy 62.155259 45.735314)
			(xy 62.085124 45.723421) (xy 62.0141 45.71944) (xy 61.943076 45.723421) (xy 61.872941 45.735314)
			(xy 61.804575 45.75497) (xy 61.738833 45.782143) (xy 61.67654 45.816493) (xy 61.618476 45.857588)
			(xy 61.565368 45.904915) (xy 61.517882 45.95788) (xy 61.476611 46.015821) (xy 61.442075 46.07801)
			(xy 61.414704 46.143669) (xy 61.394842 46.211976) (xy 61.382738 46.282074) (xy 61.378543 46.353087)
			(xy 61.38231 46.424122) (xy 61.393992 46.494293) (xy 61.413442 46.562718) (xy 61.426471 46.595817)
			(xy 61.431427 46.609177) (xy 61.434518 46.637492) (xy 61.429663 46.665558) (xy 61.417243 46.69119)
			(xy 61.398222 46.712392) (xy 61.374084 46.727512) (xy 61.346708 46.735374) (xy 61.332466 46.735949)
			(xy 61.095534 46.735949) (xy 61.081285 46.735476) (xy 61.053896 46.727607) (xy 61.02975 46.712473)
			(xy 61.010729 46.691253) (xy 60.998315 46.665602) (xy 60.993477 46.637519) (xy 60.996591 46.609192)
			(xy 61.001529 46.595817) (xy 61.014652 46.562501) (xy 61.03418 46.493607) (xy 61.045835 46.422954)
			(xy 61.049468 46.351438) (xy 61.045034 46.279968) (xy 61.032588 46.209449) (xy 61.012288 46.140779)
			(xy 60.984393 46.074827) (xy 60.949257 46.012432) (xy 60.907325 45.954386) (xy 60.859129 45.901425)
			(xy 60.805282 45.854221) (xy 60.746467 45.813374) (xy 60.68343 45.779402) (xy 60.616972 45.752737)
			(xy 60.547936 45.733716) (xy 60.477199 45.722582) (xy 60.405659 45.719475) (xy 60.334223 45.724436)
			(xy 60.263798 45.737401) (xy 60.195279 45.758205) (xy 60.129535 45.786585) (xy 60.0674 45.82218)
			(xy 60.009664 45.864538) (xy 59.957059 45.913123) (xy 59.910253 45.967316) (xy 59.86984 46.02643)
			(xy 59.836333 46.089715) (xy 59.810158 46.156368) (xy 59.791646 46.225542) (xy 59.781033 46.296359)
			(xy 59.778453 46.367921) (xy 59.78394 46.439318) (xy 59.797423 46.509645) (xy 59.818731 46.57801)
			(xy 59.847594 46.643543) (xy 59.883646 46.705414) (xy 59.926428 46.762837) (xy 59.975398 46.815082)
			(xy 60.029935 46.861488) (xy 60.089345 46.901465) (xy 60.152875 46.934505) (xy 60.219719 46.960188)
			(xy 60.289027 46.97819) (xy 60.35992 46.988282) (xy 60.431499 46.990334) (xy 60.502854 46.984322)
			(xy 60.57308 46.970322) (xy 60.641286 46.948511) (xy 60.706605 46.919166) (xy 60.768208 46.88266)
			(xy 60.797059 46.861451) (xy 60.80859 46.853311) (xy 60.834896 46.843112) (xy 60.862989 46.840501)
			(xy 60.890724 46.845678) (xy 60.915983 46.858248) (xy 60.936838 46.87725) (xy 60.951697 46.901235)
			(xy 60.959425 46.92837) (xy 60.959949 46.942477) (xy 60.959949 48.514051) (xy 62.738051 48.514051)
			(xy 62.738051 48.188601) (xy 62.738539 48.1739) (xy 62.746908 48.145715) (xy 62.762953 48.121077)
			(xy 62.785347 48.102025) (xy 62.812237 48.090135) (xy 62.841399 48.086391) (xy 62.870421 48.091102)
			(xy 62.896901 48.103879) (xy 62.908053 48.113467) (xy 62.931178 48.133908) (xy 62.981515 48.169627)
			(xy 63.035808 48.198985) (xy 63.093258 48.221549) (xy 63.153019 48.236987) (xy 63.214209 48.245071)
			(xy 63.275928 48.245683) (xy 63.337267 48.238813) (xy 63.397322 48.224563) (xy 63.455208 48.203142)
			(xy 63.510072 48.174866) (xy 63.561107 48.140152) (xy 63.60756 48.099511) (xy 63.648748 48.053541)
			(xy 63.666726 48.028454) (xy 63.67509 48.017234) (xy 63.69672 47.999494) (xy 63.722352 47.988289)
			(xy 63.750063 47.984458) (xy 63.777774 47.988289) (xy 63.803406 47.999494) (xy 63.825036 48.017234)
			(xy 63.8334 48.028454) (xy 63.851958 48.054205) (xy 63.894475 48.101338) (xy 63.942532 48.142808)
			(xy 63.99538 48.177967) (xy 64.052197 48.20627) (xy 64.112097 48.227274) (xy 64.174147 48.240653)
			(xy 64.23738 48.246197) (xy 64.300812 48.243822) (xy 64.363453 48.233563) (xy 64.424329 48.21558)
			(xy 64.48249 48.190154) (xy 64.53703 48.157681) (xy 64.587101 48.118667) (xy 64.631922 48.073719)
			(xy 64.670794 48.023538) (xy 64.703112 47.968906) (xy 64.728372 47.910673) (xy 64.746182 47.849746)
			(xy 64.756263 47.787076) (xy 64.758459 47.723638) (xy 64.752735 47.660421) (xy 64.746403 47.629318)
			(xy 64.743835 47.615448) (xy 64.745569 47.587305) (xy 64.75493 47.560708) (xy 64.771204 47.537683)
			(xy 64.793152 47.519983) (xy 64.819103 47.508956) (xy 64.833043 47.506814) (xy 64.863408 47.502552)
			(xy 64.922894 47.487675) (xy 64.980157 47.465746) (xy 65.034364 47.437084) (xy 65.084726 47.402106)
			(xy 65.130513 47.361319) (xy 65.171057 47.315319) (xy 65.20577 47.264772) (xy 65.234146 47.210415)
			(xy 65.245412 47.181897) (xy 65.251164 47.168105) (xy 65.269324 47.144389) (xy 65.293565 47.126938)
			(xy 65.321818 47.117243) (xy 65.351666 47.116133) (xy 65.380561 47.123702) (xy 65.393545 47.131097)
			(xy 65.419663 47.146583) (xy 65.47485 47.171912) (xy 65.532662 47.190482) (xy 65.592276 47.202029)
			(xy 65.652841 47.206388) (xy 65.713493 47.203497) (xy 65.773369 47.193398) (xy 65.802612 47.185224)
			(xy 65.817458 47.181398) (xy 65.848099 47.181846) (xy 65.877231 47.191354) (xy 65.902237 47.209068)
			(xy 65.92087 47.233396) (xy 65.926691 47.247581) (xy 65.940072 47.282364) (xy 65.973839 47.348803)
			(xy 66.015151 47.410833) (xy 66.06344 47.467601) (xy 66.118042 47.518327) (xy 66.178206 47.562312)
			(xy 66.243106 47.598952) (xy 66.311848 47.627744) (xy 66.347518 47.638538) (xy 66.360722 47.642814)
			(xy 66.384343 47.657361) (xy 66.403175 47.677731) (xy 66.415828 47.70242) (xy 66.421366 47.729603)
			(xy 66.41938 47.757273) (xy 66.410018 47.783387) (xy 66.402382 47.794977) (xy 66.351366 47.867541)
			(xy 66.253643 48.015603) (xy 66.20698 48.091039) (xy 66.203855 48.096145) (xy 65.659 48.641) (xy 65.659 49.307775)
			(xy 65.656816 49.314989) (xy 65.628968 49.408114) (xy 65.579304 49.596059) (xy 65.536587 49.785704)
			(xy 65.500874 49.976791) (xy 65.472213 50.169063) (xy 65.450643 50.362259) (xy 65.436194 50.556117)
			(xy 65.428885 50.750376) (xy 65.428368 50.847574) (xy 65.43128 50.950991) (xy 65.44411 51.157506)
			(xy 65.464928 51.363369) (xy 65.493701 51.568272) (xy 65.530386 51.771907) (xy 65.574929 51.973969)
			(xy 65.627262 52.174155) (xy 65.656816 52.273302) (xy 65.659 52.28049) (xy 65.659 52.578) (xy 65.823211 52.742211)
			(xy 65.827097 52.751634) (xy 65.846641 52.79893) (xy 65.88731 52.892853) (xy 65.908428 52.939467)
			(xy 65.913 52.9495) (xy 65.913 53.848) (xy 64.041858 53.848) (xy 64.026977 53.847478) (xy 63.998482 53.83889)
			(xy 63.973671 53.822454) (xy 63.954648 53.799566) (xy 63.943028 53.772167) (xy 63.939797 53.742581)
			(xy 63.945229 53.71332) (xy 63.951561 53.699842) (xy 63.965586 53.671606) (xy 63.987325 53.612424)
			(xy 64.001574 53.551007) (xy 64.008114 53.488299) (xy 64.006845 53.425264) (xy 63.997786 53.36287)
			(xy 63.981076 53.302077) (xy 63.956972 53.243818) (xy 63.925845 53.18899) (xy 63.888173 53.138434)
			(xy 63.844535 53.092929) (xy 63.795601 53.053172) (xy 63.742125 53.019776) (xy 63.684927 52.993254)
			(xy 63.624886 52.974012) (xy 63.562927 52.962348) (xy 63.5 52.95844) (xy 63.437073 52.962348) (xy 63.375114 52.974012)
			(xy 63.315073 52.993254) (xy 63.257875 53.019776) (xy 63.204399 53.053172) (xy 63.155465 53.092929)
			(xy 63.111827 53.138434) (xy 63.074155 53.18899) (xy 63.043028 53.243818) (xy 63.018924 53.302077)
			(xy 63.002214 53.36287) (xy 62.993155 53.425264) (xy 62.991886 53.488299) (xy 62.998426 53.551007)
			(xy 63.012675 53.612424) (xy 63.034414 53.671606) (xy 63.048439 53.699842) (xy 63.0548 53.71331)
			(xy 63.060233 53.74258) (xy 63.057001 53.772174) (xy 63.045378 53.799582) (xy 63.02635 53.822477)
			(xy 63.001531 53.838918) (xy 62.973027 53.847509) (xy 62.958142 53.848) (xy 60.833 53.848) (xy 59.150068 52.165068)
			(xy 61.21445 52.165068) (xy 61.21445 52.228932) (xy 61.222454 52.292293) (xy 61.238337 52.354152)
			(xy 61.261847 52.413532) (xy 61.292614 52.469497) (xy 61.330153 52.521164) (xy 61.373871 52.56772)
			(xy 61.42308 52.608428) (xy 61.477002 52.642649) (xy 61.534789 52.669841) (xy 61.595528 52.689576)
			(xy 61.658261 52.701543) (xy 61.722 52.705554) (xy 61.785739 52.701543) (xy 61.848472 52.689576)
			(xy 61.909211 52.669841) (xy 61.966998 52.642649) (xy 62.02092 52.608428) (xy 62.070129 52.56772)
			(xy 62.113847 52.521164) (xy 62.151386 52.469497) (xy 62.182153 52.413532) (xy 62.205663 52.354152)
			(xy 62.221546 52.292293) (xy 62.22955 52.228932) (xy 62.230051 52.197) (xy 62.22955 52.165068) (xy 62.48445 52.165068)
			(xy 62.48445 52.228932) (xy 62.492454 52.292293) (xy 62.508337 52.354152) (xy 62.531847 52.413532)
			(xy 62.562614 52.469497) (xy 62.600153 52.521164) (xy 62.643871 52.56772) (xy 62.69308 52.608428)
			(xy 62.747002 52.642649) (xy 62.804789 52.669841) (xy 62.865528 52.689576) (xy 62.928261 52.701543)
			(xy 62.992 52.705554) (xy 63.055739 52.701543) (xy 63.118472 52.689576) (xy 63.179211 52.669841)
			(xy 63.236998 52.642649) (xy 63.29092 52.608428) (xy 63.340129 52.56772) (xy 63.383847 52.521164)
			(xy 63.421386 52.469497) (xy 63.452153 52.413532) (xy 63.475663 52.354152) (xy 63.491546 52.292293)
			(xy 63.49955 52.228932) (xy 63.500051 52.197) (xy 63.49955 52.165068) (xy 63.491546 52.101707) (xy 63.475663 52.039848)
			(xy 63.452153 51.980468) (xy 63.421386 51.924503) (xy 63.383847 51.872836) (xy 63.340129 51.82628)
			(xy 63.29092 51.785572) (xy 63.236998 51.751351) (xy 63.179211 51.724159) (xy 63.118472 51.704424)
			(xy 63.055739 51.692457) (xy 62.992 51.688447) (xy 62.928261 51.692457) (xy 62.865528 51.704424)
			(xy 62.804789 51.724159) (xy 62.747002 51.751351) (xy 62.69308 51.785572) (xy 62.643871 51.82628)
			(xy 62.600153 51.872836) (xy 62.562614 51.924503) (xy 62.531847 51.980468) (xy 62.508337 52.039848)
			(xy 62.492454 52.101707) (xy 62.48445 52.165068) (xy 62.22955 52.165068) (xy 62.221546 52.101707)
			(xy 62.205663 52.039848) (xy 62.182153 51.980468) (xy 62.151386 51.924503) (xy 62.113847 51.872836)
			(xy 62.070129 51.82628) (xy 62.02092 51.785572) (xy 61.966998 51.751351) (xy 61.909211 51.724159)
			(xy 61.848472 51.704424) (xy 61.785739 51.692457) (xy 61.722 51.688447) (xy 61.658261 51.692457)
			(xy 61.595528 51.704424) (xy 61.534789 51.724159) (xy 61.477002 51.751351) (xy 61.42308 51.785572)
			(xy 61.373871 51.82628) (xy 61.330153 51.872836) (xy 61.292614 51.924503) (xy 61.261847 51.980468)
			(xy 61.238337 52.039848) (xy 61.222454 52.101707) (xy 61.21445 52.165068) (xy 59.150068 52.165068)
			(xy 59.055 52.07) (xy 59.055 50.407443) (xy 59.092643 50.397334) (xy 59.127415 50.387472) (xy 59.194644 50.360928)
			(xy 59.258424 50.326922) (xy 59.317931 50.285895) (xy 59.372395 50.238376) (xy 59.421112 50.184981)
			(xy 59.463451 50.126399) (xy 59.498864 50.06339) (xy 59.526895 49.996767) (xy 59.54718 49.927392)
			(xy 59.559456 49.856163) (xy 59.563566 49.784) (xy 59.559456 49.711837) (xy 59.54718 49.640608) (xy 59.526895 49.571233)
			(xy 59.498864 49.50461) (xy 59.463451 49.441601) (xy 59.421112 49.383019) (xy 59.372395 49.329624)
			(xy 59.317931 49.282105) (xy 59.258424 49.241078) (xy 59.194644 49.207072) (xy 59.127415 49.180528)
			(xy 59.092643 49.170666) (xy 59.055 49.160557) (xy 59.055 48.183851) (xy 59.563051 48.183851) (xy 59.563051 46.405749)
			(xy 59.055 46.405749) (xy 59.055 45.847) (xy 60.071 44.831) (xy 62.611 44.831) (xy 62.611 44.42681)
			(xy 62.633008 44.392697) (xy 62.670446 44.320658) (xy 62.700014 44.245048) (xy 62.721377 44.166723)
			(xy 62.734293 44.086571) (xy 62.738614 44.0055) (xy 62.734293 43.924429) (xy 62.721377 43.844277)
			(xy 62.700014 43.765952) (xy 62.670446 43.690342) (xy 62.633008 43.618303) (xy 62.611 43.58419) (xy 62.611 43.18)
			(xy 60.198 43.18) (xy 60.198 42.291) (xy 62.483949 42.291) (xy 62.483949 42.672051) (xy 63.626949 42.672051)
			(xy 63.626949 45.212051) (xy 64.007975 45.212051) (xy 64.029134 45.239491) (xy 64.076502 45.290069)
			(xy 64.129094 45.33519) (xy 64.186287 45.374316) (xy 64.247399 45.406983) (xy 64.311704 45.432803)
			(xy 64.378438 45.451468) (xy 64.446808 45.462756) (xy 64.516 45.466534) (xy 64.585192 45.462756)
			(xy 64.653562 45.451468) (xy 64.720296 45.432803) (xy 64.784601 45.406983) (xy 64.845713 45.374316)
			(xy 64.902906 45.33519) (xy 64.955498 45.290069) (xy 65.002866 45.239491) (xy 65.024025 45.212051)
			(xy 66.421051 45.212051) (xy 66.421051 44.246851) (xy 70.461759 44.246851) (xy 70.461759 43.283759)
			(xy 71.424851 43.283759) (xy 71.424851 40.462149) (xy 71.501 40.386) (xy 74.549 40.386)
		)
		(stroke
			(width 0)
			(type solid)
		)
		(fill yes)
		(layer "B.Cu")
		(net "GND")
	)
	(gr_line
		(start 3.683 31.369)
		(end 3.683 36.195)
		(stroke
			(width 0.254)
			(type default)
		)
		(layer "In5.Cu")
	)
	(gr_line
		(start 3.683 36.195)
		(end 7.366 36.195)
		(stroke
			(width 0.254)
			(type default)
		)
		(layer "In5.Cu")
	)
	(gr_line
		(start 7.366 36.195)
		(end 7.747 36.576)
		(stroke
			(width 0.254)
			(type default)
		)
		(layer "In5.Cu")
	)
	(gr_line
		(start 7.747 36.576)
		(end 7.747 44.831)
		(stroke
			(width 0.254)
			(type default)
		)
		(layer "In5.Cu")
	)
	(gr_line
		(start 7.747 44.831)
		(end 11.303 44.831)
		(stroke
			(width 0.254)
			(type default)
		)
		(layer "In5.Cu")
	)
	(gr_line
		(start 11.303 44.831)
		(end 11.303 47.498)
		(stroke
			(width 0.254)
			(type default)
		)
		(layer "In5.Cu")
	)
	(gr_line
		(start 11.303 47.498)
		(end 27.813 47.498)
		(stroke
			(width 0.254)
			(type default)
		)
		(layer "In5.Cu")
	)
	(gr_line
		(start 17.653 31.369)
		(end 38.735 31.369)
		(stroke
			(width 0.254)
			(type default)
		)
		(layer "In5.Cu")
	)
	(gr_line
		(start 17.653 37.465)
		(end 17.653 31.369)
		(stroke
			(width 0.254)
			(type default)
		)
		(layer "In5.Cu")
	)
	(gr_line
		(start 18.923 31.369)
		(end 3.683 31.369)
		(stroke
			(width 0.254)
			(type default)
		)
		(layer "In5.Cu")
	)
	(gr_line
		(start 27.813 47.498)
		(end 27.813 50.292)
		(stroke
			(width 0.254)
			(type default)
		)
		(layer "In5.Cu")
	)
	(gr_line
		(start 38.735 9.906)
		(end 44.196 9.906)
		(stroke
			(width 0.254)
			(type default)
		)
		(layer "In5.Cu")
	)
	(gr_line
		(start 38.735 10.033)
		(end 38.735 9.906)
		(stroke
			(width 0.254)
			(type default)
		)
		(layer "In5.Cu")
	)
	(gr_line
		(start 38.735 31.369)
		(end 38.735 10.033)
		(stroke
			(width 0.254)
			(type default)
		)
		(layer "In5.Cu")
	)
	(gr_line
		(start 41.529 37.465)
		(end 44.323 37.465)
		(stroke
			(width 0.254)
			(type default)
		)
		(layer "In5.Cu")
	)
	(gr_line
		(start 41.529 43.053)
		(end 41.529 37.465)
		(stroke
			(width 0.254)
			(type default)
		)
		(layer "In5.Cu")
	)
	(gr_line
		(start 43.688 18.542)
		(end 43.688 35.052)
		(stroke
			(width 0.254)
			(type default)
		)
		(layer "In5.Cu")
	)
	(gr_line
		(start 43.688 35.052)
		(end 44.323 35.687)
		(stroke
			(width 0.254)
			(type default)
		)
		(layer "In5.Cu")
	)
	(gr_line
		(start 44.196 9.906)
		(end 44.196 11.303)
		(stroke
			(width 0.254)
			(type default)
		)
		(layer "In5.Cu")
	)
	(gr_line
		(start 44.196 11.303)
		(end 44.45 11.557)
		(stroke
			(width 0.254)
			(type default)
		)
		(layer "In5.Cu")
	)
	(gr_line
		(start 44.323 35.687)
		(end 44.323 37.465)
		(stroke
			(width 0.254)
			(type default)
		)
		(layer "In5.Cu")
	)
	(gr_line
		(start 44.323 37.465)
		(end 17.653 37.465)
		(stroke
			(width 0.254)
			(type default)
		)
		(layer "In5.Cu")
	)
	(gr_line
		(start 44.323 45.847)
		(end 41.529 43.053)
		(stroke
			(width 0.254)
			(type default)
		)
		(layer "In5.Cu")
	)
	(gr_line
		(start 44.45 11.557)
		(end 44.958 11.557)
		(stroke
			(width 0.254)
			(type default)
		)
		(layer "In5.Cu")
	)
	(gr_line
		(start 44.958 11.557)
		(end 45.212 11.811)
		(stroke
			(width 0.254)
			(type default)
		)
		(layer "In5.Cu")
	)
	(gr_line
		(start 45.212 11.811)
		(end 45.212 17.018)
		(stroke
			(width 0.254)
			(type default)
		)
		(layer "In5.Cu")
	)
	(gr_line
		(start 45.212 17.018)
		(end 43.688 18.542)
		(stroke
			(width 0.254)
			(type default)
		)
		(layer "In5.Cu")
	)
	(gr_line
		(start 49.149 8.636)
		(end 49.149 9.906)
		(stroke
			(width 0.254)
			(type default)
		)
		(layer "In5.Cu")
	)
	(gr_line
		(start 49.149 9.906)
		(end 43.815 9.906)
		(stroke
			(width 0.254)
			(type default)
		)
		(layer "In5.Cu")
	)
	(gr_line
		(start 49.784 7.62)
		(end 49.784 8.636)
		(stroke
			(width 0.254)
			(type default)
		)
		(layer "In5.Cu")
	)
	(gr_line
		(start 49.784 8.636)
		(end 49.149 8.636)
		(stroke
			(width 0.254)
			(type default)
		)
		(layer "In5.Cu")
	)
	(gr_line
		(start 60.833 16.51)
		(end 60.833 21.463)
		(stroke
			(width 0.254)
			(type default)
		)
		(layer "In5.Cu")
	)
	(gr_line
		(start 60.833 21.463)
		(end 61.722 22.352)
		(stroke
			(width 0.254)
			(type default)
		)
		(layer "In5.Cu")
	)
	(gr_line
		(start 60.833 27.305)
		(end 60.833 27.686)
		(stroke
			(width 0.254)
			(type default)
		)
		(layer "In5.Cu")
	)
	(gr_line
		(start 60.833 27.686)
		(end 61.722 28.575)
		(stroke
			(width 0.254)
			(type default)
		)
		(layer "In5.Cu")
	)
	(gr_line
		(start 61.722 22.352)
		(end 61.722 26.416)
		(stroke
			(width 0.254)
			(type default)
		)
		(layer "In5.Cu")
	)
	(gr_line
		(start 61.722 26.416)
		(end 60.833 27.305)
		(stroke
			(width 0.254)
			(type default)
		)
		(layer "In5.Cu")
	)
	(gr_line
		(start 61.722 28.575)
		(end 61.722 34.671)
		(stroke
			(width 0.254)
			(type default)
		)
		(layer "In5.Cu")
	)
	(gr_line
		(start 61.722 34.671)
		(end 69.723 34.671)
		(stroke
			(width 0.254)
			(type default)
		)
		(layer "In5.Cu")
	)
	(gr_line
		(start 61.976 2.921)
		(end 61.976 15.367)
		(stroke
			(width 0.254)
			(type default)
		)
		(layer "In5.Cu")
	)
	(gr_line
		(start 61.976 7.62)
		(end 49.784 7.62)
		(stroke
			(width 0.254)
			(type default)
		)
		(layer "In5.Cu")
	)
	(gr_line
		(start 61.976 15.367)
		(end 60.833 16.51)
		(stroke
			(width 0.254)
			(type default)
		)
		(layer "In5.Cu")
	)
	(gr_line
		(start 64.643 -3.302)
		(end 64.643 2.921)
		(stroke
			(width 0.254)
			(type default)
		)
		(layer "In5.Cu")
	)
	(gr_line
		(start 64.643 2.921)
		(end 61.976 2.921)
		(stroke
			(width 0.254)
			(type default)
		)
		(layer "In5.Cu")
	)
	(gr_line
		(start 69.723 34.671)
		(end 69.723 45.847)
		(stroke
			(width 0.254)
			(type default)
		)
		(layer "In5.Cu")
	)
	(gr_line
		(start 69.723 45.847)
		(end 74.549 45.847)
		(stroke
			(width 0.254)
			(type default)
		)
		(layer "In5.Cu")
	)
	(gr_line
		(start 70.612 45.847)
		(end 44.323 45.847)
		(stroke
			(width 0.254)
			(type default)
		)
		(layer "In5.Cu")
	)
	(gr_line
		(start 74.549 45.847)
		(end 74.549 53.721)
		(stroke
			(width 0.254)
			(type default)
		)
		(layer "In5.Cu")
	)
	(gr_line
		(start 74.549 53.721)
		(end 79.121 53.721)
		(stroke
			(width 0.254)
			(type default)
		)
		(layer "In5.Cu")
	)
	(gr_line
		(start 76.454 38.862)
		(end 84.709 38.862)
		(stroke
			(width 0.254)
			(type default)
		)
		(layer "In5.Cu")
	)
	(gr_line
		(start 76.454 43.561)
		(end 76.454 38.862)
		(stroke
			(width 0.254)
			(type default)
		)
		(layer "In5.Cu")
	)
	(gr_line
		(start 77.724 32.639)
		(end 85.09 32.639)
		(stroke
			(width 0.254)
			(type default)
		)
		(layer "In5.Cu")
	)
	(gr_line
		(start 77.724 34.29)
		(end 77.724 32.639)
		(stroke
			(width 0.254)
			(type default)
		)
		(layer "In5.Cu")
	)
	(gr_line
		(start 79.121 48.641)
		(end 88.138 48.641)
		(stroke
			(width 0.254)
			(type default)
		)
		(layer "In5.Cu")
	)
	(gr_line
		(start 79.121 53.721)
		(end 79.121 48.641)
		(stroke
			(width 0.254)
			(type default)
		)
		(layer "In5.Cu")
	)
	(gr_line
		(start 84.709 34.29)
		(end 77.724 34.29)
		(stroke
			(width 0.254)
			(type default)
		)
		(layer "In5.Cu")
	)
	(gr_line
		(start 84.709 38.862)
		(end 84.709 34.29)
		(stroke
			(width 0.254)
			(type default)
		)
		(layer "In5.Cu")
	)
	(gr_line
		(start 85.09 21.971)
		(end 88.138 21.971)
		(stroke
			(width 0.254)
			(type default)
		)
		(layer "In5.Cu")
	)
	(gr_line
		(start 85.09 32.639)
		(end 85.09 21.971)
		(stroke
			(width 0.254)
			(type default)
		)
		(layer "In5.Cu")
	)
	(gr_line
		(start 88.138 43.561)
		(end 76.454 43.561)
		(stroke
			(width 0.254)
			(type default)
		)
		(layer "In5.Cu")
	)
	(gr_line
		(start 117.729 -50.8)
		(end 117.602 -50.8)
		(stroke
			(width 0.254)
			(type default)
		)
		(layer "In5.Cu")
	)
	(gr_poly
		(pts
			(xy 13.97 38.735) (xy 13.97 40.462327) (xy 13.969544 40.472145) (xy 13.962156 40.49034) (xy 13.948472 40.504426)
			(xy 13.930499 40.512338) (xy 13.920699 40.513102) (xy 13.892742 40.514417) (xy 13.83764 40.524228)
			(xy 13.784566 40.541993) (xy 13.734662 40.56733) (xy 13.689 40.599694) (xy 13.648563 40.638389) (xy 13.614222 40.682583)
			(xy 13.586714 40.731325) (xy 13.566632 40.783566) (xy 13.554407 40.838183) (xy 13.550303 40.894)
			(xy 13.554407 40.949817) (xy 13.566632 41.004434) (xy 13.586714 41.056675) (xy 13.614222 41.105417)
			(xy 13.648563 41.149611) (xy 13.689 41.188306) (xy 13.734662 41.22067) (xy 13.784566 41.246007) (xy 13.83764 41.263772)
			(xy 13.892742 41.273583) (xy 13.920699 41.274898) (xy 13.930505 41.275638) (xy 13.948486 41.283554)
			(xy 13.962176 41.297646) (xy 13.969568 41.31585) (xy 13.97 41.325673) (xy 13.97 44.069) (xy 12.7 45.339)
			(xy 7.239 45.339) (xy 7.239 41.783) (xy 11.72154 41.783) (xy 11.725606 41.838556) (xy 11.737717 41.892927)
			(xy 11.757617 41.944956) (xy 11.784879 41.993533) (xy 11.818924 42.037622) (xy 11.859026 42.076285)
			(xy 11.90433 42.108697) (xy 11.95387 42.134168) (xy 12.006591 42.152154) (xy 12.061368 42.162272)
			(xy 12.117035 42.164306) (xy 12.172405 42.158213) (xy 12.226298 42.144124) (xy 12.277566 42.122338)
			(xy 12.325114 42.093319) (xy 12.367931 42.057687) (xy 12.405104 42.0162) (xy 12.43584 41.969743)
			(xy 12.459484 41.919305) (xy 12.475532 41.865963) (xy 12.483643 41.810852) (xy 12.484151 41.783)
			(xy 12.82644 41.783) (xy 12.830506 41.838556) (xy 12.842617 41.892927) (xy 12.862517 41.944956) (xy 12.889779 41.993533)
			(xy 12.923824 42.037622) (xy 12.963926 42.076285) (xy 13.00923 42.108697) (xy 13.05877 42.134168)
			(xy 13.111491 42.152154) (xy 13.166268 42.162272) (xy 13.221935 42.164306) (xy 13.277305 42.158213)
			(xy 13.331198 42.144124) (xy 13.382466 42.122338) (xy 13.430014 42.093319) (xy 13.472831 42.057687)
			(xy 13.510004 42.0162) (xy 13.54074 41.969743) (xy 13.564384 41.919305) (xy 13.580432 41.865963)
			(xy 13.588543 41.810852) (xy 13.589051 41.783) (xy 13.588543 41.755148) (xy 13.580432 41.700037)
			(xy 13.564384 41.646695) (xy 13.54074 41.596257) (xy 13.510004 41.5498) (xy 13.472831 41.508313)
			(xy 13.430014 41.472681) (xy 13.382466 41.443662) (xy 13.331198 41.421876) (xy 13.277305 41.407787)
			(xy 13.221935 41.401694) (xy 13.166268 41.403728) (xy 13.111491 41.413846) (xy 13.05877 41.431832)
			(xy 13.00923 41.457303) (xy 12.963926 41.489715) (xy 12.923824 41.528378) (xy 12.889779 41.572467)
			(xy 12.862517 41.621044) (xy 12.842617 41.673073) (xy 12.830506 41.727444) (xy 12.82644 41.783) (xy 12.484151 41.783)
			(xy 12.483643 41.755148) (xy 12.475532 41.700037) (xy 12.459484 41.646695) (xy 12.43584 41.596257)
			(xy 12.405104 41.5498) (xy 12.367931 41.508313) (xy 12.325114 41.472681) (xy 12.277566 41.443662)
			(xy 12.226298 41.421876) (xy 12.172405 41.407787) (xy 12.117035 41.401694) (xy 12.061368 41.403728)
			(xy 12.006591 41.413846) (xy 11.95387 41.431832) (xy 11.90433 41.457303) (xy 11.859026 41.489715)
			(xy 11.818924 41.528378) (xy 11.784879 41.572467) (xy 11.757617 41.621044) (xy 11.737717 41.673073)
			(xy 11.725606 41.727444) (xy 11.72154 41.783) (xy 7.239 41.783) (xy 7.239 41.000756) (xy 7.268896 40.987269)
			(xy 7.293597 40.975594) (xy 7.339664 40.946219) (xy 7.381063 40.910566) (xy 7.416946 40.869366) (xy 7.446577 40.823463)
			(xy 7.469349 40.7738) (xy 7.484795 40.721393) (xy 7.485544 40.7162) (xy 8.67354 40.7162) (xy 8.677606 40.771756)
			(xy 8.689717 40.826127) (xy 8.709617 40.878156) (xy 8.736879 40.926733) (xy 8.770924 40.970822) (xy 8.811026 41.009485)
			(xy 8.85633 41.041897) (xy 8.90587 41.067368) (xy 8.958591 41.085354) (xy 9.013368 41.095472) (xy 9.069035 41.097506)
			(xy 9.124405 41.091413) (xy 9.178298 41.077324) (xy 9.229566 41.055538) (xy 9.277114 41.026519) (xy 9.319931 40.990887)
			(xy 9.357104 40.9494) (xy 9.38784 40.902943) (xy 9.392032 40.894) (xy 10.12134 40.894) (xy 10.125406 40.949556)
			(xy 10.137517 41.003927) (xy 10.157417 41.055956) (xy 10.184679 41.104533) (xy 10.218724 41.148622)
			(xy 10.258826 41.187285) (xy 10.30413 41.219697) (xy 10.35367 41.245168) (xy 10.406391 41.263154)
			(xy 10.461168 41.273272) (xy 10.516835 41.275306) (xy 10.572205 41.269213) (xy 10.626098 41.255124)
			(xy 10.677366 41.233338) (xy 10.724914 41.204319) (xy 10.767731 41.168687) (xy 10.804904 41.1272)
			(xy 10.83564 41.080743) (xy 10.859284 41.030305) (xy 10.875332 40.976963) (xy 10.883443 40.921852)
			(xy 10.883951 40.894) (xy 11.72154 40.894) (xy 11.725606 40.949556) (xy 11.737717 41.003927) (xy 11.757617 41.055956)
			(xy 11.784879 41.104533) (xy 11.818924 41.148622) (xy 11.859026 41.187285) (xy 11.90433 41.219697)
			(xy 11.95387 41.245168) (xy 12.006591 41.263154) (xy 12.061368 41.273272) (xy 12.117035 41.275306)
			(xy 12.172405 41.269213) (xy 12.226298 41.255124) (xy 12.277566 41.233338) (xy 12.325114 41.204319)
			(xy 12.367931 41.168687) (xy 12.405104 41.1272) (xy 12.43584 41.080743) (xy 12.459484 41.030305)
			(xy 12.475532 40.976963) (xy 12.483643 40.921852) (xy 12.484151 40.894) (xy 12.483643 40.866148)
			(xy 12.475532 40.811037) (xy 12.459484 40.757695) (xy 12.43584 40.707257) (xy 12.405104 40.6608)
			(xy 12.367931 40.619313) (xy 12.325114 40.583681) (xy 12.277566 40.554662) (xy 12.226298 40.532876)
			(xy 12.172405 40.518787) (xy 12.117035 40.512694) (xy 12.061368 40.514728) (xy 12.006591 40.524846)
			(xy 11.95387 40.542832) (xy 11.90433 40.568303) (xy 11.859026 40.600715) (xy 11.818924 40.639378)
			(xy 11.784879 40.683467) (xy 11.757617 40.732044) (xy 11.737717 40.784073) (xy 11.725606 40.838444)
			(xy 11.72154 40.894) (xy 10.883951 40.894) (xy 10.883443 40.866148) (xy 10.875332 40.811037) (xy 10.859284 40.757695)
			(xy 10.83564 40.707257) (xy 10.804904 40.6608) (xy 10.767731 40.619313) (xy 10.724914 40.583681)
			(xy 10.677366 40.554662) (xy 10.626098 40.532876) (xy 10.572205 40.518787) (xy 10.516835 40.512694)
			(xy 10.461168 40.514728) (xy 10.406391 40.524846) (xy 10.35367 40.542832) (xy 10.30413 40.568303)
			(xy 10.258826 40.600715) (xy 10.218724 40.639378) (xy 10.184679 40.683467) (xy 10.157417 40.732044)
			(xy 10.137517 40.784073) (xy 10.125406 40.838444) (xy 10.12134 40.894) (xy 9.392032 40.894) (xy 9.411484 40.852505)
			(xy 9.427532 40.799163) (xy 9.435643 40.744052) (xy 9.436151 40.7162) (xy 9.435643 40.688348) (xy 9.427532 40.633237)
			(xy 9.411484 40.579895) (xy 9.38784 40.529457) (xy 9.357104 40.483) (xy 9.319931 40.441513) (xy 9.277114 40.405881)
			(xy 9.229566 40.376862) (xy 9.178298 40.355076) (xy 9.124405 40.340987) (xy 9.069035 40.334894) (xy 9.013368 40.336928)
			(xy 8.958591 40.347046) (xy 8.90587 40.365032) (xy 8.85633 40.390503) (xy 8.811026 40.422915) (xy 8.770924 40.461578)
			(xy 8.736879 40.505667) (xy 8.709617 40.554244) (xy 8.689717 40.606273) (xy 8.677606 40.660644) (xy 8.67354 40.7162)
			(xy 7.485544 40.7162) (xy 7.492597 40.667318) (xy 7.492597 40.612682) (xy 7.484795 40.558607) (xy 7.469349 40.5062)
			(xy 7.446577 40.456537) (xy 7.416946 40.410634) (xy 7.381063 40.369434) (xy 7.339664 40.333781) (xy 7.293597 40.304406)
			(xy 7.268896 40.292731) (xy 7.239 40.279244) (xy 7.239 39.37) (xy 11.684 39.37) (xy 12.573 38.481)
			(xy 13.716 38.481)
		)
		(stroke
			(width 0)
			(type solid)
		)
		(fill yes)
		(layer "In6.Cu")
		(net "VDD_1.5V")
	)
	(gr_poly
		(pts
			(xy 17.014774 38.922376) (xy 18.925743 38.922376) (xy 18.935802 38.960095) (xy 18.943404 38.986713)
			(xy 18.96524 39.03758) (xy 18.994204 39.084754) (xy 19.029688 39.127241) (xy 19.05 39.146048) (xy 19.05 40.419604)
			(xy 19.049481 40.434502) (xy 19.040883 40.463032) (xy 19.02442 40.487868) (xy 19.001491 40.506897)
			(xy 18.974047 40.518503) (xy 18.944422 40.521697) (xy 18.92968 40.519477) (xy 18.902173 40.514818)
			(xy 18.846427 40.512648) (xy 18.79096 40.518631) (xy 18.736958 40.532637) (xy 18.685576 40.554367)
			(xy 18.637912 40.583358) (xy 18.594984 40.618989) (xy 18.557711 40.660498) (xy 18.526888 40.706999)
			(xy 18.503176 40.757497) (xy 18.48708 40.810914) (xy 18.478945 40.866106) (xy 18.478945 40.921894)
			(xy 18.48708 40.977086) (xy 18.503176 41.030503) (xy 18.526888 41.081001) (xy 18.557711 41.127502)
			(xy 18.594984 41.169011) (xy 18.637912 41.204642) (xy 18.685576 41.233633) (xy 18.736958 41.255363)
			(xy 18.79096 41.269369) (xy 18.846427 41.275352) (xy 18.902173 41.273182) (xy 18.92968 41.268523)
			(xy 18.944421 41.266287) (xy 18.974051 41.269482) (xy 19.0015 41.281089) (xy 19.024432 41.300121)
			(xy 19.040898 41.324961) (xy 19.049497 41.353495) (xy 19.05 41.368396) (xy 19.05 45.465898) (xy 18.980328 45.535596)
			(xy 18.965977 45.538822) (xy 18.938689 45.545505) (xy 18.886305 45.565804) (xy 18.837469 45.593574)
			(xy 18.793239 45.628214) (xy 18.754575 45.668972) (xy 18.722314 45.714965) (xy 18.697156 45.765197)
			(xy 18.679646 45.818578) (xy 18.670163 45.873951) (xy 18.668914 45.930117) (xy 18.675924 45.985858)
			(xy 18.691042 46.039965) (xy 18.713941 46.091266) (xy 18.728614 46.115224) (xy 18.75536 46.15721)
			(xy 18.666714 46.216214) (xy 18.647867 46.224038) (xy 18.638037 46.225993) (xy 18.629122 46.227771)
			(xy 15.557729 46.227771) (xy 15.554376 46.224419) (xy 15.554376 46.126324) (xy 15.562224 46.113903)
			(xy 15.576543 46.090302) (xy 15.598965 46.039859) (xy 15.613874 45.986708) (xy 15.620958 45.931962)
			(xy 15.620068 45.876767) (xy 15.611223 45.822279) (xy 15.594608 45.769636) (xy 15.570571 45.719942)
			(xy 15.539615 45.674237) (xy 15.502388 45.633477) (xy 15.459669 45.598514) (xy 15.412353 45.570082)
			(xy 15.361428 45.548775) (xy 15.307963 45.535039) (xy 15.253074 45.529162) (xy 15.197912 45.531266)
			(xy 15.143631 45.541308) (xy 15.091367 45.559077) (xy 15.042214 45.584202) (xy 15.019426 45.599782)
			(xy 15.007822 45.60749) (xy 14.981604 45.616876) (xy 14.953826 45.618834) (xy 14.926551 45.613217)
			(xy 14.901806 45.600444) (xy 14.881429 45.581463) (xy 14.866936 45.557685) (xy 14.859402 45.530876)
			(xy 14.859 45.516952) (xy 14.859 41.91) (xy 15.23944 41.91) (xy 15.243506 41.965556) (xy 15.255617 42.019927)
			(xy 15.275517 42.071956) (xy 15.302779 42.120533) (xy 15.336824 42.164622) (xy 15.376926 42.203285)
			(xy 15.42223 42.235697) (xy 15.47177 42.261168) (xy 15.524491 42.279154) (xy 15.579268 42.289272)
			(xy 15.634935 42.291306) (xy 15.690305 42.285213) (xy 15.744198 42.271124) (xy 15.795466 42.249338)
			(xy 15.843014 42.220319) (xy 15.885831 42.184687) (xy 15.923004 42.1432) (xy 15.95374 42.096743)
			(xy 15.977384 42.046305) (xy 15.993432 41.992963) (xy 16.001543 41.937852) (xy 16.002051 41.91) (xy 16.001543 41.882148)
			(xy 15.993432 41.827037) (xy 15.977384 41.773695) (xy 15.95374 41.723257) (xy 15.923004 41.6768)
			(xy 15.885831 41.635313) (xy 15.843014 41.599681) (xy 15.795466 41.570662) (xy 15.744198 41.548876)
			(xy 15.690305 41.534787) (xy 15.634935 41.528694) (xy 15.579268 41.530728) (xy 15.524491 41.540846)
			(xy 15.47177 41.558832) (xy 15.42223 41.584303) (xy 15.376926 41.616715) (xy 15.336824 41.655378)
			(xy 15.302779 41.699467) (xy 15.275517 41.748044) (xy 15.255617 41.800073) (xy 15.243506 41.854444)
			(xy 15.23944 41.91) (xy 14.859 41.91) (xy 14.859 40.894) (xy 15.15054 40.894) (xy 15.154606 40.949556)
			(xy 15.166717 41.003927) (xy 15.186617 41.055956) (xy 15.213879 41.104533) (xy 15.247924 41.148622)
			(xy 15.288026 41.187285) (xy 15.33333 41.219697) (xy 15.38287 41.245168) (xy 15.435591 41.263154)
			(xy 15.490368 41.273272) (xy 15.546035 41.275306) (xy 15.601405 41.269213) (xy 15.655298 41.255124)
			(xy 15.706566 41.233338) (xy 15.754114 41.204319) (xy 15.796931 41.168687) (xy 15.834104 41.1272)
			(xy 15.86484 41.080743) (xy 15.888484 41.030305) (xy 15.904532 40.976963) (xy 15.912643 40.921852)
			(xy 15.913151 40.894) (xy 16.87774 40.894) (xy 16.881806 40.949556) (xy 16.893917 41.003927) (xy 16.913817 41.055956)
			(xy 16.941079 41.104533) (xy 16.975124 41.148622) (xy 17.015226 41.187285) (xy 17.06053 41.219697)
			(xy 17.11007 41.245168) (xy 17.162791 41.263154) (xy 17.217568 41.273272) (xy 17.273235 41.275306)
			(xy 17.328605 41.269213) (xy 17.382498 41.255124) (xy 17.433766 41.233338) (xy 17.481314 41.204319)
			(xy 17.524131 41.168687) (xy 17.561304 41.1272) (xy 17.59204 41.080743) (xy 17.615684 41.030305)
			(xy 17.631732 40.976963) (xy 17.639843 40.921852) (xy 17.640351 40.894) (xy 17.639843 40.866148)
			(xy 17.631732 40.811037) (xy 17.615684 40.757695) (xy 17.59204 40.707257) (xy 17.561304 40.6608)
			(xy 17.524131 40.619313) (xy 17.481314 40.583681) (xy 17.433766 40.554662) (xy 17.382498 40.532876)
			(xy 17.328605 40.518787) (xy 17.273235 40.512694) (xy 17.217568 40.514728) (xy 17.162791 40.524846)
			(xy 17.11007 40.542832) (xy 17.06053 40.568303) (xy 17.015226 40.600715) (xy 16.975124 40.639378)
			(xy 16.941079 40.683467) (xy 16.913817 40.732044) (xy 16.893917 40.784073) (xy 16.881806 40.838444)
			(xy 16.87774 40.894) (xy 15.913151 40.894) (xy 15.912643 40.866148) (xy 15.904532 40.811037) (xy 15.888484 40.757695)
			(xy 15.86484 40.707257) (xy 15.834104 40.6608) (xy 15.796931 40.619313) (xy 15.754114 40.583681)
			(xy 15.706566 40.554662) (xy 15.655298 40.532876) (xy 15.601405 40.518787) (xy 15.546035 40.512694)
			(xy 15.490368 40.514728) (xy 15.435591 40.524846) (xy 15.38287 40.542832) (xy 15.33333 40.568303)
			(xy 15.288026 40.600715) (xy 15.247924 40.639378) (xy 15.213879 40.683467) (xy 15.186617 40.732044)
			(xy 15.166717 40.784073) (xy 15.154606 40.838444) (xy 15.15054 40.894) (xy 14.859 40.894) (xy 14.859 40.03802)
			(xy 16.25544 40.03802) (xy 16.259506 40.093576) (xy 16.271617 40.147947) (xy 16.291517 40.199976)
			(xy 16.318779 40.248553) (xy 16.352824 40.292642) (xy 16.392926 40.331305) (xy 16.43823 40.363717)
			(xy 16.48777 40.389188) (xy 16.540491 40.407174) (xy 16.595268 40.417292) (xy 16.650935 40.419326)
			(xy 16.706305 40.413233) (xy 16.760198 40.399144) (xy 16.811466 40.377358) (xy 16.859014 40.348339)
			(xy 16.901831 40.312707) (xy 16.939004 40.27122) (xy 16.96974 40.224763) (xy 16.993384 40.174325)
			(xy 17.009432 40.120983) (xy 17.017543 40.065872) (xy 17.018051 40.03802) (xy 17.017543 40.010168)
			(xy 17.009432 39.955057) (xy 16.993384 39.901715) (xy 16.96974 39.851277) (xy 16.939004 39.80482)
			(xy 16.901831 39.763333) (xy 16.859014 39.727701) (xy 16.811466 39.698682) (xy 16.760198 39.676896)
			(xy 16.706305 39.662807) (xy 16.650935 39.656714) (xy 16.595268 39.658748) (xy 16.540491 39.668866)
			(xy 16.48777 39.686852) (xy 16.43823 39.712323) (xy 16.392926 39.744735) (xy 16.352824 39.783398)
			(xy 16.318779 39.827487) (xy 16.291517 39.876064) (xy 16.271617 39.928093) (xy 16.259506 39.982464)
			(xy 16.25544 40.03802) (xy 14.859 40.03802) (xy 14.859 38.402768) (xy 14.893646 38.39116) (xy 14.909135 38.385823)
			(xy 14.93946 38.373418) (xy 14.95425 38.36637) (xy 14.981819 38.379284) (xy 15.039354 38.399182)
			(xy 15.098856 38.412062) (xy 15.15947 38.41774) (xy 15.220329 38.416133) (xy 15.280559 38.407264)
			(xy 15.339298 38.391262) (xy 15.395704 38.368354) (xy 15.42255 38.354) (xy 16.446398 38.354)
		)
		(stroke
			(width 0)
			(type solid)
		)
		(fill yes)
		(layer "In6.Cu")
		(net "VDD_1.8V")
	)
	(gr_arc
		(start -3.162046 -2.175002)
		(mid -2.869146 -2.8821)
		(end -2.162048 -3.175)
		(stroke
			(width 0.05)
			(type default)
		)
		(layer "Edge.Cuts")
	)
	(gr_line
		(start -3.162046 37.824918)
		(end -3.162046 -2.175002)
		(stroke
			(width 0.05)
			(type default)
		)
		(layer "Edge.Cuts")
	)
	(gr_line
		(start -2.162048 -3.175)
		(end 87.138002 -3.175)
		(stroke
			(width 0.05)
			(type default)
		)
		(layer "Edge.Cuts")
	)
	(gr_arc
		(start -2.162048 38.824916)
		(mid -2.869153 38.532023)
		(end -3.162046 37.824918)
		(stroke
			(width 0.05)
			(type default)
		)
		(layer "Edge.Cuts")
	)
	(gr_line
		(start 4.137914 38.824916)
		(end -2.162048 38.824916)
		(stroke
			(width 0.05)
			(type default)
		)
		(layer "Edge.Cuts")
	)
	(gr_arc
		(start 4.137914 38.824916)
		(mid 4.845019 39.11781)
		(end 5.137912 39.824914)
		(stroke
			(width 0.05)
			(type default)
		)
		(layer "Edge.Cuts")
	)
	(gr_line
		(start 5.137912 49.325022)
		(end 5.137912 39.824914)
		(stroke
			(width 0.05)
			(type default)
		)
		(layer "Edge.Cuts")
	)
	(gr_arc
		(start 6.13791 50.32502)
		(mid 5.430812 50.03212)
		(end 5.137912 49.325022)
		(stroke
			(width 0.05)
			(type default)
		)
		(layer "Edge.Cuts")
	)
	(gr_line
		(start 37.138102 50.32502)
		(end 6.13791 50.32502)
		(stroke
			(width 0.05)
			(type default)
		)
		(layer "Edge.Cuts")
	)
	(gr_arc
		(start 37.138102 50.32502)
		(mid 37.8452 50.617914)
		(end 38.1381 51.325018)
		(stroke
			(width 0.05)
			(type default)
		)
		(layer "Edge.Cuts")
	)
	(gr_line
		(start 38.1381 57.824878)
		(end 38.1381 51.325018)
		(stroke
			(width 0.05)
			(type default)
		)
		(layer "Edge.Cuts")
	)
	(gr_arc
		(start 39.138098 58.824876)
		(mid 38.43097 58.532006)
		(end 38.1381 57.824878)
		(stroke
			(width 0.05)
			(type default)
		)
		(layer "Edge.Cuts")
	)
	(gr_arc
		(start 87.138002 -3.175)
		(mid 87.845107 -2.882107)
		(end 88.138 -2.175002)
		(stroke
			(width 0.05)
			(type default)
		)
		(layer "Edge.Cuts")
	)
	(gr_line
		(start 87.138002 58.824876)
		(end 39.138098 58.824876)
		(stroke
			(width 0.05)
			(type default)
		)
		(layer "Edge.Cuts")
	)
	(gr_line
		(start 88.138 -2.175002)
		(end 88.138 57.824878)
		(stroke
			(width 0.05)
			(type default)
		)
		(layer "Edge.Cuts")
	)
	(gr_arc
		(start 88.138 57.824878)
		(mid 87.845122 58.531998)
		(end 87.138002 58.824876)
		(stroke
			(width 0.05)
			(type default)
		)
		(layer "Edge.Cuts")
	)
	(segment
		(start 41.237002 22.041993)
		(end 40.737003 22.541992)
		(width 0.14732)
		(layer "F.Cu")
		(net "_NFP_PCIE0_RESET_OUT_L")
	)
	(via
		(at 43.815 26.543)
		(size 0.762)
		(drill 0.381)
		(layers "F.Cu" "B.Cu")
		(net "_NFP_PCIE0_RESET_OUT_L")
	)
	(via
		(at 40.737003 22.541992)
		(size 0.4826)
		(drill 0.20574)
		(layers "F.Cu" "B.Cu")
		(net "_NFP_PCIE0_RESET_OUT_L")
	)
	(segment
		(start 42.237152 22.042247)
		(end 42.237152 23.666907)
		(width 0.14732)
		(layer "B.Cu")
		(net "_NFP_PCIE0_RESET_OUT_L")
	)
	(segment
		(start 42.295039 23.725099)
		(end 42.295039 23.724794)
		(width 0.14732)
		(layer "B.Cu")
		(net "_NFP_PCIE0_RESET_OUT_L")
	)
	(segment
		(start 44.31599 26.04201)
		(end 44.95099 26.04201)
		(width 0.14732)
		(layer "B.Cu")
		(net "_NFP_PCIE0_RESET_OUT_L")
	)
	(segment
		(start 45.236994 24.154994)
		(end 45.123989 24.041989)
		(width 0.14732)
		(layer "B.Cu")
		(net "_NFP_PCIE0_RESET_OUT_L")
	)
	(segment
		(start 45.236994 25.756006)
		(end 45.236994 24.154994)
		(width 0.14732)
		(layer "B.Cu")
		(net "_NFP_PCIE0_RESET_OUT_L")
	)
	(segment
		(start 43.815 26.543)
		(end 44.31599 26.04201)
		(width 0.14732)
		(layer "B.Cu")
		(net "_NFP_PCIE0_RESET_OUT_L")
	)
	(segment
		(start 42.237152 23.666907)
		(end 41.862197 24.041862)
		(width 0.14732)
		(layer "B.Cu")
		(net "_NFP_PCIE0_RESET_OUT_L")
	)
	(segment
		(start 42.295039 23.724794)
		(end 42.237152 23.666907)
		(width 0.14732)
		(layer "B.Cu")
		(net "_NFP_PCIE0_RESET_OUT_L")
	)
	(segment
		(start 44.95099 26.04201)
		(end 45.236994 25.756006)
		(width 0.14732)
		(layer "B.Cu")
		(net "_NFP_PCIE0_RESET_OUT_L")
	)
	(segment
		(start 42.611929 24.041989)
		(end 42.295039 23.725099)
		(width 0.14732)
		(layer "B.Cu")
		(net "_NFP_PCIE0_RESET_OUT_L")
	)
	(segment
		(start 41.611677 22.042247)
		(end 41.111932 22.541992)
		(width 0.14732)
		(layer "B.Cu")
		(net "_NFP_PCIE0_RESET_OUT_L")
	)
	(segment
		(start 41.862197 24.041862)
		(end 41.237027 24.041862)
		(width 0.14732)
		(layer "B.Cu")
		(net "_NFP_PCIE0_RESET_OUT_L")
	)
	(segment
		(start 42.237152 22.042247)
		(end 41.611677 22.042247)
		(width 0.14732)
		(layer "B.Cu")
		(net "_NFP_PCIE0_RESET_OUT_L")
	)
	(segment
		(start 45.123989 24.041989)
		(end 42.611929 24.041989)
		(width 0.14732)
		(layer "B.Cu")
		(net "_NFP_PCIE0_RESET_OUT_L")
	)
	(segment
		(start 41.111932 22.541992)
		(end 40.737003 22.541992)
		(width 0.14732)
		(layer "B.Cu")
		(net "_NFP_PCIE0_RESET_OUT_L")
	)
	(segment
		(start 26.924 22.6568)
		(end 26.0858 22.6568)
		(width 0.14732)
		(layer "F.Cu")
		(net "_NFP_CLK_NRESET_L")
	)
	(via
		(at 26.0858 22.6568)
		(size 0.762)
		(drill 0.381)
		(layers "F.Cu" "B.Cu")
		(net "_NFP_CLK_NRESET_L")
	)
	(via
		(at 26.924 22.6568)
		(size 0.4572)
		(drill 0.20574)
		(layers "F.Cu" "B.Cu")
		(net "_NFP_CLK_NRESET_L")
	)
	(segment
		(start 26.035 22.6441)
		(end 26.4033 22.6441)
		(width 0.14732)
		(layer "B.Cu")
		(net "_NFP_CLK_NRESET_L")
	)
	(segment
		(start 26.416 22.6568)
		(end 26.924 22.6568)
		(width 0.14732)
		(layer "B.Cu")
		(net "_NFP_CLK_NRESET_L")
	)
	(segment
		(start 26.4033 22.6441)
		(end 26.416 22.6568)
		(width 0.14732)
		(layer "B.Cu")
		(net "_NFP_CLK_NRESET_L")
	)
	(segment
		(start 26.924 22.6568)
		(end 27.315592 23.048392)
		(width 0.12065)
		(layer "In1.Cu")
		(net "_NFP_CLK_NRESET_L")
	)
	(segment
		(start 27.315592 23.048392)
		(end 28.745993 23.048392)
		(width 0.12065)
		(layer "In1.Cu")
		(net "_NFP_CLK_NRESET_L")
	)
	(segment
		(start 48.236988 10.041992)
		(end 47.736989 9.541993)
		(width 0.254)
		(layer "F.Cu")
		(net "VDDA_SERDES")
	)
	(segment
		(start 48.236988 9.041994)
		(end 47.736989 8.541995)
		(width 0.254)
		(layer "F.Cu")
		(net "VDDA_SERDES")
	)
	(segment
		(start 49.237011 10.041992)
		(end 48.737012 9.541993)
		(width 0.254)
		(layer "F.Cu")
		(net "VDDA_SERDES")
	)
	(segment
		(start 49.237011 9.041994)
		(end 48.737012 8.541995)
		(width 0.254)
		(layer "F.Cu")
		(net "VDDA_SERDES")
	)
	(segment
		(start 47.23699 10.041992)
		(end 46.736991 9.541993)
		(width 0.254)
		(layer "F.Cu")
		(net "VDDA_SERDES")
	)
	(via
		(at 47.736989 9.541993)
		(size 0.4826)
		(drill 0.20574)
		(layers "F.Cu" "B.Cu")
		(net "VDDA_SERDES")
	)
	(via
		(at 56.261 18.669)
		(size 0.762)
		(drill 0.381)
		(layers "F.Cu" "B.Cu")
		(net "VDDA_SERDES")
	)
	(via
		(at 48.737012 8.541995)
		(size 0.4826)
		(drill 0.20574)
		(layers "F.Cu" "B.Cu")
		(net "VDDA_SERDES")
	)
	(via
		(at 54.737 10.543438)
		(size 0.4826)
		(drill 0.20574)
		(layers "F.Cu" "B.Cu")
		(net "VDDA_SERDES")
	)
	(via
		(at 48.737012 9.541993)
		(size 0.4826)
		(drill 0.20574)
		(layers "F.Cu" "B.Cu")
		(net "VDDA_SERDES")
	)
	(via
		(at 46.736991 9.541993)
		(size 0.4826)
		(drill 0.20574)
		(layers "F.Cu" "B.Cu")
		(net "VDDA_SERDES")
	)
	(via
		(at 54.737 11.543436)
		(size 0.508)
		(drill 0.25654)
		(layers "F.Cu" "B.Cu")
		(net "VDDA_SERDES")
	)
	(via
		(at 47.736989 8.541995)
		(size 0.4826)
		(drill 0.20574)
		(layers "F.Cu" "B.Cu")
		(net "VDDA_SERDES")
	)
	(segment
		(start 48.768 5.2451)
		(end 48.768 5.588)
		(width 0.508)
		(layer "B.Cu")
		(net "VDDA_SERDES")
	)
	(segment
		(start 46.736991 9.541993)
		(end 47.236888 10.04189)
		(width 0.254)
		(layer "B.Cu")
		(net "VDDA_SERDES")
	)
	(segment
		(start 48.237013 11.049)
		(end 48.237013 10.042017)
		(width 0.254)
		(layer "B.Cu")
		(net "VDDA_SERDES")
	)
	(segment
		(start 54.737 11.543436)
		(end 54.737 10.543438)
		(width 0.508)
		(layer "B.Cu")
		(net "VDDA_SERDES")
	)
	(segment
		(start 47.625 8.382)
		(end 47.736989 8.493989)
		(width 0.4572)
		(layer "B.Cu")
		(net "VDDA_SERDES")
	)
	(segment
		(start 55.1053 11.911736)
		(end 55.185488 11.911736)
		(width 0.2032)
		(layer "B.Cu")
		(net "VDDA_SERDES")
	)
	(segment
		(start 47.736989 8.541995)
		(end 48.237013 9.042019)
		(width 0.254)
		(layer "B.Cu")
		(net "VDDA_SERDES")
	)
	(segment
		(start 48.237013 13.042138)
		(end 48.237013 12.04214)
		(width 0.254)
		(layer "B.Cu")
		(net "VDDA_SERDES")
	)
	(segment
		(start 47.736989 8.493989)
		(end 47.736989 8.541995)
		(width 0.4572)
		(layer "B.Cu")
		(net "VDDA_SERDES")
	)
	(segment
		(start 49.237011 9.041892)
		(end 49.237011 9.041994)
		(width 0.254)
		(layer "B.Cu")
		(net "VDDA_SERDES")
	)
	(segment
		(start 56.2197 12.34219)
		(end 56.2197 12.4047)
		(width 0.2032)
		(layer "B.Cu")
		(net "VDDA_SERDES")
	)
	(segment
		(start 55.185488 11.911736)
		(end 55.333062 12.05931)
		(width 0.2032)
		(layer "B.Cu")
		(net "VDDA_SERDES")
	)
	(segment
		(start 49.237011 9.041994)
		(end 48.737012 9.541993)
		(width 0.254)
		(layer "B.Cu")
		(net "VDDA_SERDES")
	)
	(segment
		(start 48.063912 6.292088)
		(end 47.981591 6.542024)
		(width 0.508)
		(layer "B.Cu")
		(net "VDDA_SERDES")
	)
	(segment
		(start 47.981591 6.542024)
		(end 47.625 6.980936)
		(width 0.4572)
		(layer "B.Cu")
		(net "VDDA_SERDES")
	)
	(segment
		(start 49.236884 11.042015)
		(end 48.243998 11.042015)
		(width 0.254)
		(layer "B.Cu")
		(net "VDDA_SERDES")
	)
	(segment
		(start 55.93682 12.05931)
		(end 56.2197 12.34219)
		(width 0.2032)
		(layer "B.Cu")
		(net "VDDA_SERDES")
	)
	(segment
		(start 47.625 6.980936)
		(end 47.625 8.382)
		(width 0.4572)
		(layer "B.Cu")
		(net "VDDA_SERDES")
	)
	(segment
		(start 54.737 11.543436)
		(end 55.1053 11.911736)
		(width 0.2032)
		(layer "B.Cu")
		(net "VDDA_SERDES")
	)
	(segment
		(start 48.243998 11.042015)
		(end 48.237013 11.049)
		(width 0.254)
		(layer "B.Cu")
		(net "VDDA_SERDES")
	)
	(segment
		(start 48.237013 12.04214)
		(end 48.237013 11.049)
		(width 0.254)
		(layer "B.Cu")
		(net "VDDA_SERDES")
	)
	(segment
		(start 48.768 5.588)
		(end 48.063912 6.292088)
		(width 0.508)
		(layer "B.Cu")
		(net "VDDA_SERDES")
	)
	(segment
		(start 47.236888 10.04189)
		(end 47.237015 10.04189)
		(width 0.254)
		(layer "B.Cu")
		(net "VDDA_SERDES")
	)
	(segment
		(start 56.2197 12.4047)
		(end 56.261 12.446)
		(width 0.2032)
		(layer "B.Cu")
		(net "VDDA_SERDES")
	)
	(segment
		(start 48.237013 9.042019)
		(end 48.237013 9.042146)
		(width 0.254)
		(layer "B.Cu")
		(net "VDDA_SERDES")
	)
	(segment
		(start 55.333062 12.05931)
		(end 55.93682 12.05931)
		(width 0.2032)
		(layer "B.Cu")
		(net "VDDA_SERDES")
	)
	(segment
		(start 48.237013 10.042017)
		(end 47.736989 9.541993)
		(width 0.254)
		(layer "B.Cu")
		(net "VDDA_SERDES")
	)
	(segment
		(start 56.261 12.446)
		(end 56.261 18.669)
		(width 0.2032)
		(layer "B.Cu")
		(net "VDDA_SERDES")
	)
	(segment
		(start 51.237007 9.041994)
		(end 50.737008 8.541995)
		(width 0.254)
		(layer "F.Cu")
		(net "VDDAH_SERDES")
	)
	(segment
		(start 50.237009 9.041994)
		(end 49.73701 8.541995)
		(width 0.254)
		(layer "F.Cu")
		(net "VDDAH_SERDES")
	)
	(via
		(at 47.752 2.413)
		(size 0.762)
		(drill 0.381)
		(layers "F.Cu" "B.Cu")
		(net "VDDAH_SERDES")
	)
	(via
		(at 49.73701 8.541995)
		(size 0.4826)
		(drill 0.20574)
		(layers "F.Cu" "B.Cu")
		(net "VDDAH_SERDES")
	)
	(via
		(at 50.737008 8.541995)
		(size 0.4826)
		(drill 0.20574)
		(layers "F.Cu" "B.Cu")
		(net "VDDAH_SERDES")
	)
	(segment
		(start 49.604752 2.413)
		(end 50.038 2.413)
		(width 0.254)
		(layer "B.Cu")
		(net "VDDAH_SERDES")
	)
	(segment
		(start 47.752 2.413)
		(end 48.13112 2.03388)
		(width 0.254)
		(layer "B.Cu")
		(net "VDDAH_SERDES")
	)
	(segment
		(start 50.237111 9.041892)
		(end 50.737008 8.541995)
		(width 0.254)
		(layer "B.Cu")
		(net "VDDAH_SERDES")
	)
	(segment
		(start 50.236907 9.041892)
		(end 50.237009 9.041892)
		(width 0.254)
		(layer "B.Cu")
		(net "VDDAH_SERDES")
	)
	(segment
		(start 50.038 2.413)
		(end 50.546 1.905)
		(width 0.254)
		(layer "B.Cu")
		(net "VDDAH_SERDES")
	)
	(segment
		(start 52.236878 5.042027)
		(end 52.236878 6.042025)
		(width 0.254)
		(layer "B.Cu")
		(net "VDDAH_SERDES")
	)
	(segment
		(start 51.151003 8.128)
		(end 50.737008 8.541995)
		(width 0.254)
		(layer "B.Cu")
		(net "VDDAH_SERDES")
	)
	(segment
		(start 51.562 3.683)
		(end 51.925703 4.046703)
		(width 0.254)
		(layer "B.Cu")
		(net "VDDAH_SERDES")
	)
	(segment
		(start 50.927 1.905)
		(end 51.562 2.54)
		(width 0.254)
		(layer "B.Cu")
		(net "VDDAH_SERDES")
	)
	(segment
		(start 50.737008 8.541995)
		(end 51.23688 9.041867)
		(width 0.254)
		(layer "B.Cu")
		(net "VDDAH_SERDES")
	)
	(segment
		(start 47.752 2.413)
		(end 47.169553 1.830553)
		(width 0.254)
		(layer "B.Cu")
		(net "VDDAH_SERDES")
	)
	(segment
		(start 48.13112 2.03388)
		(end 49.228858 2.03388)
		(width 0.254)
		(layer "B.Cu")
		(net "VDDAH_SERDES")
	)
	(segment
		(start 49.73701 8.541995)
		(end 50.236907 9.041892)
		(width 0.254)
		(layer "B.Cu")
		(net "VDDAH_SERDES")
	)
	(segment
		(start 47.169553 1.830553)
		(end 47.169553 1.72527)
		(width 0.254)
		(layer "B.Cu")
		(net "VDDAH_SERDES")
	)
	(segment
		(start 52.236878 6.042025)
		(end 52.236878 7.042023)
		(width 0.254)
		(layer "B.Cu")
		(net "VDDAH_SERDES")
	)
	(segment
		(start 52.236878 4.341393)
		(end 52.236878 5.042027)
		(width 0.254)
		(layer "B.Cu")
		(net "VDDAH_SERDES")
	)
	(segment
		(start 52.236878 7.042023)
		(end 52.236878 7.834122)
		(width 0.254)
		(layer "B.Cu")
		(net "VDDAH_SERDES")
	)
	(segment
		(start 51.562 2.54)
		(end 51.562 3.683)
		(width 0.254)
		(layer "B.Cu")
		(net "VDDAH_SERDES")
	)
	(segment
		(start 49.228858 2.03388)
		(end 49.276 2.081022)
		(width 0.254)
		(layer "B.Cu")
		(net "VDDAH_SERDES")
	)
	(segment
		(start 50.237009 9.041892)
		(end 50.237111 9.041892)
		(width 0.254)
		(layer "B.Cu")
		(net "VDDAH_SERDES")
	)
	(segment
		(start 50.546 1.905)
		(end 50.927 1.905)
		(width 0.254)
		(layer "B.Cu")
		(net "VDDAH_SERDES")
	)
	(segment
		(start 51.23688 9.041867)
		(end 51.23688 9.042019)
		(width 0.254)
		(layer "B.Cu")
		(net "VDDAH_SERDES")
	)
	(segment
		(start 51.23688 10.042017)
		(end 51.23688 9.042019)
		(width 0.254)
		(layer "B.Cu")
		(net "VDDAH_SERDES")
	)
	(segment
		(start 51.942187 4.046703)
		(end 52.236878 4.341393)
		(width 0.254)
		(layer "B.Cu")
		(net "VDDAH_SERDES")
	)
	(segment
		(start 49.276 2.084248)
		(end 49.604752 2.413)
		(width 0.254)
		(layer "B.Cu")
		(net "VDDAH_SERDES")
	)
	(segment
		(start 47.169553 1.72527)
		(end 46.486318 1.042035)
		(width 0.254)
		(layer "B.Cu")
		(net "VDDAH_SERDES")
	)
	(segment
		(start 51.943 8.128)
		(end 51.151003 8.128)
		(width 0.254)
		(layer "B.Cu")
		(net "VDDAH_SERDES")
	)
	(segment
		(start 52.236878 7.834122)
		(end 51.943 8.128)
		(width 0.254)
		(layer "B.Cu")
		(net "VDDAH_SERDES")
	)
	(segment
		(start 49.276 2.081022)
		(end 49.276 2.084248)
		(width 0.254)
		(layer "B.Cu")
		(net "VDDAH_SERDES")
	)
	(segment
		(start 51.925703 4.046703)
		(end 51.942187 4.046703)
		(width 0.254)
		(layer "B.Cu")
		(net "VDDAH_SERDES")
	)
	(segment
		(start 55.736998 8.541995)
		(end 55.236999 9.041994)
		(width 0.254)
		(layer "F.Cu")
		(net "VDDAH_PCIE0")
	)
	(via
		(at 64.77 5.461)
		(size 0.762)
		(drill 0.381)
		(layers "F.Cu" "B.Cu")
		(net "VDDAH_PCIE0")
	)
	(via
		(at 55.736998 8.541995)
		(size 0.4826)
		(drill 0.20574)
		(layers "F.Cu" "B.Cu")
		(net "VDDAH_PCIE0")
	)
	(segment
		(start 60.241688 5.737784)
		(end 60.241688 5.336819)
		(width 0.254)
		(layer "B.Cu")
		(net "VDDAH_PCIE0")
	)
	(segment
		(start 65.405 4.826)
		(end 64.77 5.461)
		(width 0.254)
		(layer "B.Cu")
		(net "VDDAH_PCIE0")
	)
	(segment
		(start 56.531815 5.046701)
		(end 57.942175 5.046701)
		(width 0.254)
		(layer "B.Cu")
		(net "VDDAH_PCIE0")
	)
	(segment
		(start 58.232294 5.336819)
		(end 58.232294 5.366995)
		(width 0.254)
		(layer "B.Cu")
		(net "VDDAH_PCIE0")
	)
	(segment
		(start 58.241692 5.747182)
		(end 58.541209 6.046699)
		(width 0.254)
		(layer "B.Cu")
		(net "VDDAH_PCIE0")
	)
	(segment
		(start 55.736998 8.541995)
		(end 56.236895 9.041892)
		(width 0.254)
		(layer "B.Cu")
		(net "VDDAH_PCIE0")
	)
	(segment
		(start 56.23687 7.042023)
		(end 56.23687 6.042025)
		(width 0.254)
		(layer "B.Cu")
		(net "VDDAH_PCIE0")
	)
	(segment
		(start 56.23687 8.042021)
		(end 56.23687 8.042123)
		(width 0.254)
		(layer "B.Cu")
		(net "VDDAH_PCIE0")
	)
	(segment
		(start 56.23687 6.042025)
		(end 56.23687 5.341645)
		(width 0.254)
		(layer "B.Cu")
		(net "VDDAH_PCIE0")
	)
	(segment
		(start 56.236895 9.041892)
		(end 56.236997 9.041892)
		(width 0.254)
		(layer "B.Cu")
		(net "VDDAH_PCIE0")
	)
	(segment
		(start 64.7827 3.556)
		(end 64.7827 3.6957)
		(width 0.254)
		(layer "B.Cu")
		(net "VDDAH_PCIE0")
	)
	(segment
		(start 58.541209 6.046699)
		(end 59.932773 6.046699)
		(width 0.254)
		(layer "B.Cu")
		(net "VDDAH_PCIE0")
	)
	(segment
		(start 64.7827 3.6957)
		(end 65.405 4.318)
		(width 0.254)
		(layer "B.Cu")
		(net "VDDAH_PCIE0")
	)
	(segment
		(start 60.241688 5.336819)
		(end 60.531807 5.046701)
		(width 0.254)
		(layer "B.Cu")
		(net "VDDAH_PCIE0")
	)
	(segment
		(start 56.23687 5.341645)
		(end 56.531815 5.046701)
		(width 0.254)
		(layer "B.Cu")
		(net "VDDAH_PCIE0")
	)
	(segment
		(start 64.355701 5.046701)
		(end 64.77 5.461)
		(width 0.254)
		(layer "B.Cu")
		(net "VDDAH_PCIE0")
	)
	(segment
		(start 58.232294 5.366995)
		(end 58.241692 5.376393)
		(width 0.254)
		(layer "B.Cu")
		(net "VDDAH_PCIE0")
	)
	(segment
		(start 58.241692 5.376393)
		(end 58.241692 5.747182)
		(width 0.254)
		(layer "B.Cu")
		(net "VDDAH_PCIE0")
	)
	(segment
		(start 65.405 4.318)
		(end 65.405 4.826)
		(width 0.254)
		(layer "B.Cu")
		(net "VDDAH_PCIE0")
	)
	(segment
		(start 56.23687 8.042123)
		(end 55.736998 8.541995)
		(width 0.254)
		(layer "B.Cu")
		(net "VDDAH_PCIE0")
	)
	(segment
		(start 60.531807 5.046701)
		(end 64.355701 5.046701)
		(width 0.254)
		(layer "B.Cu")
		(net "VDDAH_PCIE0")
	)
	(segment
		(start 56.23687 8.042021)
		(end 56.23687 7.042023)
		(width 0.254)
		(layer "B.Cu")
		(net "VDDAH_PCIE0")
	)
	(segment
		(start 59.932773 6.046699)
		(end 60.241688 5.737784)
		(width 0.254)
		(layer "B.Cu")
		(net "VDDAH_PCIE0")
	)
	(segment
		(start 57.942175 5.046701)
		(end 58.232294 5.336819)
		(width 0.254)
		(layer "B.Cu")
		(net "VDDAH_PCIE0")
	)
	(segment
		(start 36.449 33.9598)
		(end 36.068 34.29)
		(width 0.508)
		(layer "F.Cu")
		(net "10N2370")
	)
	(segment
		(start 36.470768 33.930768)
		(end 37.338 33.930768)
		(width 0.508)
		(layer "F.Cu")
		(net "10N2370")
	)
	(segment
		(start 37.719 40.8559)
		(end 37.719 39.1033)
		(width 0.508)
		(layer "F.Cu")
		(net "10N2370")
	)
	(segment
		(start 35.179 34.925)
		(end 34.9885 35.1155)
		(width 0.508)
		(layer "F.Cu")
		(net "10N2370")
	)
	(segment
		(start 37.8714 39.0144)
		(end 38.1 38.7223)
		(width 0.508)
		(layer "F.Cu")
		(net "10N2370")
	)
	(segment
		(start 38.1 34.692768)
		(end 38.1 37.4015)
		(width 0.508)
		(layer "F.Cu")
		(net "10N2370")
	)
	(segment
		(start 35.6489 34.9758)
		(end 35.179 34.925)
		(width 0.508)
		(layer "F.Cu")
		(net "10N2370")
	)
	(segment
		(start 37.719 39.1033)
		(end 37.8714 39.0144)
		(width 0.508)
		(layer "F.Cu")
		(net "10N2370")
	)
	(segment
		(start 34.254008 35.849992)
		(end 34.0614 35.849992)
		(width 0.2032)
		(layer "F.Cu")
		(net "10N2370")
	)
	(segment
		(start 37.338 33.930768)
		(end 38.1 34.692768)
		(width 0.508)
		(layer "F.Cu")
		(net "10N2370")
	)
	(segment
		(start 36.449 33.9598)
		(end 36.470768 33.930768)
		(width 0.508)
		(layer "F.Cu")
		(net "10N2370")
	)
	(segment
		(start 36.062564 34.29)
		(end 35.6489 34.703664)
		(width 0.508)
		(layer "F.Cu")
		(net "10N2370")
	)
	(segment
		(start 36.068 34.29)
		(end 36.062564 34.29)
		(width 0.508)
		(layer "F.Cu")
		(net "10N2370")
	)
	(segment
		(start 35.6489 34.703664)
		(end 35.6489 34.9758)
		(width 0.508)
		(layer "F.Cu")
		(net "10N2370")
	)
	(segment
		(start 34.9885 35.1155)
		(end 34.254008 35.849992)
		(width 0.2032)
		(layer "F.Cu")
		(net "10N2370")
	)
	(segment
		(start 38.1 38.7223)
		(end 38.1 37.4015)
		(width 0.508)
		(layer "F.Cu")
		(net "10N2370")
	)
	(via
		(at 36.449 33.9598)
		(size 0.762)
		(drill 0.381)
		(layers "F.Cu" "B.Cu")
		(net "10N2370")
	)
	(via
		(at 12.8524 27.2669)
		(size 0.508)
		(drill 0.254)
		(layers "F.Cu" "B.Cu")
		(net "MAIN_3.3V")
	)
	(via
		(at 14.1224 25.9969)
		(size 0.508)
		(drill 0.254)
		(layers "F.Cu" "B.Cu")
		(net "MAIN_3.3V")
	)
	(via
		(at 14.1224 27.2669)
		(size 0.762)
		(drill 0.2667)
		(layers "F.Cu" "B.Cu")
		(net "MAIN_3.3V")
	)
	(segment
		(start 14.7574 27.9019)
		(end 14.7574 31.7754)
		(width 0.254)
		(layer "B.Cu")
		(net "MAIN_3.3V")
	)
	(segment
		(start 14.7574 26.6319)
		(end 14.1224 25.9969)
		(width 0.254)
		(layer "B.Cu")
		(net "MAIN_3.3V")
	)
	(segment
		(start 14.7574 27.9019)
		(end 14.1224 27.2669)
		(width 0.254)
		(layer "B.Cu")
		(net "MAIN_3.3V")
	)
	(segment
		(start 13.4874 27.9019)
		(end 12.8524 27.2669)
		(width 0.254)
		(layer "B.Cu")
		(net "MAIN_3.3V")
	)
	(segment
		(start 14.7574 31.7754)
		(end 15.113 32.131)
		(width 0.254)
		(layer "B.Cu")
		(net "MAIN_3.3V")
	)
	(segment
		(start 16.129 6.604)
		(end 15.875 6.35)
		(width 0.14732)
		(layer "F.Cu")
		(net "SMBUS_SDA")
	)
	(segment
		(start 17.653 11.7729)
		(end 17.653 9.652)
		(width 0.14732)
		(layer "F.Cu")
		(net "SMBUS_SDA")
	)
	(segment
		(start 17.653 9.652)
		(end 16.891 8.89)
		(width 0.14732)
		(layer "F.Cu")
		(net "SMBUS_SDA")
	)
	(segment
		(start 16.891 8.89)
		(end 16.383 8.89)
		(width 0.14732)
		(layer "F.Cu")
		(net "SMBUS_SDA")
	)
	(segment
		(start 19.812 10.795)
		(end 25.527 10.795)
		(width 0.14732)
		(layer "F.Cu")
		(net "SMBUS_SDA")
	)
	(segment
		(start 16.383 8.89)
		(end 16.129 8.636)
		(width 0.14732)
		(layer "F.Cu")
		(net "SMBUS_SDA")
	)
	(segment
		(start 15.875 6.35)
		(end 12.319 6.35)
		(width 0.14732)
		(layer "F.Cu")
		(net "SMBUS_SDA")
	)
	(segment
		(start 12.319 6.35)
		(end 11.6459 5.6769)
		(width 0.14732)
		(layer "F.Cu")
		(net "SMBUS_SDA")
	)
	(segment
		(start 17.653 11.7729)
		(end 18.7579 11.7729)
		(width 0.14732)
		(layer "F.Cu")
		(net "SMBUS_SDA")
	)
	(segment
		(start 18.7579 11.7729)
		(end 18.796 11.811)
		(width 0.14732)
		(layer "F.Cu")
		(net "SMBUS_SDA")
	)
	(segment
		(start 25.527 10.795)
		(end 26.162 10.16)
		(width 0.14732)
		(layer "F.Cu")
		(net "SMBUS_SDA")
	)
	(segment
		(start 11.6459 5.6769)
		(end 11.5824 5.6769)
		(width 0.14732)
		(layer "F.Cu")
		(net "SMBUS_SDA")
	)
	(segment
		(start 26.162 10.16)
		(end 26.162 8.9281)
		(width 0.14732)
		(layer "F.Cu")
		(net "SMBUS_SDA")
	)
	(segment
		(start 16.129 8.636)
		(end 16.129 6.604)
		(width 0.14732)
		(layer "F.Cu")
		(net "SMBUS_SDA")
	)
	(segment
		(start 18.796 11.811)
		(end 19.812 10.795)
		(width 0.14732)
		(layer "F.Cu")
		(net "SMBUS_SDA")
	)
	(via
		(at 18.796 11.811)
		(size 0.762)
		(drill 0.381)
		(layers "F.Cu" "B.Cu")
		(net "SMBUS_SDA")
	)
	(via
		(at 11.5824 5.6769)
		(size 0.508)
		(drill 0.254)
		(layers "F.Cu" "B.Cu")
		(net "SMBUS_SDA")
	)
	(segment
		(start 12.2174 6.3119)
		(end 11.5824 5.6769)
		(width 0.254)
		(layer "B.Cu")
		(net "SMBUS_SDA")
	)
	(segment
		(start 15.621 1.8161)
		(end 15.1511 2.286)
		(width 0.14732)
		(layer "F.Cu")
		(net "SMBUS_SCL")
	)
	(segment
		(start 13.081 3.81)
		(end 12.1793 3.81)
		(width 0.14732)
		(layer "F.Cu")
		(net "SMBUS_SCL")
	)
	(segment
		(start 15.28826 1.44526)
		(end 15.621 1.778)
		(width 0.14732)
		(layer "F.Cu")
		(net "SMBUS_SCL")
	)
	(segment
		(start 13.462 3.429)
		(end 13.081 3.81)
		(width 0.14732)
		(layer "F.Cu")
		(net "SMBUS_SCL")
	)
	(segment
		(start 15.283866 1.44526)
		(end 15.28826 1.44526)
		(width 0.14732)
		(layer "F.Cu")
		(net "SMBUS_SCL")
	)
	(segment
		(start 14.3129 1.8161)
		(end 13.462 2.667)
		(width 0.14732)
		(layer "F.Cu")
		(net "SMBUS_SCL")
	)
	(segment
		(start 13.462 2.667)
		(end 13.462 3.429)
		(width 0.14732)
		(layer "F.Cu")
		(net "SMBUS_SCL")
	)
	(segment
		(start 15.16634 1.327734)
		(end 15.283866 1.44526)
		(width 0.14732)
		(layer "F.Cu")
		(net "SMBUS_SCL")
	)
	(segment
		(start 15.16634 1.32334)
		(end 15.16634 1.327734)
		(width 0.14732)
		(layer "F.Cu")
		(net "SMBUS_SCL")
	)
	(segment
		(start 15.03934 -0.68834)
		(end 15.03934 1.19634)
		(width 0.14732)
		(layer "F.Cu")
		(net "SMBUS_SCL")
	)
	(segment
		(start 12.1793 3.81)
		(end 11.5824 4.4069)
		(width 0.14732)
		(layer "F.Cu")
		(net "SMBUS_SCL")
	)
	(segment
		(start 15.113 -0.762)
		(end 15.03934 -0.68834)
		(width 0.14732)
		(layer "F.Cu")
		(net "SMBUS_SCL")
	)
	(segment
		(start 15.621 1.778)
		(end 15.621 1.8161)
		(width 0.14732)
		(layer "F.Cu")
		(net "SMBUS_SCL")
	)
	(segment
		(start 15.03934 1.19634)
		(end 15.16634 1.32334)
		(width 0.14732)
		(layer "F.Cu")
		(net "SMBUS_SCL")
	)
	(segment
		(start 15.1511 2.286)
		(end 14.8209 2.286)
		(width 0.14732)
		(layer "F.Cu")
		(net "SMBUS_SCL")
	)
	(segment
		(start 14.8209 2.286)
		(end 14.351 1.8161)
		(width 0.14732)
		(layer "F.Cu")
		(net "SMBUS_SCL")
	)
	(segment
		(start 14.351 1.8161)
		(end 14.3129 1.8161)
		(width 0.14732)
		(layer "F.Cu")
		(net "SMBUS_SCL")
	)
	(via
		(at 15.113 -0.762)
		(size 0.762)
		(drill 0.381)
		(layers "F.Cu" "B.Cu")
		(net "SMBUS_SCL")
	)
	(via
		(at 11.5824 4.4069)
		(size 0.508)
		(drill 0.254)
		(layers "F.Cu" "B.Cu")
		(net "SMBUS_SCL")
	)
	(segment
		(start 12.2174 5.0419)
		(end 11.5824 4.4069)
		(width 0.13208)
		(layer "B.Cu")
		(net "SMBUS_SCL")
	)
	(via
		(at 2.794 11.176)
		(size 0.508)
		(drill 0.25654)
		(layers "F.Cu" "B.Cu")
		(net "NWK1_I2C_SDA")
	)
	(via
		(at 16.6624 23.4569)
		(size 0.762)
		(drill 0.2667)
		(layers "F.Cu" "B.Cu")
		(net "NWK1_I2C_SDA")
	)
	(segment
		(start 2.794 10.668)
		(end 2.794 11.176)
		(width 0.14732)
		(layer "B.Cu")
		(net "NWK1_I2C_SDA")
	)
	(segment
		(start 2.289988 12.5222)
		(end 2.289988 11.680012)
		(width 0.14732)
		(layer "B.Cu")
		(net "NWK1_I2C_SDA")
	)
	(segment
		(start 2.289988 11.680012)
		(end 2.794 11.176)
		(width 0.14732)
		(layer "B.Cu")
		(net "NWK1_I2C_SDA")
	)
	(segment
		(start 2.032 10.2743)
		(end 2.4511 10.3251)
		(width 0.14732)
		(layer "B.Cu")
		(net "NWK1_I2C_SDA")
	)
	(segment
		(start 17.2974 24.0919)
		(end 16.6624 23.4569)
		(width 0.254)
		(layer "B.Cu")
		(net "NWK1_I2C_SDA")
	)
	(segment
		(start 2.4511 10.3251)
		(end 2.794 10.668)
		(width 0.14732)
		(layer "B.Cu")
		(net "NWK1_I2C_SDA")
	)
	(segment
		(start 16.221075 24.545925)
		(end 16.129 24.638)
		(width 0.12065)
		(layer "In7.Cu")
		(net "NWK1_I2C_SDA")
	)
	(segment
		(start 15.875 27.813)
		(end 8.89 27.813)
		(width 0.12065)
		(layer "In7.Cu")
		(net "NWK1_I2C_SDA")
	)
	(segment
		(start 4.445 15.748)
		(end 2.413 13.716)
		(width 0.12065)
		(layer "In7.Cu")
		(net "NWK1_I2C_SDA")
	)
	(segment
		(start 16.221075 24.544071)
		(end 16.221075 24.545925)
		(width 0.12065)
		(layer "In7.Cu")
		(net "NWK1_I2C_SDA")
	)
	(segment
		(start 16.6624 23.4569)
		(end 16.6624 24.102746)
		(width 0.12065)
		(layer "In7.Cu")
		(net "NWK1_I2C_SDA")
	)
	(segment
		(start 16.129 27.559)
		(end 15.875 27.813)
		(width 0.12065)
		(layer "In7.Cu")
		(net "NWK1_I2C_SDA")
	)
	(segment
		(start 16.129 24.638)
		(end 16.129 27.559)
		(width 0.12065)
		(layer "In7.Cu")
		(net "NWK1_I2C_SDA")
	)
	(segment
		(start 8.601075 24.544071)
		(end 8.342579 24.285575)
		(width 0.12065)
		(layer "In7.Cu")
		(net "NWK1_I2C_SDA")
	)
	(segment
		(start 8.342579 24.285575)
		(end 6.837172 24.285575)
		(width 0.12065)
		(layer "In7.Cu")
		(net "NWK1_I2C_SDA")
	)
	(segment
		(start 4.445 20.753654)
		(end 4.445 15.748)
		(width 0.12065)
		(layer "In7.Cu")
		(net "NWK1_I2C_SDA")
	)
	(segment
		(start 8.601075 27.524075)
		(end 8.601075 24.544071)
		(width 0.12065)
		(layer "In7.Cu")
		(net "NWK1_I2C_SDA")
	)
	(segment
		(start 8.89 27.813)
		(end 8.601075 27.524075)
		(width 0.12065)
		(layer "In7.Cu")
		(net "NWK1_I2C_SDA")
	)
	(segment
		(start 16.6624 24.102746)
		(end 16.221075 24.544071)
		(width 0.12065)
		(layer "In7.Cu")
		(net "NWK1_I2C_SDA")
	)
	(segment
		(start 2.413 13.716)
		(end 2.413 11.557)
		(width 0.12065)
		(layer "In7.Cu")
		(net "NWK1_I2C_SDA")
	)
	(segment
		(start 6.837172 24.285575)
		(end 5.815609 23.264012)
		(width 0.12065)
		(layer "In7.Cu")
		(net "NWK1_I2C_SDA")
	)
	(segment
		(start 2.413 11.557)
		(end 2.794 11.176)
		(width 0.12065)
		(layer "In7.Cu")
		(net "NWK1_I2C_SDA")
	)
	(segment
		(start 5.815609 22.124264)
		(end 4.445 20.753654)
		(width 0.12065)
		(layer "In7.Cu")
		(net "NWK1_I2C_SDA")
	)
	(segment
		(start 5.815609 23.264012)
		(end 5.815609 22.124264)
		(width 0.12065)
		(layer "In7.Cu")
		(net "NWK1_I2C_SDA")
	)
	(via
		(at 0.6604 11.176)
		(size 0.508)
		(drill 0.25654)
		(layers "F.Cu" "B.Cu")
		(net "NWK1_I2C_SCL")
	)
	(via
		(at 16.6624 24.7269)
		(size 0.762)
		(drill 0.2667)
		(layers "F.Cu" "B.Cu")
		(net "NWK1_I2C_SCL")
	)
	(segment
		(start 0.8382 11.3538)
		(end 0.6604 11.176)
		(width 0.14732)
		(layer "B.Cu")
		(net "NWK1_I2C_SCL")
	)
	(segment
		(start 17.2974 25.3619)
		(end 16.6624 24.7269)
		(width 0.254)
		(layer "B.Cu")
		(net "NWK1_I2C_SCL")
	)
	(segment
		(start 0.8382 13.465988)
		(end 0.8382 11.3538)
		(width 0.14732)
		(layer "B.Cu")
		(net "NWK1_I2C_SCL")
	)
	(segment
		(start 0.6604 10.2743)
		(end 0.6604 11.176)
		(width 0.14732)
		(layer "B.Cu")
		(net "NWK1_I2C_SCL")
	)
	(segment
		(start 8.255 28.575)
		(end 0.127 20.447)
		(width 0.12065)
		(layer "In7.Cu")
		(net "NWK1_I2C_SCL")
	)
	(segment
		(start 17.272 28.067)
		(end 16.764 28.575)
		(width 0.12065)
		(layer "In7.Cu")
		(net "NWK1_I2C_SCL")
	)
	(segment
		(start 0.127 14.986)
		(end 0.6604 14.4526)
		(width 0.12065)
		(layer "In7.Cu")
		(net "NWK1_I2C_SCL")
	)
	(segment
		(start 0.127 20.447)
		(end 0.127 14.986)
		(width 0.12065)
		(layer "In7.Cu")
		(net "NWK1_I2C_SCL")
	)
	(segment
		(start 16.764 28.575)
		(end 8.255 28.575)
		(width 0.12065)
		(layer "In7.Cu")
		(net "NWK1_I2C_SCL")
	)
	(segment
		(start 0.6604 14.4526)
		(end 0.6604 11.176)
		(width 0.12065)
		(layer "In7.Cu")
		(net "NWK1_I2C_SCL")
	)
	(segment
		(start 16.6624 24.7269)
		(end 17.272 25.3365)
		(width 0.12065)
		(layer "In7.Cu")
		(net "NWK1_I2C_SCL")
	)
	(segment
		(start 17.272 25.3365)
		(end 17.272 28.067)
		(width 0.12065)
		(layer "In7.Cu")
		(net "NWK1_I2C_SCL")
	)
	(via
		(at 7.493 26.035)
		(size 0.508)
		(drill 0.254)
		(layers "F.Cu" "B.Cu")
		(net "NWK0_I2C_SDA")
	)
	(via
		(at 2.032 21.463)
		(size 0.508)
		(drill 0.2667)
		(layers "F.Cu" "B.Cu")
		(net "NWK0_I2C_SDA")
	)
	(via
		(at 0.6604 16.129)
		(size 0.508)
		(drill 0.25654)
		(layers "F.Cu" "B.Cu")
		(net "NWK0_I2C_SDA")
	)
	(segment
		(start 7.8105 26.035)
		(end 7.493 26.035)
		(width 0.254)
		(layer "B.Cu")
		(net "NWK0_I2C_SDA")
	)
	(segment
		(start 1.28999 15.65181)
		(end 0.8128 16.129)
		(width 0.14732)
		(layer "B.Cu")
		(net "NWK0_I2C_SDA")
	)
	(segment
		(start 0.8128 16.8275)
		(end 0.8128 16.129)
		(width 0.14732)
		(layer "B.Cu")
		(net "NWK0_I2C_SDA")
	)
	(segment
		(start 8.4074 26.6319)
		(end 7.8105 26.035)
		(width 0.254)
		(layer "B.Cu")
		(net "NWK0_I2C_SDA")
	)
	(segment
		(start 0.6096 17.0307)
		(end 0.8128 16.8275)
		(width 0.14732)
		(layer "B.Cu")
		(net "NWK0_I2C_SDA")
	)
	(segment
		(start 1.28999 14.9098)
		(end 1.28999 15.65181)
		(width 0.14732)
		(layer "B.Cu")
		(net "NWK0_I2C_SDA")
	)
	(segment
		(start 2.032 21.463)
		(end 2.032 21.642553)
		(width 0.12065)
		(layer "In7.Cu")
		(net "NWK0_I2C_SDA")
	)
	(segment
		(start 0.6604 16.129)
		(end 2.032 17.5006)
		(width 0.12065)
		(layer "In7.Cu")
		(net "NWK0_I2C_SDA")
	)
	(segment
		(start 6.386347 25.9969)
		(end 7.4549 25.9969)
		(width 0.12065)
		(layer "In7.Cu")
		(net "NWK0_I2C_SDA")
	)
	(segment
		(start 7.4549 25.9969)
		(end 7.493 26.035)
		(width 0.12065)
		(layer "In7.Cu")
		(net "NWK0_I2C_SDA")
	)
	(segment
		(start 2.032 21.642553)
		(end 6.386347 25.9969)
		(width 0.12065)
		(layer "In7.Cu")
		(net "NWK0_I2C_SDA")
	)
	(segment
		(start 2.032 17.5006)
		(end 2.032 21.463)
		(width 0.12065)
		(layer "In7.Cu")
		(net "NWK0_I2C_SDA")
	)
	(via
		(at 3.556 22.098)
		(size 0.508)
		(drill 0.2667)
		(layers "F.Cu" "B.Cu")
		(net "NWK0_I2C_SCL")
	)
	(via
		(at 2.794 16.129)
		(size 0.508)
		(drill 0.25654)
		(layers "F.Cu" "B.Cu")
		(net "NWK0_I2C_SCL")
	)
	(via
		(at 7.7724 27.2669)
		(size 0.508)
		(drill 0.254)
		(layers "F.Cu" "B.Cu")
		(net "NWK0_I2C_SCL")
	)
	(segment
		(start 2.790012 14.9098)
		(end 2.790012 15.490012)
		(width 0.14732)
		(layer "B.Cu")
		(net "NWK0_I2C_SCL")
	)
	(segment
		(start 2.667 17.0307)
		(end 2.794 16.8529)
		(width 0.14732)
		(layer "B.Cu")
		(net "NWK0_I2C_SCL")
	)
	(segment
		(start 2.794 16.8529)
		(end 2.794 16.129)
		(width 0.14732)
		(layer "B.Cu")
		(net "NWK0_I2C_SCL")
	)
	(segment
		(start 2.794 15.494)
		(end 2.794 16.129)
		(width 0.14732)
		(layer "B.Cu")
		(net "NWK0_I2C_SCL")
	)
	(segment
		(start 2.790012 15.490012)
		(end 2.794 15.494)
		(width 0.14732)
		(layer "B.Cu")
		(net "NWK0_I2C_SCL")
	)
	(segment
		(start 8.4074 27.9019)
		(end 7.7724 27.2669)
		(width 0.254)
		(layer "B.Cu")
		(net "NWK0_I2C_SCL")
	)
	(segment
		(start 2.794 21.336)
		(end 2.794 16.129)
		(width 0.12065)
		(layer "In7.Cu")
		(net "NWK0_I2C_SCL")
	)
	(segment
		(start 3.556 22.098)
		(end 2.794 21.336)
		(width 0.12065)
		(layer "In7.Cu")
		(net "NWK0_I2C_SCL")
	)
	(segment
		(start 8.001 27.0383)
		(end 8.001 25.601346)
		(width 0.12065)
		(layer "In7.Cu")
		(net "NWK0_I2C_SCL")
	)
	(segment
		(start 6.626225 25.168225)
		(end 3.556 22.098)
		(width 0.12065)
		(layer "In7.Cu")
		(net "NWK0_I2C_SCL")
	)
	(segment
		(start 7.7724 27.2669)
		(end 8.001 27.0383)
		(width 0.12065)
		(layer "In7.Cu")
		(net "NWK0_I2C_SCL")
	)
	(segment
		(start 7.567879 25.168225)
		(end 6.626225 25.168225)
		(width 0.12065)
		(layer "In7.Cu")
		(net "NWK0_I2C_SCL")
	)
	(segment
		(start 8.001 25.601346)
		(end 7.567879 25.168225)
		(width 0.12065)
		(layer "In7.Cu")
		(net "NWK0_I2C_SCL")
	)
	(segment
		(start 23.60201 5.87281)
		(end 24.0792 6.35)
		(width 0.14732)
		(layer "F.Cu")
		(net "NFP_SMBUS_SDA")
	)
	(segment
		(start 23.60201 5.1308)
		(end 23.60201 5.87281)
		(width 0.14732)
		(layer "F.Cu")
		(net "NFP_SMBUS_SDA")
	)
	(segment
		(start 24.2316 6.35)
		(end 24.892 6.35)
		(width 0.14732)
		(layer "F.Cu")
		(net "NFP_SMBUS_SDA")
	)
	(segment
		(start 24.892 6.35)
		(end 26.162 7.62)
		(width 0.14732)
		(layer "F.Cu")
		(net "NFP_SMBUS_SDA")
	)
	(segment
		(start 26.162 7.62)
		(end 26.162 8.0899)
		(width 0.14732)
		(layer "F.Cu")
		(net "NFP_SMBUS_SDA")
	)
	(segment
		(start 24.0792 6.35)
		(end 24.2316 6.35)
		(width 0.14732)
		(layer "F.Cu")
		(net "NFP_SMBUS_SDA")
	)
	(via
		(at 24.2316 6.35)
		(size 0.508)
		(drill 0.25654)
		(layers "F.Cu" "B.Cu")
		(net "NFP_SMBUS_SDA")
	)
	(segment
		(start 24.2316 6.35)
		(end 24.2316 5.4737)
		(width 0.14732)
		(layer "B.Cu")
		(net "NFP_SMBUS_SDA")
	)
	(segment
		(start 24.2316 5.4737)
		(end 23.876 5.1181)
		(width 0.14732)
		(layer "B.Cu")
		(net "NFP_SMBUS_SDA")
	)
	(segment
		(start 24.0538 1.5748)
		(end 24.0538 3.686988)
		(width 0.14732)
		(layer "F.Cu")
		(net "NFP_SMBUS_SCL")
	)
	(segment
		(start 24.2316 1.397)
		(end 24.0538 1.5748)
		(width 0.14732)
		(layer "F.Cu")
		(net "NFP_SMBUS_SCL")
	)
	(segment
		(start 14.351 0.9779)
		(end 14.351 0.254)
		(width 0.14732)
		(layer "F.Cu")
		(net "NFP_SMBUS_SCL")
	)
	(via
		(at 24.2316 1.397)
		(size 0.508)
		(drill 0.25654)
		(layers "F.Cu" "B.Cu")
		(net "NFP_SMBUS_SCL")
	)
	(via
		(at 14.351 0.254)
		(size 0.508)
		(drill 0.254)
		(layers "F.Cu" "B.Cu")
		(net "NFP_SMBUS_SCL")
	)
	(segment
		(start 24.2316 2.2733)
		(end 24.13 2.3749)
		(width 0.14732)
		(layer "B.Cu")
		(net "NFP_SMBUS_SCL")
	)
	(segment
		(start 24.2316 1.397)
		(end 24.2316 2.2733)
		(width 0.14732)
		(layer "B.Cu")
		(net "NFP_SMBUS_SCL")
	)
	(segment
		(start 15.078253 -0.7493)
		(end 14.351 -0.022047)
		(width 0.12065)
		(layer "In6.Cu")
		(net "NFP_SMBUS_SCL")
	)
	(segment
		(start 14.351 -0.022047)
		(end 14.351 0.254)
		(width 0.12065)
		(layer "In6.Cu")
		(net "NFP_SMBUS_SCL")
	)
	(segment
		(start 24.2316 1.397)
		(end 22.3266 -0.508)
		(width 0.12065)
		(layer "In6.Cu")
		(net "NFP_SMBUS_SCL")
	)
	(segment
		(start 22.3266 -0.508)
		(end 20.902447 -0.508)
		(width 0.12065)
		(layer "In6.Cu")
		(net "NFP_SMBUS_SCL")
	)
	(segment
		(start 16.964025 -0.688975)
		(end 16.9037 -0.7493)
		(width 0.12065)
		(layer "In6.Cu")
		(net "NFP_SMBUS_SCL")
	)
	(segment
		(start 20.721472 -0.688975)
		(end 16.964025 -0.688975)
		(width 0.12065)
		(layer "In6.Cu")
		(net "NFP_SMBUS_SCL")
	)
	(segment
		(start 16.9037 -0.7493)
		(end 15.078253 -0.7493)
		(width 0.12065)
		(layer "In6.Cu")
		(net "NFP_SMBUS_SCL")
	)
	(segment
		(start 20.902447 -0.508)
		(end 20.721472 -0.688975)
		(width 0.12065)
		(layer "In6.Cu")
		(net "NFP_SMBUS_SCL")
	)
	(segment
		(start 23.102011 5.1308)
		(end 23.102011 6.336589)
		(width 0.14732)
		(layer "F.Cu")
		(net "MUX_NFP_SMBUS_SDA")
	)
	(segment
		(start 42.237 10.041992)
		(end 41.737001 9.541993)
		(width 0.13208)
		(layer "F.Cu")
		(net "MUX_NFP_SMBUS_SDA")
	)
	(segment
		(start 23.102011 6.336589)
		(end 23.0886 6.35)
		(width 0.14732)
		(layer "F.Cu")
		(net "MUX_NFP_SMBUS_SDA")
	)
	(via
		(at 23.0886 6.35)
		(size 0.508)
		(drill 0.25654)
		(layers "F.Cu" "B.Cu")
		(net "MUX_NFP_SMBUS_SDA")
	)
	(via
		(at 41.737001 9.541993)
		(size 0.4826)
		(drill 0.20574)
		(layers "F.Cu" "B.Cu")
		(net "MUX_NFP_SMBUS_SDA")
	)
	(via
		(at 41.737001 3.542005)
		(size 0.4826)
		(drill 0.25654)
		(layers "F.Cu" "B.Cu")
		(net "MUX_NFP_SMBUS_SDA")
	)
	(segment
		(start 24.60658 5.895975)
		(end 25.326975 5.895975)
		(width 0.12065)
		(layer "In3.Cu")
		(net "MUX_NFP_SMBUS_SDA")
	)
	(segment
		(start 23.0886 6.35)
		(end 23.5966 5.842)
		(width 0.12065)
		(layer "In3.Cu")
		(net "MUX_NFP_SMBUS_SDA")
	)
	(segment
		(start 25.757454 6.326454)
		(end 28.217546 6.326454)
		(width 0.12065)
		(layer "In3.Cu")
		(net "MUX_NFP_SMBUS_SDA")
	)
	(segment
		(start 30.950103 4.064)
		(end 33.782 4.064)
		(width 0.12065)
		(layer "In3.Cu")
		(net "MUX_NFP_SMBUS_SDA")
	)
	(segment
		(start 24.552605 5.842)
		(end 24.60658 5.895975)
		(width 0.12065)
		(layer "In3.Cu")
		(net "MUX_NFP_SMBUS_SDA")
	)
	(segment
		(start 34.72373 3.937)
		(end 34.735287 3.925443)
		(width 0.12065)
		(layer "In3.Cu")
		(net "MUX_NFP_SMBUS_SDA")
	)
	(segment
		(start 33.782 4.064)
		(end 33.909 3.937)
		(width 0.12065)
		(layer "In3.Cu")
		(net "MUX_NFP_SMBUS_SDA")
	)
	(segment
		(start 38.354 4.064)
		(end 41.215005 4.064)
		(width 0.12065)
		(layer "In3.Cu")
		(net "MUX_NFP_SMBUS_SDA")
	)
	(segment
		(start 28.963696 6.050407)
		(end 30.950103 4.064)
		(width 0.12065)
		(layer "In3.Cu")
		(net "MUX_NFP_SMBUS_SDA")
	)
	(segment
		(start 23.5966 5.842)
		(end 24.552605 5.842)
		(width 0.12065)
		(layer "In3.Cu")
		(net "MUX_NFP_SMBUS_SDA")
	)
	(segment
		(start 25.326975 5.895975)
		(end 25.757454 6.326454)
		(width 0.12065)
		(layer "In3.Cu")
		(net "MUX_NFP_SMBUS_SDA")
	)
	(segment
		(start 41.215005 4.064)
		(end 41.737001 3.542005)
		(width 0.12065)
		(layer "In3.Cu")
		(net "MUX_NFP_SMBUS_SDA")
	)
	(segment
		(start 28.493593 6.050407)
		(end 28.963696 6.050407)
		(width 0.12065)
		(layer "In3.Cu")
		(net "MUX_NFP_SMBUS_SDA")
	)
	(segment
		(start 37.781738 3.925443)
		(end 37.793295 3.937)
		(width 0.12065)
		(layer "In3.Cu")
		(net "MUX_NFP_SMBUS_SDA")
	)
	(segment
		(start 37.793295 3.937)
		(end 38.227 3.937)
		(width 0.12065)
		(layer "In3.Cu")
		(net "MUX_NFP_SMBUS_SDA")
	)
	(segment
		(start 38.227 3.937)
		(end 38.354 4.064)
		(width 0.12065)
		(layer "In3.Cu")
		(net "MUX_NFP_SMBUS_SDA")
	)
	(segment
		(start 33.909 3.937)
		(end 34.72373 3.937)
		(width 0.12065)
		(layer "In3.Cu")
		(net "MUX_NFP_SMBUS_SDA")
	)
	(segment
		(start 34.735287 3.925443)
		(end 37.781738 3.925443)
		(width 0.12065)
		(layer "In3.Cu")
		(net "MUX_NFP_SMBUS_SDA")
	)
	(segment
		(start 28.217546 6.326454)
		(end 28.493593 6.050407)
		(width 0.12065)
		(layer "In3.Cu")
		(net "MUX_NFP_SMBUS_SDA")
	)
	(segment
		(start 41.737001 3.601999)
		(end 41.275 4.064)
		(width 0.12065)
		(layer "In7.Cu")
		(net "MUX_NFP_SMBUS_SDA")
	)
	(segment
		(start 42.333774 5.709056)
		(end 42.569943 5.945226)
		(width 0.12065)
		(layer "In7.Cu")
		(net "MUX_NFP_SMBUS_SDA")
	)
	(segment
		(start 43.18 8.669274)
		(end 42.710506 9.138768)
		(width 0.12065)
		(layer "In7.Cu")
		(net "MUX_NFP_SMBUS_SDA")
	)
	(segment
		(start 42.418 9.138768)
		(end 42.014775 9.541993)
		(width 0.12065)
		(layer "In7.Cu")
		(net "MUX_NFP_SMBUS_SDA")
	)
	(segment
		(start 43.18 6.414719)
		(end 43.18 8.669274)
		(width 0.12065)
		(layer "In7.Cu")
		(net "MUX_NFP_SMBUS_SDA")
	)
	(segment
		(start 42.710506 9.138768)
		(end 42.418 9.138768)
		(width 0.12065)
		(layer "In7.Cu")
		(net "MUX_NFP_SMBUS_SDA")
	)
	(segment
		(start 42.333774 5.568493)
		(end 42.333774 5.709056)
		(width 0.12065)
		(layer "In7.Cu")
		(net "MUX_NFP_SMBUS_SDA")
	)
	(segment
		(start 42.569943 5.945226)
		(end 42.710506 5.945226)
		(width 0.12065)
		(layer "In7.Cu")
		(net "MUX_NFP_SMBUS_SDA")
	)
	(segment
		(start 41.904056 5.138776)
		(end 42.333774 5.568493)
		(width 0.12065)
		(layer "In7.Cu")
		(net "MUX_NFP_SMBUS_SDA")
	)
	(segment
		(start 41.763493 5.138776)
		(end 41.904056 5.138776)
		(width 0.12065)
		(layer "In7.Cu")
		(net "MUX_NFP_SMBUS_SDA")
	)
	(segment
		(start 41.275 4.650283)
		(end 41.763493 5.138776)
		(width 0.12065)
		(layer "In7.Cu")
		(net "MUX_NFP_SMBUS_SDA")
	)
	(segment
		(start 41.737001 3.542005)
		(end 41.737001 3.601999)
		(width 0.12065)
		(layer "In7.Cu")
		(net "MUX_NFP_SMBUS_SDA")
	)
	(segment
		(start 41.275 4.064)
		(end 41.275 4.650283)
		(width 0.12065)
		(layer "In7.Cu")
		(net "MUX_NFP_SMBUS_SDA")
	)
	(segment
		(start 42.710506 5.945226)
		(end 43.18 6.414719)
		(width 0.12065)
		(layer "In7.Cu")
		(net "MUX_NFP_SMBUS_SDA")
	)
	(segment
		(start 42.014775 9.541993)
		(end 41.737001 9.541993)
		(width 0.12065)
		(layer "In7.Cu")
		(net "MUX_NFP_SMBUS_SDA")
	)
	(segment
		(start 42.237 11.04199)
		(end 41.737001 10.541991)
		(width 0.13208)
		(layer "F.Cu")
		(net "MUX_NFP_SMBUS_SCL")
	)
	(segment
		(start 23.60201 2.358974)
		(end 23.60201 2.7432)
		(width 0.14732)
		(layer "F.Cu")
		(net "MUX_NFP_SMBUS_SCL")
	)
	(segment
		(start 23.60201 1.75801)
		(end 23.241 1.397)
		(width 0.14732)
		(layer "F.Cu")
		(net "MUX_NFP_SMBUS_SCL")
	)
	(segment
		(start 23.60201 2.358974)
		(end 23.60201 1.75801)
		(width 0.14732)
		(layer "F.Cu")
		(net "MUX_NFP_SMBUS_SCL")
	)
	(via
		(at 41.737001 10.541991)
		(size 0.4826)
		(drill 0.20574)
		(layers "F.Cu" "B.Cu")
		(net "MUX_NFP_SMBUS_SCL")
	)
	(via
		(at 23.114 1.397)
		(size 0.508)
		(drill 0.25654)
		(layers "F.Cu" "B.Cu")
		(net "MUX_NFP_SMBUS_SCL")
	)
	(via
		(at 47.43704 0.895096)
		(size 0.508)
		(drill 0.254)
		(layers "F.Cu" "B.Cu")
		(net "MUX_NFP_SMBUS_SCL")
	)
	(segment
		(start 47.303944 0.762)
		(end 47.43704 0.895096)
		(width 0.12065)
		(layer "In2.Cu")
		(net "MUX_NFP_SMBUS_SCL")
	)
	(segment
		(start 23.114 1.397)
		(end 23.590504 0.895096)
		(width 0.12065)
		(layer "In2.Cu")
		(net "MUX_NFP_SMBUS_SCL")
	)
	(segment
		(start 42.078021 0.762)
		(end 47.303944 0.762)
		(width 0.12065)
		(layer "In2.Cu")
		(net "MUX_NFP_SMBUS_SCL")
	)
	(segment
		(start 23.590504 0.895096)
		(end 41.944925 0.895096)
		(width 0.12065)
		(layer "In2.Cu")
		(net "MUX_NFP_SMBUS_SCL")
	)
	(segment
		(start 41.944925 0.895096)
		(end 42.078021 0.762)
		(width 0.12065)
		(layer "In2.Cu")
		(net "MUX_NFP_SMBUS_SCL")
	)
	(segment
		(start 51.904062 4.138778)
		(end 52.140231 4.374947)
		(width 0.12065)
		(layer "In6.Cu")
		(net "MUX_NFP_SMBUS_SCL")
	)
	(segment
		(start 47.43704 1.84404)
		(end 48.641 3.048)
		(width 0.12065)
		(layer "In6.Cu")
		(net "MUX_NFP_SMBUS_SCL")
	)
	(segment
		(start 42.245991 10.033)
		(end 41.737001 10.541991)
		(width 0.12065)
		(layer "In6.Cu")
		(net "MUX_NFP_SMBUS_SCL")
	)
	(segment
		(start 51.562 3.937)
		(end 51.763778 4.138778)
		(width 0.12065)
		(layer "In6.Cu")
		(net "MUX_NFP_SMBUS_SCL")
	)
	(segment
		(start 53.213 9.652)
		(end 52.832 10.033)
		(width 0.12065)
		(layer "In6.Cu")
		(net "MUX_NFP_SMBUS_SCL")
	)
	(segment
		(start 52.951228 4.945228)
		(end 53.213 5.207)
		(width 0.12065)
		(layer "In6.Cu")
		(net "MUX_NFP_SMBUS_SCL")
	)
	(segment
		(start 51.562 3.302)
		(end 51.562 3.937)
		(width 0.12065)
		(layer "In6.Cu")
		(net "MUX_NFP_SMBUS_SCL")
	)
	(segment
		(start 51.308 3.048)
		(end 51.562 3.302)
		(width 0.12065)
		(layer "In6.Cu")
		(net "MUX_NFP_SMBUS_SCL")
	)
	(segment
		(start 52.140231 4.374947)
		(end 52.140231 4.634459)
		(width 0.12065)
		(layer "In6.Cu")
		(net "MUX_NFP_SMBUS_SCL")
	)
	(segment
		(start 53.213 5.207)
		(end 53.213 9.652)
		(width 0.12065)
		(layer "In6.Cu")
		(net "MUX_NFP_SMBUS_SCL")
	)
	(segment
		(start 52.832 10.033)
		(end 42.245991 10.033)
		(width 0.12065)
		(layer "In6.Cu")
		(net "MUX_NFP_SMBUS_SCL")
	)
	(segment
		(start 48.641 3.048)
		(end 51.308 3.048)
		(width 0.12065)
		(layer "In6.Cu")
		(net "MUX_NFP_SMBUS_SCL")
	)
	(segment
		(start 47.43704 0.895096)
		(end 47.43704 1.84404)
		(width 0.12065)
		(layer "In6.Cu")
		(net "MUX_NFP_SMBUS_SCL")
	)
	(segment
		(start 51.763778 4.138778)
		(end 51.904062 4.138778)
		(width 0.12065)
		(layer "In6.Cu")
		(net "MUX_NFP_SMBUS_SCL")
	)
	(segment
		(start 52.140231 4.634459)
		(end 52.451 4.945228)
		(width 0.12065)
		(layer "In6.Cu")
		(net "MUX_NFP_SMBUS_SCL")
	)
	(segment
		(start 52.451 4.945228)
		(end 52.951228 4.945228)
		(width 0.12065)
		(layer "In6.Cu")
		(net "MUX_NFP_SMBUS_SCL")
	)
	(segment
		(start 21.209 5.842)
		(end 21.1074 5.9436)
		(width 0.14732)
		(layer "F.Cu")
		(net "MUX_NFP_SMBUS_ALERT_L")
	)
	(segment
		(start 21.601989 5.1308)
		(end 21.59 5.142789)
		(width 0.14732)
		(layer "F.Cu")
		(net "MUX_NFP_SMBUS_ALERT_L")
	)
	(segment
		(start 21.59 5.142789)
		(end 21.59 5.715)
		(width 0.14732)
		(layer "F.Cu")
		(net "MUX_NFP_SMBUS_ALERT_L")
	)
	(segment
		(start 21.59 5.715)
		(end 21.463 5.842)
		(width 0.14732)
		(layer "F.Cu")
		(net "MUX_NFP_SMBUS_ALERT_L")
	)
	(segment
		(start 21.1074 5.9436)
		(end 21.1074 6.35)
		(width 0.14732)
		(layer "F.Cu")
		(net "MUX_NFP_SMBUS_ALERT_L")
	)
	(segment
		(start 41.237002 11.04199)
		(end 40.737003 10.541991)
		(width 0.13208)
		(layer "F.Cu")
		(net "MUX_NFP_SMBUS_ALERT_L")
	)
	(segment
		(start 21.463 5.842)
		(end 21.209 5.842)
		(width 0.14732)
		(layer "F.Cu")
		(net "MUX_NFP_SMBUS_ALERT_L")
	)
	(via
		(at 20.955 6.35)
		(size 0.508)
		(drill 0.25654)
		(layers "F.Cu" "B.Cu")
		(net "MUX_NFP_SMBUS_ALERT_L")
	)
	(via
		(at 40.737003 10.541991)
		(size 0.4826)
		(drill 0.20574)
		(layers "F.Cu" "B.Cu")
		(net "MUX_NFP_SMBUS_ALERT_L")
	)
	(via
		(at 40.737003 2.542007)
		(size 0.4826)
		(drill 0.25654)
		(layers "F.Cu" "B.Cu")
		(net "MUX_NFP_SMBUS_ALERT_L")
	)
	(segment
		(start 38.15273 3.556)
		(end 38.08288 3.556)
		(width 0.12065)
		(layer "In3.Cu")
		(net "MUX_NFP_SMBUS_ALERT_L")
	)
	(segment
		(start 25.074829 5.648325)
		(end 24.709171 5.648325)
		(width 0.12065)
		(layer "In3.Cu")
		(net "MUX_NFP_SMBUS_ALERT_L")
	)
	(segment
		(start 21.075523 6.102477)
		(end 21.075523 6.176747)
		(width 0.12065)
		(layer "In3.Cu")
		(net "MUX_NFP_SMBUS_ALERT_L")
	)
	(segment
		(start 20.955 6.29727)
		(end 20.955 6.35)
		(width 0.12065)
		(layer "In3.Cu")
		(net "MUX_NFP_SMBUS_ALERT_L")
	)
	(segment
		(start 38.569951 3.13878)
		(end 38.15273 3.556)
		(width 0.12065)
		(layer "In3.Cu")
		(net "MUX_NFP_SMBUS_ALERT_L")
	)
	(segment
		(start 40.737003 2.542007)
		(end 40.14023 3.13878)
		(width 0.12065)
		(layer "In3.Cu")
		(net "MUX_NFP_SMBUS_ALERT_L")
	)
	(segment
		(start 26.648105 5.802706)
		(end 26.003707 5.158359)
		(width 0.12065)
		(layer "In3.Cu")
		(net "MUX_NFP_SMBUS_ALERT_L")
	)
	(segment
		(start 26.003707 5.158359)
		(end 25.564795 5.158359)
		(width 0.12065)
		(layer "In3.Cu")
		(net "MUX_NFP_SMBUS_ALERT_L")
	)
	(segment
		(start 26.648156 5.802757)
		(end 26.648105 5.802706)
		(width 0.12065)
		(layer "In3.Cu")
		(net "MUX_NFP_SMBUS_ALERT_L")
	)
	(segment
		(start 38.006528 3.632352)
		(end 31.03151 3.632352)
		(width 0.12065)
		(layer "In3.Cu")
		(net "MUX_NFP_SMBUS_ALERT_L")
	)
	(segment
		(start 40.14023 3.13878)
		(end 38.569951 3.13878)
		(width 0.12065)
		(layer "In3.Cu")
		(net "MUX_NFP_SMBUS_ALERT_L")
	)
	(segment
		(start 22.019641 5.158359)
		(end 21.075523 6.102477)
		(width 0.12065)
		(layer "In3.Cu")
		(net "MUX_NFP_SMBUS_ALERT_L")
	)
	(segment
		(start 31.03151 3.632352)
		(end 28.861106 5.802757)
		(width 0.12065)
		(layer "In3.Cu")
		(net "MUX_NFP_SMBUS_ALERT_L")
	)
	(segment
		(start 28.861106 5.802757)
		(end 26.648156 5.802757)
		(width 0.12065)
		(layer "In3.Cu")
		(net "MUX_NFP_SMBUS_ALERT_L")
	)
	(segment
		(start 25.564795 5.158359)
		(end 25.074829 5.648325)
		(width 0.12065)
		(layer "In3.Cu")
		(net "MUX_NFP_SMBUS_ALERT_L")
	)
	(segment
		(start 24.709171 5.648325)
		(end 24.219205 5.158359)
		(width 0.12065)
		(layer "In3.Cu")
		(net "MUX_NFP_SMBUS_ALERT_L")
	)
	(segment
		(start 24.219205 5.158359)
		(end 22.019641 5.158359)
		(width 0.12065)
		(layer "In3.Cu")
		(net "MUX_NFP_SMBUS_ALERT_L")
	)
	(segment
		(start 21.075523 6.176747)
		(end 20.955 6.29727)
		(width 0.12065)
		(layer "In3.Cu")
		(net "MUX_NFP_SMBUS_ALERT_L")
	)
	(segment
		(start 38.08288 3.556)
		(end 38.006528 3.632352)
		(width 0.12065)
		(layer "In3.Cu")
		(net "MUX_NFP_SMBUS_ALERT_L")
	)
	(segment
		(start 41.333776 5.709056)
		(end 42.140226 6.515506)
		(width 0.12065)
		(layer "In7.Cu")
		(net "MUX_NFP_SMBUS_ALERT_L")
	)
	(segment
		(start 42.140226 8.786774)
		(end 41.788232 9.138768)
		(width 0.12065)
		(layer "In7.Cu")
		(net "MUX_NFP_SMBUS_ALERT_L")
	)
	(segment
		(start 40.904058 5.138776)
		(end 41.333776 5.568493)
		(width 0.12065)
		(layer "In7.Cu")
		(net "MUX_NFP_SMBUS_ALERT_L")
	)
	(segment
		(start 40.698776 5.138776)
		(end 40.904058 5.138776)
		(width 0.12065)
		(layer "In7.Cu")
		(net "MUX_NFP_SMBUS_ALERT_L")
	)
	(segment
		(start 40.259 3.048)
		(end 40.259 4.699)
		(width 0.12065)
		(layer "In7.Cu")
		(net "MUX_NFP_SMBUS_ALERT_L")
	)
	(segment
		(start 40.259 4.699)
		(end 40.698776 5.138776)
		(width 0.12065)
		(layer "In7.Cu")
		(net "MUX_NFP_SMBUS_ALERT_L")
	)
	(segment
		(start 41.333776 5.568493)
		(end 41.333776 5.709056)
		(width 0.12065)
		(layer "In7.Cu")
		(net "MUX_NFP_SMBUS_ALERT_L")
	)
	(segment
		(start 41.788232 9.138768)
		(end 41.534232 9.138768)
		(width 0.12065)
		(layer "In7.Cu")
		(net "MUX_NFP_SMBUS_ALERT_L")
	)
	(segment
		(start 40.737003 9.935997)
		(end 40.737003 10.541991)
		(width 0.12065)
		(layer "In7.Cu")
		(net "MUX_NFP_SMBUS_ALERT_L")
	)
	(segment
		(start 40.737003 2.569997)
		(end 40.259 3.048)
		(width 0.12065)
		(layer "In7.Cu")
		(net "MUX_NFP_SMBUS_ALERT_L")
	)
	(segment
		(start 41.534232 9.138768)
		(end 40.737003 9.935997)
		(width 0.12065)
		(layer "In7.Cu")
		(net "MUX_NFP_SMBUS_ALERT_L")
	)
	(segment
		(start 42.140226 6.515506)
		(end 42.140226 8.786774)
		(width 0.12065)
		(layer "In7.Cu")
		(net "MUX_NFP_SMBUS_ALERT_L")
	)
	(segment
		(start 40.737003 2.542007)
		(end 40.737003 2.569997)
		(width 0.12065)
		(layer "In7.Cu")
		(net "MUX_NFP_SMBUS_ALERT_L")
	)
	(segment
		(start 22.101988 2.289988)
		(end 21.844 2.032)
		(width 0.14732)
		(layer "F.Cu")
		(net "MUX_NFP_PCIE0_WAKE_L")
	)
	(segment
		(start 22.101988 2.7432)
		(end 22.101988 2.289988)
		(width 0.14732)
		(layer "F.Cu")
		(net "MUX_NFP_PCIE0_WAKE_L")
	)
	(segment
		(start 21.209 1.4986)
		(end 21.1074 1.397)
		(width 0.14732)
		(layer "F.Cu")
		(net "MUX_NFP_PCIE0_WAKE_L")
	)
	(segment
		(start 21.463 2.032)
		(end 21.209 1.778)
		(width 0.14732)
		(layer "F.Cu")
		(net "MUX_NFP_PCIE0_WAKE_L")
	)
	(segment
		(start 21.844 2.032)
		(end 21.463 2.032)
		(width 0.14732)
		(layer "F.Cu")
		(net "MUX_NFP_PCIE0_WAKE_L")
	)
	(segment
		(start 21.209 1.778)
		(end 21.209 1.4986)
		(width 0.14732)
		(layer "F.Cu")
		(net "MUX_NFP_PCIE0_WAKE_L")
	)
	(segment
		(start 43.236998 10.041992)
		(end 42.736999 9.541993)
		(width 0.13208)
		(layer "F.Cu")
		(net "MUX_NFP_PCIE0_WAKE_L")
	)
	(via
		(at 30.988 2.032)
		(size 0.508)
		(drill 0.2667)
		(layers "F.Cu" "B.Cu")
		(net "MUX_NFP_PCIE0_WAKE_L")
	)
	(via
		(at 42.736999 9.541993)
		(size 0.4826)
		(drill 0.20574)
		(layers "F.Cu" "B.Cu")
		(net "MUX_NFP_PCIE0_WAKE_L")
	)
	(via
		(at 20.955 1.397)
		(size 0.508)
		(drill 0.25654)
		(layers "F.Cu" "B.Cu")
		(net "MUX_NFP_PCIE0_WAKE_L")
	)
	(segment
		(start 46.93539 0.19939)
		(end 45.847 -0.889)
		(width 0.12065)
		(layer "In6.Cu")
		(net "MUX_NFP_PCIE0_WAKE_L")
	)
	(segment
		(start 52.197 5.431714)
		(end 51.904062 5.138776)
		(width 0.12065)
		(layer "In6.Cu")
		(net "MUX_NFP_PCIE0_WAKE_L")
	)
	(segment
		(start 52.197 8.636)
		(end 52.197 5.431714)
		(width 0.12065)
		(layer "In6.Cu")
		(net "MUX_NFP_PCIE0_WAKE_L")
	)
	(segment
		(start 47.244 2.794)
		(end 47.244 2.04056)
		(width 0.12065)
		(layer "In6.Cu")
		(net "MUX_NFP_PCIE0_WAKE_L")
	)
	(segment
		(start 43.261991 9.017)
		(end 51.816 9.017)
		(width 0.12065)
		(layer "In6.Cu")
		(net "MUX_NFP_PCIE0_WAKE_L")
	)
	(segment
		(start 47.244 2.04056)
		(end 46.93539 1.73195)
		(width 0.12065)
		(layer "In6.Cu")
		(net "MUX_NFP_PCIE0_WAKE_L")
	)
	(segment
		(start 46.93539 1.73195)
		(end 46.93539 0.19939)
		(width 0.12065)
		(layer "In6.Cu")
		(net "MUX_NFP_PCIE0_WAKE_L")
	)
	(segment
		(start 51.816 9.017)
		(end 52.197 8.636)
		(width 0.12065)
		(layer "In6.Cu")
		(net "MUX_NFP_PCIE0_WAKE_L")
	)
	(segment
		(start 38.735 -0.889)
		(end 36.703 1.143)
		(width 0.12065)
		(layer "In6.Cu")
		(net "MUX_NFP_PCIE0_WAKE_L")
	)
	(segment
		(start 51.904062 5.138776)
		(end 49.588776 5.138776)
		(width 0.12065)
		(layer "In6.Cu")
		(net "MUX_NFP_PCIE0_WAKE_L")
	)
	(segment
		(start 42.736999 9.541993)
		(end 43.261991 9.017)
		(width 0.12065)
		(layer "In6.Cu")
		(net "MUX_NFP_PCIE0_WAKE_L")
	)
	(segment
		(start 31.877 1.143)
		(end 30.988 2.032)
		(width 0.12065)
		(layer "In6.Cu")
		(net "MUX_NFP_PCIE0_WAKE_L")
	)
	(segment
		(start 49.588776 5.138776)
		(end 47.244 2.794)
		(width 0.12065)
		(layer "In6.Cu")
		(net "MUX_NFP_PCIE0_WAKE_L")
	)
	(segment
		(start 36.703 1.143)
		(end 31.877 1.143)
		(width 0.12065)
		(layer "In6.Cu")
		(net "MUX_NFP_PCIE0_WAKE_L")
	)
	(segment
		(start 45.847 -0.889)
		(end 38.735 -0.889)
		(width 0.12065)
		(layer "In6.Cu")
		(net "MUX_NFP_PCIE0_WAKE_L")
	)
	(segment
		(start 30.089475 1.133475)
		(end 25.409525 1.133475)
		(width 0.12065)
		(layer "In7.Cu")
		(net "MUX_NFP_PCIE0_WAKE_L")
	)
	(segment
		(start 25.409525 1.133475)
		(end 24.638 1.905)
		(width 0.12065)
		(layer "In7.Cu")
		(net "MUX_NFP_PCIE0_WAKE_L")
	)
	(segment
		(start 30.988 2.032)
		(end 30.089475 1.133475)
		(width 0.12065)
		(layer "In7.Cu")
		(net "MUX_NFP_PCIE0_WAKE_L")
	)
	(segment
		(start 21.463 1.905)
		(end 20.955 1.397)
		(width 0.12065)
		(layer "In7.Cu")
		(net "MUX_NFP_PCIE0_WAKE_L")
	)
	(segment
		(start 24.638 1.905)
		(end 21.463 1.905)
		(width 0.12065)
		(layer "In7.Cu")
		(net "MUX_NFP_PCIE0_WAKE_L")
	)
	(segment
		(start 42.237 16.042005)
		(end 41.737001 15.542006)
		(width 0.13208)
		(layer "F.Cu")
		(net "MUX_NFP_GPIO3_NWK1_I2C_SDA")
	)
	(via
		(at 41.737001 15.542006)
		(size 0.4826)
		(drill 0.25654)
		(layers "F.Cu" "B.Cu")
		(net "MUX_NFP_GPIO3_NWK1_I2C_SDA")
	)
	(via
		(at 3.937 11.176)
		(size 0.508)
		(drill 0.25654)
		(layers "F.Cu" "B.Cu")
		(net "MUX_NFP_GPIO3_NWK1_I2C_SDA")
	)
	(segment
		(start 3.048 11.811)
		(end 3.429 11.811)
		(width 0.14732)
		(layer "B.Cu")
		(net "MUX_NFP_GPIO3_NWK1_I2C_SDA")
	)
	(segment
		(start 2.790012 12.068988)
		(end 3.048 11.811)
		(width 0.14732)
		(layer "B.Cu")
		(net "MUX_NFP_GPIO3_NWK1_I2C_SDA")
	)
	(segment
		(start 3.683 11.557)
		(end 3.683 11.2776)
		(width 0.14732)
		(layer "B.Cu")
		(net "MUX_NFP_GPIO3_NWK1_I2C_SDA")
	)
	(segment
		(start 3.683 11.2776)
		(end 3.7846 11.176)
		(width 0.14732)
		(layer "B.Cu")
		(net "MUX_NFP_GPIO3_NWK1_I2C_SDA")
	)
	(segment
		(start 3.429 11.811)
		(end 3.683 11.557)
		(width 0.14732)
		(layer "B.Cu")
		(net "MUX_NFP_GPIO3_NWK1_I2C_SDA")
	)
	(segment
		(start 2.790012 12.5222)
		(end 2.790012 12.068988)
		(width 0.14732)
		(layer "B.Cu")
		(net "MUX_NFP_GPIO3_NWK1_I2C_SDA")
	)
	(segment
		(start 40.14023 11.374933)
		(end 39.814297 11.049)
		(width 0.12065)
		(layer "In2.Cu")
		(net "MUX_NFP_GPIO3_NWK1_I2C_SDA")
	)
	(segment
		(start 26.67 13.97)
		(end 26.67 14.732)
		(width 0.12065)
		(layer "In2.Cu")
		(net "MUX_NFP_GPIO3_NWK1_I2C_SDA")
	)
	(segment
		(start 26.67 14.732)
		(end 25.4 16.002)
		(width 0.12065)
		(layer "In2.Cu")
		(net "MUX_NFP_GPIO3_NWK1_I2C_SDA")
	)
	(segment
		(start 40.904058 12.138787)
		(end 40.751023 12.138787)
		(width 0.12065)
		(layer "In2.Cu")
		(net "MUX_NFP_GPIO3_NWK1_I2C_SDA")
	)
	(segment
		(start 24.257 16.002)
		(end 22.098 18.161)
		(width 0.12065)
		(layer "In2.Cu")
		(net "MUX_NFP_GPIO3_NWK1_I2C_SDA")
	)
	(segment
		(start 41.751021 13.138785)
		(end 41.140228 12.527991)
		(width 0.12065)
		(layer "In2.Cu")
		(net "MUX_NFP_GPIO3_NWK1_I2C_SDA")
	)
	(segment
		(start 41.140228 12.527991)
		(end 41.140228 12.374956)
		(width 0.12065)
		(layer "In2.Cu")
		(net "MUX_NFP_GPIO3_NWK1_I2C_SDA")
	)
	(segment
		(start 43.132223 14.705736)
		(end 43.132223 14.37828)
		(width 0.104648)
		(layer "In2.Cu")
		(net "MUX_NFP_GPIO3_NWK1_I2C_SDA")
	)
	(segment
		(start 5.70865 13.738225)
		(end 3.937 11.966575)
		(width 0.12065)
		(layer "In2.Cu")
		(net "MUX_NFP_GPIO3_NWK1_I2C_SDA")
	)
	(segment
		(start 16.51 19.431)
		(end 16.51 19.356553)
		(width 0.12065)
		(layer "In2.Cu")
		(net "MUX_NFP_GPIO3_NWK1_I2C_SDA")
	)
	(segment
		(start 13.035229 14.125575)
		(end 12.093575 14.125575)
		(width 0.12065)
		(layer "In2.Cu")
		(net "MUX_NFP_GPIO3_NWK1_I2C_SDA")
	)
	(segment
		(start 17.430775 21.124545)
		(end 17.430775 20.351775)
		(width 0.12065)
		(layer "In2.Cu")
		(net "MUX_NFP_GPIO3_NWK1_I2C_SDA")
	)
	(segment
		(start 42.771492 14.937232)
		(end 42.900727 14.937232)
		(width 0.104648)
		(layer "In2.Cu")
		(net "MUX_NFP_GPIO3_NWK1_I2C_SDA")
	)
	(segment
		(start 41.904056 13.138785)
		(end 41.751021 13.138785)
		(width 0.12065)
		(layer "In2.Cu")
		(net "MUX_NFP_GPIO3_NWK1_I2C_SDA")
	)
	(segment
		(start 40.751023 12.138787)
		(end 40.14023 11.527993)
		(width 0.12065)
		(layer "In2.Cu")
		(net "MUX_NFP_GPIO3_NWK1_I2C_SDA")
	)
	(segment
		(start 13.681075 16.019729)
		(end 13.681075 14.771421)
		(width 0.12065)
		(layer "In2.Cu")
		(net "MUX_NFP_GPIO3_NWK1_I2C_SDA")
	)
	(segment
		(start 39.814297 11.049)
		(end 38.354 11.049)
		(width 0.12065)
		(layer "In2.Cu")
		(net "MUX_NFP_GPIO3_NWK1_I2C_SDA")
	)
	(segment
		(start 43.132223 14.37828)
		(end 42.900727 14.146784)
		(width 0.104648)
		(layer "In2.Cu")
		(net "MUX_NFP_GPIO3_NWK1_I2C_SDA")
	)
	(segment
		(start 42.233799 13.785799)
		(end 42.164 13.716)
		(width 0.12065)
		(layer "In2.Cu")
		(net "MUX_NFP_GPIO3_NWK1_I2C_SDA")
	)
	(segment
		(start 14.373225 16.278225)
		(end 13.939571 16.278225)
		(width 0.12065)
		(layer "In2.Cu")
		(net "MUX_NFP_GPIO3_NWK1_I2C_SDA")
	)
	(segment
		(start 31.556325 10.480675)
		(end 28.574924 13.462076)
		(width 0.12065)
		(layer "In2.Cu")
		(net "MUX_NFP_GPIO3_NWK1_I2C_SDA")
	)
	(segment
		(start 25.4 16.002)
		(end 24.257 16.002)
		(width 0.12065)
		(layer "In2.Cu")
		(net "MUX_NFP_GPIO3_NWK1_I2C_SDA")
	)
	(segment
		(start 14.605 17.451553)
		(end 14.605 16.51)
		(width 0.12065)
		(layer "In2.Cu")
		(net "MUX_NFP_GPIO3_NWK1_I2C_SDA")
	)
	(segment
		(start 3.937 11.966575)
		(end 3.937 11.176)
		(width 0.12065)
		(layer "In2.Cu")
		(net "MUX_NFP_GPIO3_NWK1_I2C_SDA")
	)
	(segment
		(start 41.737001 15.542006)
		(end 42.166718 15.542006)
		(width 0.12065)
		(layer "In2.Cu")
		(net "MUX_NFP_GPIO3_NWK1_I2C_SDA")
	)
	(segment
		(start 42.166718 15.542006)
		(end 42.43291 15.275814)
		(width 0.12065)
		(layer "In2.Cu")
		(net "MUX_NFP_GPIO3_NWK1_I2C_SDA")
	)
	(segment
		(start 14.605 16.51)
		(end 14.373225 16.278225)
		(width 0.12065)
		(layer "In2.Cu")
		(net "MUX_NFP_GPIO3_NWK1_I2C_SDA")
	)
	(segment
		(start 12.093575 14.125575)
		(end 11.706225 13.738225)
		(width 0.12065)
		(layer "In2.Cu")
		(net "MUX_NFP_GPIO3_NWK1_I2C_SDA")
	)
	(segment
		(start 28.574924 13.462076)
		(end 27.177924 13.462076)
		(width 0.12065)
		(layer "In2.Cu")
		(net "MUX_NFP_GPIO3_NWK1_I2C_SDA")
	)
	(segment
		(start 17.430775 20.351775)
		(end 16.51 19.431)
		(width 0.12065)
		(layer "In2.Cu")
		(net "MUX_NFP_GPIO3_NWK1_I2C_SDA")
	)
	(segment
		(start 42.43291 15.275814)
		(end 42.771492 14.937232)
		(width 0.104648)
		(layer "In2.Cu")
		(net "MUX_NFP_GPIO3_NWK1_I2C_SDA")
	)
	(segment
		(start 17.724755 21.418525)
		(end 17.430775 21.124545)
		(width 0.12065)
		(layer "In2.Cu")
		(net "MUX_NFP_GPIO3_NWK1_I2C_SDA")
	)
	(segment
		(start 42.164 13.716)
		(end 42.164 13.398729)
		(width 0.12065)
		(layer "In2.Cu")
		(net "MUX_NFP_GPIO3_NWK1_I2C_SDA")
	)
	(segment
		(start 19.094475 21.418525)
		(end 17.724755 21.418525)
		(width 0.12065)
		(layer "In2.Cu")
		(net "MUX_NFP_GPIO3_NWK1_I2C_SDA")
	)
	(segment
		(start 42.900727 14.937232)
		(end 43.132223 14.705736)
		(width 0.104648)
		(layer "In2.Cu")
		(net "MUX_NFP_GPIO3_NWK1_I2C_SDA")
	)
	(segment
		(start 42.900727 14.146784)
		(end 42.594784 14.146784)
		(width 0.104648)
		(layer "In2.Cu")
		(net "MUX_NFP_GPIO3_NWK1_I2C_SDA")
	)
	(segment
		(start 40.14023 11.527993)
		(end 40.14023 11.374933)
		(width 0.12065)
		(layer "In2.Cu")
		(net "MUX_NFP_GPIO3_NWK1_I2C_SDA")
	)
	(segment
		(start 13.681075 14.771421)
		(end 13.035229 14.125575)
		(width 0.12065)
		(layer "In2.Cu")
		(net "MUX_NFP_GPIO3_NWK1_I2C_SDA")
	)
	(segment
		(start 37.785675 10.480675)
		(end 31.556325 10.480675)
		(width 0.12065)
		(layer "In2.Cu")
		(net "MUX_NFP_GPIO3_NWK1_I2C_SDA")
	)
	(segment
		(start 11.706225 13.738225)
		(end 5.70865 13.738225)
		(width 0.12065)
		(layer "In2.Cu")
		(net "MUX_NFP_GPIO3_NWK1_I2C_SDA")
	)
	(segment
		(start 38.354 11.049)
		(end 37.785675 10.480675)
		(width 0.12065)
		(layer "In2.Cu")
		(net "MUX_NFP_GPIO3_NWK1_I2C_SDA")
	)
	(segment
		(start 16.51 19.356553)
		(end 14.605 17.451553)
		(width 0.12065)
		(layer "In2.Cu")
		(net "MUX_NFP_GPIO3_NWK1_I2C_SDA")
	)
	(segment
		(start 42.594784 14.146784)
		(end 42.233799 13.785799)
		(width 0.104648)
		(layer "In2.Cu")
		(net "MUX_NFP_GPIO3_NWK1_I2C_SDA")
	)
	(segment
		(start 41.140228 12.374956)
		(end 40.904058 12.138787)
		(width 0.12065)
		(layer "In2.Cu")
		(net "MUX_NFP_GPIO3_NWK1_I2C_SDA")
	)
	(segment
		(start 13.939571 16.278225)
		(end 13.681075 16.019729)
		(width 0.12065)
		(layer "In2.Cu")
		(net "MUX_NFP_GPIO3_NWK1_I2C_SDA")
	)
	(segment
		(start 22.098 18.415)
		(end 19.094475 21.418525)
		(width 0.12065)
		(layer "In2.Cu")
		(net "MUX_NFP_GPIO3_NWK1_I2C_SDA")
	)
	(segment
		(start 42.164 13.398729)
		(end 41.904056 13.138785)
		(width 0.12065)
		(layer "In2.Cu")
		(net "MUX_NFP_GPIO3_NWK1_I2C_SDA")
	)
	(segment
		(start 22.098 18.161)
		(end 22.098 18.415)
		(width 0.12065)
		(layer "In2.Cu")
		(net "MUX_NFP_GPIO3_NWK1_I2C_SDA")
	)
	(segment
		(start 27.177924 13.462076)
		(end 26.67 13.97)
		(width 0.12065)
		(layer "In2.Cu")
		(net "MUX_NFP_GPIO3_NWK1_I2C_SDA")
	)
	(segment
		(start 42.237 15.042007)
		(end 41.737001 14.542008)
		(width 0.13208)
		(layer "F.Cu")
		(net "MUX_NFP_GPIO2_NWK1_I2C_SCL")
	)
	(via
		(at 1.8034 11.176)
		(size 0.508)
		(drill 0.25654)
		(layers "F.Cu" "B.Cu")
		(net "MUX_NFP_GPIO2_NWK1_I2C_SCL")
	)
	(via
		(at 41.737001 14.542008)
		(size 0.4826)
		(drill 0.25654)
		(layers "F.Cu" "B.Cu")
		(net "MUX_NFP_GPIO2_NWK1_I2C_SCL")
	)
	(segment
		(start 1.28999 12.5222)
		(end 1.28999 12.137974)
		(width 0.14732)
		(layer "B.Cu")
		(net "MUX_NFP_GPIO2_NWK1_I2C_SCL")
	)
	(segment
		(start 1.8034 11.624564)
		(end 1.8034 11.176)
		(width 0.14732)
		(layer "B.Cu")
		(net "MUX_NFP_GPIO2_NWK1_I2C_SCL")
	)
	(segment
		(start 1.28999 12.137974)
		(end 1.8034 11.624564)
		(width 0.14732)
		(layer "B.Cu")
		(net "MUX_NFP_GPIO2_NWK1_I2C_SCL")
	)
	(segment
		(start 9.225229 16.278225)
		(end 5.715 16.278225)
		(width 0.12065)
		(layer "In2.Cu")
		(net "MUX_NFP_GPIO2_NWK1_I2C_SCL")
	)
	(segment
		(start 9.877425 15.395575)
		(end 9.483725 15.789275)
		(width 0.12065)
		(layer "In2.Cu")
		(net "MUX_NFP_GPIO2_NWK1_I2C_SCL")
	)
	(segment
		(start 41.164993 13.97)
		(end 40.910993 13.716)
		(width 0.12065)
		(layer "In2.Cu")
		(net "MUX_NFP_GPIO2_NWK1_I2C_SCL")
	)
	(segment
		(start 38.312192 14.138783)
		(end 34.543975 17.907)
		(width 0.12065)
		(layer "In2.Cu")
		(net "MUX_NFP_GPIO2_NWK1_I2C_SCL")
	)
	(segment
		(start 38.710514 14.138783)
		(end 38.312192 14.138783)
		(width 0.12065)
		(layer "In2.Cu")
		(net "MUX_NFP_GPIO2_NWK1_I2C_SCL")
	)
	(segment
		(start 9.483725 16.019729)
		(end 9.225229 16.278225)
		(width 0.12065)
		(layer "In2.Cu")
		(net "MUX_NFP_GPIO2_NWK1_I2C_SCL")
	)
	(segment
		(start 13.29784 16.928186)
		(end 13.035229 16.665575)
		(width 0.12065)
		(layer "In2.Cu")
		(net "MUX_NFP_GPIO2_NWK1_I2C_SCL")
	)
	(segment
		(start 15.7702 20.088225)
		(end 15.209571 20.088225)
		(width 0.12065)
		(layer "In2.Cu")
		(net "MUX_NFP_GPIO2_NWK1_I2C_SCL")
	)
	(segment
		(start 39.569949 13.138785)
		(end 39.33378 13.374954)
		(width 0.12065)
		(layer "In2.Cu")
		(net "MUX_NFP_GPIO2_NWK1_I2C_SCL")
	)
	(segment
		(start 1.8034 12.3444)
		(end 1.8034 11.176)
		(width 0.12065)
		(layer "In2.Cu")
		(net "MUX_NFP_GPIO2_NWK1_I2C_SCL")
	)
	(segment
		(start 3.428975 14.985975)
		(end 2.54 14.097)
		(width 0.12065)
		(layer "In2.Cu")
		(net "MUX_NFP_GPIO2_NWK1_I2C_SCL")
	)
	(segment
		(start 16.221075 20.5391)
		(end 15.7702 20.088225)
		(width 0.12065)
		(layer "In2.Cu")
		(net "MUX_NFP_GPIO2_NWK1_I2C_SCL")
	)
	(segment
		(start 16.80812 21.358225)
		(end 16.479571 21.358225)
		(width 0.12065)
		(layer "In2.Cu")
		(net "MUX_NFP_GPIO2_NWK1_I2C_SCL")
	)
	(segment
		(start 41.737001 14.432001)
		(end 41.275 13.97)
		(width 0.12065)
		(layer "In2.Cu")
		(net "MUX_NFP_GPIO2_NWK1_I2C_SCL")
	)
	(segment
		(start 24.069675 21.153171)
		(end 24.069675 21.269325)
		(width 0.12065)
		(layer "In2.Cu")
		(net "MUX_NFP_GPIO2_NWK1_I2C_SCL")
	)
	(segment
		(start 39.33378 13.374954)
		(end 39.33378 13.515518)
		(width 0.12065)
		(layer "In2.Cu")
		(net "MUX_NFP_GPIO2_NWK1_I2C_SCL")
	)
	(segment
		(start 34.543975 17.907)
		(end 27.315846 17.907)
		(width 0.12065)
		(layer "In2.Cu")
		(net "MUX_NFP_GPIO2_NWK1_I2C_SCL")
	)
	(segment
		(start 11.204677 15.395575)
		(end 9.877425 15.395575)
		(width 0.12065)
		(layer "In2.Cu")
		(net "MUX_NFP_GPIO2_NWK1_I2C_SCL")
	)
	(segment
		(start 13.035229 16.665575)
		(end 12.474677 16.665575)
		(width 0.12065)
		(layer "In2.Cu")
		(net "MUX_NFP_GPIO2_NWK1_I2C_SCL")
	)
	(segment
		(start 2.54 13.081)
		(end 1.8034 12.3444)
		(width 0.12065)
		(layer "In2.Cu")
		(net "MUX_NFP_GPIO2_NWK1_I2C_SCL")
	)
	(segment
		(start 39.33378 13.515518)
		(end 38.710514 14.138783)
		(width 0.12065)
		(layer "In2.Cu")
		(net "MUX_NFP_GPIO2_NWK1_I2C_SCL")
	)
	(segment
		(start 9.483725 15.789275)
		(end 9.483725 16.019729)
		(width 0.12065)
		(layer "In2.Cu")
		(net "MUX_NFP_GPIO2_NWK1_I2C_SCL")
	)
	(segment
		(start 40.910993 13.716)
		(end 40.513 13.716)
		(width 0.12065)
		(layer "In2.Cu")
		(net "MUX_NFP_GPIO2_NWK1_I2C_SCL")
	)
	(segment
		(start 21.077504 21.971)
		(end 17.420895 21.971)
		(width 0.12065)
		(layer "In2.Cu")
		(net "MUX_NFP_GPIO2_NWK1_I2C_SCL")
	)
	(segment
		(start 15.209571 20.088225)
		(end 13.29784 18.176494)
		(width 0.12065)
		(layer "In2.Cu")
		(net "MUX_NFP_GPIO2_NWK1_I2C_SCL")
	)
	(segment
		(start 24.069675 21.269325)
		(end 23.561675 21.777325)
		(width 0.12065)
		(layer "In2.Cu")
		(net "MUX_NFP_GPIO2_NWK1_I2C_SCL")
	)
	(segment
		(start 13.29784 18.176494)
		(end 13.29784 16.928186)
		(width 0.12065)
		(layer "In2.Cu")
		(net "MUX_NFP_GPIO2_NWK1_I2C_SCL")
	)
	(segment
		(start 27.315846 17.907)
		(end 24.069675 21.153171)
		(width 0.12065)
		(layer "In2.Cu")
		(net "MUX_NFP_GPIO2_NWK1_I2C_SCL")
	)
	(segment
		(start 12.474677 16.665575)
		(end 11.204677 15.395575)
		(width 0.12065)
		(layer "In2.Cu")
		(net "MUX_NFP_GPIO2_NWK1_I2C_SCL")
	)
	(segment
		(start 16.479571 21.358225)
		(end 16.221075 21.099729)
		(width 0.12065)
		(layer "In2.Cu")
		(net "MUX_NFP_GPIO2_NWK1_I2C_SCL")
	)
	(segment
		(start 39.935785 13.138785)
		(end 39.569949 13.138785)
		(width 0.12065)
		(layer "In2.Cu")
		(net "MUX_NFP_GPIO2_NWK1_I2C_SCL")
	)
	(segment
		(start 16.221075 21.099729)
		(end 16.221075 20.5391)
		(width 0.12065)
		(layer "In2.Cu")
		(net "MUX_NFP_GPIO2_NWK1_I2C_SCL")
	)
	(segment
		(start 23.561675 21.777325)
		(end 21.271179 21.777325)
		(width 0.12065)
		(layer "In2.Cu")
		(net "MUX_NFP_GPIO2_NWK1_I2C_SCL")
	)
	(segment
		(start 17.420895 21.971)
		(end 16.80812 21.358225)
		(width 0.12065)
		(layer "In2.Cu")
		(net "MUX_NFP_GPIO2_NWK1_I2C_SCL")
	)
	(segment
		(start 41.275 13.97)
		(end 41.164993 13.97)
		(width 0.12065)
		(layer "In2.Cu")
		(net "MUX_NFP_GPIO2_NWK1_I2C_SCL")
	)
	(segment
		(start 40.513 13.716)
		(end 39.935785 13.138785)
		(width 0.12065)
		(layer "In2.Cu")
		(net "MUX_NFP_GPIO2_NWK1_I2C_SCL")
	)
	(segment
		(start 4.42275 14.985975)
		(end 3.428975 14.985975)
		(width 0.12065)
		(layer "In2.Cu")
		(net "MUX_NFP_GPIO2_NWK1_I2C_SCL")
	)
	(segment
		(start 41.737001 14.542008)
		(end 41.737001 14.432001)
		(width 0.12065)
		(layer "In2.Cu")
		(net "MUX_NFP_GPIO2_NWK1_I2C_SCL")
	)
	(segment
		(start 21.271179 21.777325)
		(end 21.077504 21.971)
		(width 0.12065)
		(layer "In2.Cu")
		(net "MUX_NFP_GPIO2_NWK1_I2C_SCL")
	)
	(segment
		(start 5.715 16.278225)
		(end 4.42275 14.985975)
		(width 0.12065)
		(layer "In2.Cu")
		(net "MUX_NFP_GPIO2_NWK1_I2C_SCL")
	)
	(segment
		(start 2.54 14.097)
		(end 2.54 13.081)
		(width 0.12065)
		(layer "In2.Cu")
		(net "MUX_NFP_GPIO2_NWK1_I2C_SCL")
	)
	(segment
		(start 43.236998 16.042005)
		(end 42.736999 15.542006)
		(width 0.13208)
		(layer "F.Cu")
		(net "MUX_NFP_GPIO1_NWK0_I2C_SDA")
	)
	(via
		(at 1.8034 16.129)
		(size 0.508)
		(drill 0.25654)
		(layers "F.Cu" "B.Cu")
		(net "MUX_NFP_GPIO1_NWK0_I2C_SDA")
	)
	(via
		(at 1.651 17.272)
		(size 0.762)
		(drill 0.381)
		(layers "F.Cu" "B.Cu")
		(net "MUX_NFP_GPIO1_NWK0_I2C_SDA")
	)
	(via
		(at 42.736999 15.542006)
		(size 0.4826)
		(drill 0.20574)
		(layers "F.Cu" "B.Cu")
		(net "MUX_NFP_GPIO1_NWK0_I2C_SDA")
	)
	(segment
		(start 1.8034 17.1196)
		(end 1.651 17.272)
		(width 0.14732)
		(layer "B.Cu")
		(net "MUX_NFP_GPIO1_NWK0_I2C_SDA")
	)
	(segment
		(start 1.789989 14.9098)
		(end 1.789989 16.115589)
		(width 0.14732)
		(layer "B.Cu")
		(net "MUX_NFP_GPIO1_NWK0_I2C_SDA")
	)
	(segment
		(start 1.8034 16.129)
		(end 1.8034 17.1196)
		(width 0.14732)
		(layer "B.Cu")
		(net "MUX_NFP_GPIO1_NWK0_I2C_SDA")
	)
	(segment
		(start 1.789989 16.115589)
		(end 1.8034 16.129)
		(width 0.14732)
		(layer "B.Cu")
		(net "MUX_NFP_GPIO1_NWK0_I2C_SDA")
	)
	(segment
		(start 11.138738 17.309084)
		(end 11.138738 20.155738)
		(width 0.12065)
		(layer "In2.Cu")
		(net "MUX_NFP_GPIO1_NWK0_I2C_SDA")
	)
	(segment
		(start 10.129571 16.665575)
		(end 10.495229 16.665575)
		(width 0.12065)
		(layer "In2.Cu")
		(net "MUX_NFP_GPIO1_NWK0_I2C_SDA")
	)
	(segment
		(start 9.871075 17.306925)
		(end 9.871075 16.924071)
		(width 0.12065)
		(layer "In2.Cu")
		(net "MUX_NFP_GPIO1_NWK0_I2C_SDA")
	)
	(segment
		(start 42.291 16.002)
		(end 42.736999 15.556001)
		(width 0.12065)
		(layer "In2.Cu")
		(net "MUX_NFP_GPIO1_NWK0_I2C_SDA")
	)
	(segment
		(start 26.761796 20.601559)
		(end 26.769441 20.601559)
		(width 0.12065)
		(layer "In2.Cu")
		(net "MUX_NFP_GPIO1_NWK0_I2C_SDA")
	)
	(segment
		(start 9.525 17.653)
		(end 9.871075 17.306925)
		(width 0.12065)
		(layer "In2.Cu")
		(net "MUX_NFP_GPIO1_NWK0_I2C_SDA")
	)
	(segment
		(start 11.43 20.447)
		(end 13.208 20.447)
		(width 0.12065)
		(layer "In2.Cu")
		(net "MUX_NFP_GPIO1_NWK0_I2C_SDA")
	)
	(segment
		(start 13.208 20.447)
		(end 13.462 20.701)
		(width 0.12065)
		(layer "In2.Cu")
		(net "MUX_NFP_GPIO1_NWK0_I2C_SDA")
	)
	(segment
		(start 39.497 15.113)
		(end 41.021 15.113)
		(width 0.12065)
		(layer "In2.Cu")
		(net "MUX_NFP_GPIO1_NWK0_I2C_SDA")
	)
	(segment
		(start 16.221075 21.80021)
		(end 16.221075 22.369729)
		(width 0.12065)
		(layer "In2.Cu")
		(net "MUX_NFP_GPIO1_NWK0_I2C_SDA")
	)
	(segment
		(start 8.382 18.669)
		(end 8.382 18.161)
		(width 0.12065)
		(layer "In2.Cu")
		(net "MUX_NFP_GPIO1_NWK0_I2C_SDA")
	)
	(segment
		(start 15.883865 21.463)
		(end 16.221075 21.80021)
		(width 0.12065)
		(layer "In2.Cu")
		(net "MUX_NFP_GPIO1_NWK0_I2C_SDA")
	)
	(segment
		(start 16.221075 22.369729)
		(end 16.505504 22.654184)
		(width 0.12065)
		(layer "In2.Cu")
		(net "MUX_NFP_GPIO1_NWK0_I2C_SDA")
	)
	(segment
		(start 8.128 18.923)
		(end 8.382 18.669)
		(width 0.12065)
		(layer "In2.Cu")
		(net "MUX_NFP_GPIO1_NWK0_I2C_SDA")
	)
	(segment
		(start 39.140232 15.709062)
		(end 39.140232 15.469768)
		(width 0.12065)
		(layer "In2.Cu")
		(net "MUX_NFP_GPIO1_NWK0_I2C_SDA")
	)
	(segment
		(start 38.156769 15.945231)
		(end 38.904062 15.945231)
		(width 0.12065)
		(layer "In2.Cu")
		(net "MUX_NFP_GPIO1_NWK0_I2C_SDA")
	)
	(segment
		(start 29.402684 19.303975)
		(end 34.798025 19.303975)
		(width 0.12065)
		(layer "In2.Cu")
		(net "MUX_NFP_GPIO1_NWK0_I2C_SDA")
	)
	(segment
		(start 11.138738 20.155738)
		(end 11.43 20.447)
		(width 0.12065)
		(layer "In2.Cu")
		(net "MUX_NFP_GPIO1_NWK0_I2C_SDA")
	)
	(segment
		(start 24.887072 22.304375)
		(end 25.347524 21.843924)
		(width 0.12065)
		(layer "In2.Cu")
		(net "MUX_NFP_GPIO1_NWK0_I2C_SDA")
	)
	(segment
		(start 4.5974 18.923)
		(end 8.128 18.923)
		(width 0.12065)
		(layer "In2.Cu")
		(net "MUX_NFP_GPIO1_NWK0_I2C_SDA")
	)
	(segment
		(start 25.400076 21.843924)
		(end 26.413104 20.830896)
		(width 0.12065)
		(layer "In2.Cu")
		(net "MUX_NFP_GPIO1_NWK0_I2C_SDA")
	)
	(segment
		(start 8.89 17.653)
		(end 9.525 17.653)
		(width 0.12065)
		(layer "In2.Cu")
		(net "MUX_NFP_GPIO1_NWK0_I2C_SDA")
	)
	(segment
		(start 13.462 20.701)
		(end 13.462 20.955)
		(width 0.12065)
		(layer "In2.Cu")
		(net "MUX_NFP_GPIO1_NWK0_I2C_SDA")
	)
	(segment
		(start 1.8034 16.129)
		(end 4.5974 18.923)
		(width 0.12065)
		(layer "In2.Cu")
		(net "MUX_NFP_GPIO1_NWK0_I2C_SDA")
	)
	(segment
		(start 10.495229 16.665575)
		(end 11.138738 17.309084)
		(width 0.12065)
		(layer "In2.Cu")
		(net "MUX_NFP_GPIO1_NWK0_I2C_SDA")
	)
	(segment
		(start 16.995775 22.733)
		(end 22.098 22.733)
		(width 0.12065)
		(layer "In2.Cu")
		(net "MUX_NFP_GPIO1_NWK0_I2C_SDA")
	)
	(segment
		(start 41.529 16.002)
		(end 42.291 16.002)
		(width 0.12065)
		(layer "In2.Cu")
		(net "MUX_NFP_GPIO1_NWK0_I2C_SDA")
	)
	(segment
		(start 26.532459 20.830896)
		(end 26.761796 20.601559)
		(width 0.12065)
		(layer "In2.Cu")
		(net "MUX_NFP_GPIO1_NWK0_I2C_SDA")
	)
	(segment
		(start 22.098 22.733)
		(end 22.526625 22.304375)
		(width 0.12065)
		(layer "In2.Cu")
		(net "MUX_NFP_GPIO1_NWK0_I2C_SDA")
	)
	(segment
		(start 29.275659 19.431)
		(end 29.402684 19.303975)
		(width 0.12065)
		(layer "In2.Cu")
		(net "MUX_NFP_GPIO1_NWK0_I2C_SDA")
	)
	(segment
		(start 8.382 18.161)
		(end 8.89 17.653)
		(width 0.12065)
		(layer "In2.Cu")
		(net "MUX_NFP_GPIO1_NWK0_I2C_SDA")
	)
	(segment
		(start 38.904062 15.945231)
		(end 39.140232 15.709062)
		(width 0.12065)
		(layer "In2.Cu")
		(net "MUX_NFP_GPIO1_NWK0_I2C_SDA")
	)
	(segment
		(start 22.526625 22.304375)
		(end 24.887072 22.304375)
		(width 0.12065)
		(layer "In2.Cu")
		(net "MUX_NFP_GPIO1_NWK0_I2C_SDA")
	)
	(segment
		(start 26.769441 20.601559)
		(end 27.94 19.431)
		(width 0.12065)
		(layer "In2.Cu")
		(net "MUX_NFP_GPIO1_NWK0_I2C_SDA")
	)
	(segment
		(start 42.736999 15.556001)
		(end 42.736999 15.542006)
		(width 0.12065)
		(layer "In2.Cu")
		(net "MUX_NFP_GPIO1_NWK0_I2C_SDA")
	)
	(segment
		(start 34.798025 19.303975)
		(end 38.156769 15.945231)
		(width 0.12065)
		(layer "In2.Cu")
		(net "MUX_NFP_GPIO1_NWK0_I2C_SDA")
	)
	(segment
		(start 13.97 21.463)
		(end 15.883865 21.463)
		(width 0.12065)
		(layer "In2.Cu")
		(net "MUX_NFP_GPIO1_NWK0_I2C_SDA")
	)
	(segment
		(start 13.462 20.955)
		(end 13.97 21.463)
		(width 0.12065)
		(layer "In2.Cu")
		(net "MUX_NFP_GPIO1_NWK0_I2C_SDA")
	)
	(segment
		(start 16.505504 22.654184)
		(end 16.916959 22.654184)
		(width 0.12065)
		(layer "In2.Cu")
		(net "MUX_NFP_GPIO1_NWK0_I2C_SDA")
	)
	(segment
		(start 27.94 19.431)
		(end 29.275659 19.431)
		(width 0.12065)
		(layer "In2.Cu")
		(net "MUX_NFP_GPIO1_NWK0_I2C_SDA")
	)
	(segment
		(start 39.140232 15.469768)
		(end 39.497 15.113)
		(width 0.12065)
		(layer "In2.Cu")
		(net "MUX_NFP_GPIO1_NWK0_I2C_SDA")
	)
	(segment
		(start 9.871075 16.924071)
		(end 10.129571 16.665575)
		(width 0.12065)
		(layer "In2.Cu")
		(net "MUX_NFP_GPIO1_NWK0_I2C_SDA")
	)
	(segment
		(start 41.275 15.748)
		(end 41.529 16.002)
		(width 0.12065)
		(layer "In2.Cu")
		(net "MUX_NFP_GPIO1_NWK0_I2C_SDA")
	)
	(segment
		(start 25.347524 21.843924)
		(end 25.400076 21.843924)
		(width 0.12065)
		(layer "In2.Cu")
		(net "MUX_NFP_GPIO1_NWK0_I2C_SDA")
	)
	(segment
		(start 16.916959 22.654184)
		(end 16.995775 22.733)
		(width 0.12065)
		(layer "In2.Cu")
		(net "MUX_NFP_GPIO1_NWK0_I2C_SDA")
	)
	(segment
		(start 41.021 15.113)
		(end 41.275 15.367)
		(width 0.12065)
		(layer "In2.Cu")
		(net "MUX_NFP_GPIO1_NWK0_I2C_SDA")
	)
	(segment
		(start 41.275 15.367)
		(end 41.275 15.748)
		(width 0.12065)
		(layer "In2.Cu")
		(net "MUX_NFP_GPIO1_NWK0_I2C_SDA")
	)
	(segment
		(start 26.413104 20.830896)
		(end 26.532459 20.830896)
		(width 0.12065)
		(layer "In2.Cu")
		(net "MUX_NFP_GPIO1_NWK0_I2C_SDA")
	)
	(segment
		(start 43.236998 15.042007)
		(end 42.736999 14.542008)
		(width 0.13208)
		(layer "F.Cu")
		(net "MUX_NFP_GPIO0_NWK0_I2C_SCL")
	)
	(via
		(at 3.937 16.129)
		(size 0.508)
		(drill 0.25654)
		(layers "F.Cu" "B.Cu")
		(net "MUX_NFP_GPIO0_NWK0_I2C_SCL")
	)
	(via
		(at 42.736999 14.542008)
		(size 0.4826)
		(drill 0.20574)
		(layers "F.Cu" "B.Cu")
		(net "MUX_NFP_GPIO0_NWK0_I2C_SCL")
	)
	(via
		(at 1.27 20.193)
		(size 0.508)
		(drill 0.2667)
		(layers "F.Cu" "B.Cu")
		(net "MUX_NFP_GPIO0_NWK0_I2C_SCL")
	)
	(segment
		(start 3.683 15.621)
		(end 3.7846 15.7226)
		(width 0.14732)
		(layer "B.Cu")
		(net "MUX_NFP_GPIO0_NWK0_I2C_SCL")
	)
	(segment
		(start 3.290011 14.9098)
		(end 3.302 14.921789)
		(width 0.14732)
		(layer "B.Cu")
		(net "MUX_NFP_GPIO0_NWK0_I2C_SCL")
	)
	(segment
		(start 3.302 14.921789)
		(end 3.302 15.494)
		(width 0.14732)
		(layer "B.Cu")
		(net "MUX_NFP_GPIO0_NWK0_I2C_SCL")
	)
	(segment
		(start 3.429 15.621)
		(end 3.683 15.621)
		(width 0.14732)
		(layer "B.Cu")
		(net "MUX_NFP_GPIO0_NWK0_I2C_SCL")
	)
	(segment
		(start 3.302 15.494)
		(end 3.429 15.621)
		(width 0.14732)
		(layer "B.Cu")
		(net "MUX_NFP_GPIO0_NWK0_I2C_SCL")
	)
	(segment
		(start 3.7846 15.7226)
		(end 3.7846 16.129)
		(width 0.14732)
		(layer "B.Cu")
		(net "MUX_NFP_GPIO0_NWK0_I2C_SCL")
	)
	(segment
		(start 7.432675 16.951325)
		(end 7.432675 16.924071)
		(width 0.12065)
		(layer "In2.Cu")
		(net "MUX_NFP_GPIO0_NWK0_I2C_SCL")
	)
	(segment
		(start 22.726218 22.056725)
		(end 22.757968 22.024975)
		(width 0.12065)
		(layer "In2.Cu")
		(net "MUX_NFP_GPIO0_NWK0_I2C_SCL")
	)
	(segment
		(start 23.506278 22.056725)
		(end 23.991722 22.056725)
		(width 0.12065)
		(layer "In2.Cu")
		(net "MUX_NFP_GPIO0_NWK0_I2C_SCL")
	)
	(segment
		(start 7.432675 16.924071)
		(end 7.691171 16.665575)
		(width 0.12065)
		(layer "In2.Cu")
		(net "MUX_NFP_GPIO0_NWK0_I2C_SCL")
	)
	(segment
		(start 23.991722 22.056725)
		(end 24.204447 21.844)
		(width 0.12065)
		(layer "In2.Cu")
		(net "MUX_NFP_GPIO0_NWK0_I2C_SCL")
	)
	(segment
		(start 32.512 18.415)
		(end 32.699325 18.227675)
		(width 0.12065)
		(layer "In2.Cu")
		(net "MUX_NFP_GPIO0_NWK0_I2C_SCL")
	)
	(segment
		(start 21.37725 22.056725)
		(end 22.726218 22.056725)
		(width 0.12065)
		(layer "In2.Cu")
		(net "MUX_NFP_GPIO0_NWK0_I2C_SCL")
	)
	(segment
		(start 35.112325 18.227675)
		(end 38.394767 14.945233)
		(width 0.12065)
		(layer "In2.Cu")
		(net "MUX_NFP_GPIO0_NWK0_I2C_SCL")
	)
	(segment
		(start 11.377879 16.278225)
		(end 12.411075 17.311421)
		(width 0.12065)
		(layer "In2.Cu")
		(net "MUX_NFP_GPIO0_NWK0_I2C_SCL")
	)
	(segment
		(start 4.826 17.78)
		(end 6.985 17.78)
		(width 0.12065)
		(layer "In2.Cu")
		(net "MUX_NFP_GPIO0_NWK0_I2C_SCL")
	)
	(segment
		(start 39.569949 14.138783)
		(end 39.582217 14.138783)
		(width 0.12065)
		(layer "In2.Cu")
		(net "MUX_NFP_GPIO0_NWK0_I2C_SCL")
	)
	(segment
		(start 27.432 19.05)
		(end 29.21 19.05)
		(width 0.12065)
		(layer "In2.Cu")
		(net "MUX_NFP_GPIO0_NWK0_I2C_SCL")
	)
	(segment
		(start 12.411075 17.311421)
		(end 12.411075 18.761075)
		(width 0.12065)
		(layer "In2.Cu")
		(net "MUX_NFP_GPIO0_NWK0_I2C_SCL")
	)
	(segment
		(start 15.833725 21.06262)
		(end 16.488105 21.717)
		(width 0.12065)
		(layer "In2.Cu")
		(net "MUX_NFP_GPIO0_NWK0_I2C_SCL")
	)
	(segment
		(start 23.474528 22.024975)
		(end 23.506278 22.056725)
		(width 0.12065)
		(layer "In2.Cu")
		(net "MUX_NFP_GPIO0_NWK0_I2C_SCL")
	)
	(segment
		(start 39.624 14.097)
		(end 40.862275 14.097)
		(width 0.12065)
		(layer "In2.Cu")
		(net "MUX_NFP_GPIO0_NWK0_I2C_SCL")
	)
	(segment
		(start 17.324654 22.225)
		(end 21.208975 22.225)
		(width 0.12065)
		(layer "In2.Cu")
		(net "MUX_NFP_GPIO0_NWK0_I2C_SCL")
	)
	(segment
		(start 41.140228 14.515516)
		(end 41.569945 14.945233)
		(width 0.12065)
		(layer "In2.Cu")
		(net "MUX_NFP_GPIO0_NWK0_I2C_SCL")
	)
	(segment
		(start 7.366 17.399)
		(end 7.366 17.018)
		(width 0.12065)
		(layer "In2.Cu")
		(net "MUX_NFP_GPIO0_NWK0_I2C_SCL")
	)
	(segment
		(start 39.33378 14.38722)
		(end 39.33378 14.374952)
		(width 0.12065)
		(layer "In2.Cu")
		(net "MUX_NFP_GPIO0_NWK0_I2C_SCL")
	)
	(segment
		(start 29.21 19.05)
		(end 29.845 18.415)
		(width 0.12065)
		(layer "In2.Cu")
		(net "MUX_NFP_GPIO0_NWK0_I2C_SCL")
	)
	(segment
		(start 14.900656 20.488681)
		(end 15.071293 20.488681)
		(width 0.12065)
		(layer "In2.Cu")
		(net "MUX_NFP_GPIO0_NWK0_I2C_SCL")
	)
	(segment
		(start 16.816654 21.717)
		(end 17.324654 22.225)
		(width 0.12065)
		(layer "In2.Cu")
		(net "MUX_NFP_GPIO0_NWK0_I2C_SCL")
	)
	(segment
		(start 12.411075 18.761075)
		(end 12.827 19.177)
		(width 0.12065)
		(layer "In2.Cu")
		(net "MUX_NFP_GPIO0_NWK0_I2C_SCL")
	)
	(segment
		(start 24.204447 21.844)
		(end 24.638 21.844)
		(width 0.12065)
		(layer "In2.Cu")
		(net "MUX_NFP_GPIO0_NWK0_I2C_SCL")
	)
	(segment
		(start 14.223975 19.812)
		(end 14.900656 20.488681)
		(width 0.12065)
		(layer "In2.Cu")
		(net "MUX_NFP_GPIO0_NWK0_I2C_SCL")
	)
	(segment
		(start 16.488105 21.717)
		(end 16.816654 21.717)
		(width 0.12065)
		(layer "In2.Cu")
		(net "MUX_NFP_GPIO0_NWK0_I2C_SCL")
	)
	(segment
		(start 3.937 16.129)
		(end 3.937 16.891)
		(width 0.12065)
		(layer "In2.Cu")
		(net "MUX_NFP_GPIO0_NWK0_I2C_SCL")
	)
	(segment
		(start 7.366 17.018)
		(end 7.432675 16.951325)
		(width 0.12065)
		(layer "In2.Cu")
		(net "MUX_NFP_GPIO0_NWK0_I2C_SCL")
	)
	(segment
		(start 13.97 19.812)
		(end 14.223975 19.812)
		(width 0.12065)
		(layer "In2.Cu")
		(net "MUX_NFP_GPIO0_NWK0_I2C_SCL")
	)
	(segment
		(start 39.33378 14.374952)
		(end 39.569949 14.138783)
		(width 0.12065)
		(layer "In2.Cu")
		(net "MUX_NFP_GPIO0_NWK0_I2C_SCL")
	)
	(segment
		(start 6.985 17.78)
		(end 7.366 17.399)
		(width 0.12065)
		(layer "In2.Cu")
		(net "MUX_NFP_GPIO0_NWK0_I2C_SCL")
	)
	(segment
		(start 10.137775 16.278225)
		(end 11.377879 16.278225)
		(width 0.12065)
		(layer "In2.Cu")
		(net "MUX_NFP_GPIO0_NWK0_I2C_SCL")
	)
	(segment
		(start 42.333774 14.945233)
		(end 42.736999 14.542008)
		(width 0.12065)
		(layer "In2.Cu")
		(net "MUX_NFP_GPIO0_NWK0_I2C_SCL")
	)
	(segment
		(start 21.208975 22.225)
		(end 21.37725 22.056725)
		(width 0.12065)
		(layer "In2.Cu")
		(net "MUX_NFP_GPIO0_NWK0_I2C_SCL")
	)
	(segment
		(start 3.937 16.891)
		(end 4.826 17.78)
		(width 0.12065)
		(layer "In2.Cu")
		(net "MUX_NFP_GPIO0_NWK0_I2C_SCL")
	)
	(segment
		(start 40.862275 14.097)
		(end 41.140228 14.374952)
		(width 0.12065)
		(layer "In2.Cu")
		(net "MUX_NFP_GPIO0_NWK0_I2C_SCL")
	)
	(segment
		(start 15.0844 20.475575)
		(end 15.575229 20.475575)
		(width 0.12065)
		(layer "In2.Cu")
		(net "MUX_NFP_GPIO0_NWK0_I2C_SCL")
	)
	(segment
		(start 39.140232 14.709064)
		(end 39.140232 14.580768)
		(width 0.12065)
		(layer "In2.Cu")
		(net "MUX_NFP_GPIO0_NWK0_I2C_SCL")
	)
	(segment
		(start 29.845 18.415)
		(end 32.512 18.415)
		(width 0.12065)
		(layer "In2.Cu")
		(net "MUX_NFP_GPIO0_NWK0_I2C_SCL")
	)
	(segment
		(start 15.833725 20.734071)
		(end 15.833725 21.06262)
		(width 0.12065)
		(layer "In2.Cu")
		(net "MUX_NFP_GPIO0_NWK0_I2C_SCL")
	)
	(segment
		(start 15.575229 20.475575)
		(end 15.833725 20.734071)
		(width 0.12065)
		(layer "In2.Cu")
		(net "MUX_NFP_GPIO0_NWK0_I2C_SCL")
	)
	(segment
		(start 39.140232 14.580768)
		(end 39.33378 14.38722)
		(width 0.12065)
		(layer "In2.Cu")
		(net "MUX_NFP_GPIO0_NWK0_I2C_SCL")
	)
	(segment
		(start 7.691171 16.665575)
		(end 9.750425 16.665575)
		(width 0.12065)
		(layer "In2.Cu")
		(net "MUX_NFP_GPIO0_NWK0_I2C_SCL")
	)
	(segment
		(start 41.569945 14.945233)
		(end 42.333774 14.945233)
		(width 0.12065)
		(layer "In2.Cu")
		(net "MUX_NFP_GPIO0_NWK0_I2C_SCL")
	)
	(segment
		(start 15.071293 20.488681)
		(end 15.0844 20.475575)
		(width 0.12065)
		(layer "In2.Cu")
		(net "MUX_NFP_GPIO0_NWK0_I2C_SCL")
	)
	(segment
		(start 24.638 21.844)
		(end 27.432 19.05)
		(width 0.12065)
		(layer "In2.Cu")
		(net "MUX_NFP_GPIO0_NWK0_I2C_SCL")
	)
	(segment
		(start 9.750425 16.665575)
		(end 10.137775 16.278225)
		(width 0.12065)
		(layer "In2.Cu")
		(net "MUX_NFP_GPIO0_NWK0_I2C_SCL")
	)
	(segment
		(start 38.394767 14.945233)
		(end 38.904062 14.945233)
		(width 0.12065)
		(layer "In2.Cu")
		(net "MUX_NFP_GPIO0_NWK0_I2C_SCL")
	)
	(segment
		(start 38.904062 14.945233)
		(end 39.140232 14.709064)
		(width 0.12065)
		(layer "In2.Cu")
		(net "MUX_NFP_GPIO0_NWK0_I2C_SCL")
	)
	(segment
		(start 32.699325 18.227675)
		(end 35.112325 18.227675)
		(width 0.12065)
		(layer "In2.Cu")
		(net "MUX_NFP_GPIO0_NWK0_I2C_SCL")
	)
	(segment
		(start 13.335 19.177)
		(end 13.97 19.812)
		(width 0.12065)
		(layer "In2.Cu")
		(net "MUX_NFP_GPIO0_NWK0_I2C_SCL")
	)
	(segment
		(start 39.582217 14.138783)
		(end 39.624 14.097)
		(width 0.12065)
		(layer "In2.Cu")
		(net "MUX_NFP_GPIO0_NWK0_I2C_SCL")
	)
	(segment
		(start 22.757968 22.024975)
		(end 23.474528 22.024975)
		(width 0.12065)
		(layer "In2.Cu")
		(net "MUX_NFP_GPIO0_NWK0_I2C_SCL")
	)
	(segment
		(start 12.827 19.177)
		(end 13.335 19.177)
		(width 0.12065)
		(layer "In2.Cu")
		(net "MUX_NFP_GPIO0_NWK0_I2C_SCL")
	)
	(segment
		(start 41.140228 14.374952)
		(end 41.140228 14.515516)
		(width 0.12065)
		(layer "In2.Cu")
		(net "MUX_NFP_GPIO0_NWK0_I2C_SCL")
	)
	(segment
		(start 1.778 18.288)
		(end 3.937 16.129)
		(width 0.12065)
		(layer "In6.Cu")
		(net "MUX_NFP_GPIO0_NWK0_I2C_SCL")
	)
	(segment
		(start 1.27 20.193)
		(end 1.778 19.685)
		(width 0.12065)
		(layer "In6.Cu")
		(net "MUX_NFP_GPIO0_NWK0_I2C_SCL")
	)
	(segment
		(start 1.778 19.685)
		(end 1.778 18.288)
		(width 0.12065)
		(layer "In6.Cu")
		(net "MUX_NFP_GPIO0_NWK0_I2C_SCL")
	)
	(segment
		(start 17.653 13.843)
		(end 18.542 14.732)
		(width 0.14732)
		(layer "F.Cu")
		(net "CPLD_SMBUS_SDA")
	)
	(segment
		(start 17.653 12.6111)
		(end 17.653 13.843)
		(width 0.14732)
		(layer "F.Cu")
		(net "CPLD_SMBUS_SDA")
	)
	(via
		(at 18.542 14.732)
		(size 0.762)
		(drill 0.2667)
		(layers "F.Cu" "B.Cu")
		(net "CPLD_SMBUS_SDA")
	)
	(via
		(at 31.9786 21.1074)
		(size 0.4572)
		(drill 0.20574)
		(layers "F.Cu" "B.Cu")
		(net "CPLD_SMBUS_SDA")
	)
	(segment
		(start 32.64916 21.727135)
		(end 32.029425 21.1074)
		(width 0.14732)
		(layer "B.Cu")
		(net "CPLD_SMBUS_SDA")
	)
	(segment
		(start 32.64916 22.58568)
		(end 32.64916 21.727135)
		(width 0.14732)
		(layer "B.Cu")
		(net "CPLD_SMBUS_SDA")
	)
	(segment
		(start 32.79648 22.733)
		(end 32.64916 22.58568)
		(width 0.14732)
		(layer "B.Cu")
		(net "CPLD_SMBUS_SDA")
	)
	(segment
		(start 32.029425 21.1074)
		(end 31.9786 21.1074)
		(width 0.14732)
		(layer "B.Cu")
		(net "CPLD_SMBUS_SDA")
	)
	(segment
		(start 33.2359 22.733)
		(end 32.79648 22.733)
		(width 0.14732)
		(layer "B.Cu")
		(net "CPLD_SMBUS_SDA")
	)
	(segment
		(start 31.9786 22.280982)
		(end 32.246011 22.548393)
		(width 0.127)
		(layer "In1.Cu")
		(net "CPLD_SMBUS_SDA")
	)
	(segment
		(start 31.9786 21.1074)
		(end 31.9786 22.280982)
		(width 0.127)
		(layer "In1.Cu")
		(net "CPLD_SMBUS_SDA")
	)
	(segment
		(start 19.872325 17.084675)
		(end 19.872325 18.608675)
		(width 0.12065)
		(layer "In3.Cu")
		(net "CPLD_SMBUS_SDA")
	)
	(segment
		(start 31.561659 20.690459)
		(end 31.9786 21.1074)
		(width 0.12065)
		(layer "In3.Cu")
		(net "CPLD_SMBUS_SDA")
	)
	(segment
		(start 31.332322 19.903059)
		(end 31.561659 20.132396)
		(width 0.12065)
		(layer "In3.Cu")
		(net "CPLD_SMBUS_SDA")
	)
	(segment
		(start 19.177 21.844)
		(end 19.812 22.479)
		(width 0.12065)
		(layer "In3.Cu")
		(net "CPLD_SMBUS_SDA")
	)
	(segment
		(start 21.971 22.479)
		(end 22.799675 21.650325)
		(width 0.12065)
		(layer "In3.Cu")
		(net "CPLD_SMBUS_SDA")
	)
	(segment
		(start 28.448 21.59)
		(end 29.591 21.59)
		(width 0.12065)
		(layer "In3.Cu")
		(net "CPLD_SMBUS_SDA")
	)
	(segment
		(start 18.542 14.732)
		(end 20.253325 16.316325)
		(width 0.12065)
		(layer "In3.Cu")
		(net "CPLD_SMBUS_SDA")
	)
	(segment
		(start 28.194 20.955)
		(end 28.194 21.336)
		(width 0.12065)
		(layer "In3.Cu")
		(net "CPLD_SMBUS_SDA")
	)
	(segment
		(start 27.559 20.32)
		(end 28.194 20.955)
		(width 0.12065)
		(layer "In3.Cu")
		(net "CPLD_SMBUS_SDA")
	)
	(segment
		(start 28.194 21.336)
		(end 28.448 21.59)
		(width 0.12065)
		(layer "In3.Cu")
		(net "CPLD_SMBUS_SDA")
	)
	(segment
		(start 19.177 19.304)
		(end 19.177 21.844)
		(width 0.12065)
		(layer "In3.Cu")
		(net "CPLD_SMBUS_SDA")
	)
	(segment
		(start 31.561659 20.132396)
		(end 31.561659 20.690459)
		(width 0.12065)
		(layer "In3.Cu")
		(net "CPLD_SMBUS_SDA")
	)
	(segment
		(start 20.253325 16.703675)
		(end 19.872325 17.084675)
		(width 0.12065)
		(layer "In3.Cu")
		(net "CPLD_SMBUS_SDA")
	)
	(segment
		(start 29.910659 20.132396)
		(end 30.139996 19.903059)
		(width 0.12065)
		(layer "In3.Cu")
		(net "CPLD_SMBUS_SDA")
	)
	(segment
		(start 30.139996 19.903059)
		(end 31.332322 19.903059)
		(width 0.12065)
		(layer "In3.Cu")
		(net "CPLD_SMBUS_SDA")
	)
	(segment
		(start 19.812 22.479)
		(end 21.971 22.479)
		(width 0.12065)
		(layer "In3.Cu")
		(net "CPLD_SMBUS_SDA")
	)
	(segment
		(start 23.368 20.32)
		(end 27.559 20.32)
		(width 0.12065)
		(layer "In3.Cu")
		(net "CPLD_SMBUS_SDA")
	)
	(segment
		(start 29.591 21.59)
		(end 29.910659 21.270341)
		(width 0.12065)
		(layer "In3.Cu")
		(net "CPLD_SMBUS_SDA")
	)
	(segment
		(start 19.872325 18.608675)
		(end 19.177 19.304)
		(width 0.12065)
		(layer "In3.Cu")
		(net "CPLD_SMBUS_SDA")
	)
	(segment
		(start 22.799675 20.888325)
		(end 23.368 20.32)
		(width 0.12065)
		(layer "In3.Cu")
		(net "CPLD_SMBUS_SDA")
	)
	(segment
		(start 29.910659 21.270341)
		(end 29.910659 20.132396)
		(width 0.12065)
		(layer "In3.Cu")
		(net "CPLD_SMBUS_SDA")
	)
	(segment
		(start 22.799675 21.650325)
		(end 22.799675 20.888325)
		(width 0.12065)
		(layer "In3.Cu")
		(net "CPLD_SMBUS_SDA")
	)
	(segment
		(start 20.253325 16.316325)
		(end 20.253325 16.703675)
		(width 0.12065)
		(layer "In3.Cu")
		(net "CPLD_SMBUS_SDA")
	)
	(segment
		(start 15.621 0.381)
		(end 15.494 0.254)
		(width 0.14732)
		(layer "F.Cu")
		(net "CPLD_SMBUS_SCL")
	)
	(segment
		(start 31.9532 20.2946)
		(end 31.944742 20.548524)
		(width 0.127)
		(layer "F.Cu")
		(net "CPLD_SMBUS_SCL")
	)
	(segment
		(start 31.5595 21.861882)
		(end 31.746012 22.048394)
		(width 0.127)
		(layer "F.Cu")
		(net "CPLD_SMBUS_SCL")
	)
	(segment
		(start 31.944742 20.548524)
		(end 31.5595 20.933766)
		(width 0.127)
		(layer "F.Cu")
		(net "CPLD_SMBUS_SCL")
	)
	(segment
		(start 31.5595 20.933766)
		(end 31.5595 21.861882)
		(width 0.127)
		(layer "F.Cu")
		(net "CPLD_SMBUS_SCL")
	)
	(segment
		(start 15.621 0.9779)
		(end 15.621 0.381)
		(width 0.14732)
		(layer "F.Cu")
		(net "CPLD_SMBUS_SCL")
	)
	(via
		(at 31.9532 20.2946)
		(size 0.4572)
		(drill 0.20574)
		(layers "F.Cu" "B.Cu")
		(net "CPLD_SMBUS_SCL")
	)
	(via
		(at 15.494 0.254)
		(size 0.508)
		(drill 0.254)
		(layers "F.Cu" "B.Cu")
		(net "CPLD_SMBUS_SCL")
	)
	(via
		(at 21.971 10.795)
		(size 0.762)
		(drill 0.381)
		(layers "F.Cu" "B.Cu")
		(net "CPLD_SMBUS_SCL")
	)
	(via
		(at 20.543215 11.303)
		(size 0.508)
		(drill 0.254)
		(layers "F.Cu" "B.Cu")
		(net "CPLD_SMBUS_SCL")
	)
	(segment
		(start 20.543215 11.303)
		(end 21.463 11.303)
		(width 0.14732)
		(layer "B.Cu")
		(net "CPLD_SMBUS_SCL")
	)
	(segment
		(start 20.32 2.2479)
		(end 20.066 2.159)
		(width 0.14732)
		(layer "B.Cu")
		(net "CPLD_SMBUS_SCL")
	)
	(segment
		(start 19.177 1.27)
		(end 16.51 1.27)
		(width 0.14732)
		(layer "B.Cu")
		(net "CPLD_SMBUS_SCL")
	)
	(segment
		(start 20.066 2.159)
		(end 19.177 1.27)
		(width 0.14732)
		(layer "B.Cu")
		(net "CPLD_SMBUS_SCL")
	)
	(segment
		(start 16.51 1.27)
		(end 15.494 0.254)
		(width 0.14732)
		(layer "B.Cu")
		(net "CPLD_SMBUS_SCL")
	)
	(segment
		(start 21.463 11.303)
		(end 21.971 10.795)
		(width 0.14732)
		(layer "B.Cu")
		(net "CPLD_SMBUS_SCL")
	)
	(segment
		(start 31.9532 19.8882)
		(end 31.623 19.558)
		(width 0.12065)
		(layer "In3.Cu")
		(net "CPLD_SMBUS_SCL")
	)
	(segment
		(start 20.918018 17.09867)
		(end 20.918018 16.68333)
		(width 0.12065)
		(layer "In3.Cu")
		(net "CPLD_SMBUS_SCL")
	)
	(segment
		(start 20.543215 15.39654)
		(end 20.543215 11.303)
		(width 0.12065)
		(layer "In3.Cu")
		(net "CPLD_SMBUS_SCL")
	)
	(segment
		(start 20.193 21.46935)
		(end 20.193 21.082)
		(width 0.12065)
		(layer "In3.Cu")
		(net "CPLD_SMBUS_SCL")
	)
	(segment
		(start 20.918018 16.68333)
		(end 20.894675 16.659987)
		(width 0.12065)
		(layer "In3.Cu")
		(net "CPLD_SMBUS_SCL")
	)
	(segment
		(start 20.894675 15.748)
		(end 20.543215 15.39654)
		(width 0.12065)
		(layer "In3.Cu")
		(net "CPLD_SMBUS_SCL")
	)
	(segment
		(start 31.9532 20.2946)
		(end 31.9532 19.8882)
		(width 0.12065)
		(layer "In3.Cu")
		(net "CPLD_SMBUS_SCL")
	)
	(segment
		(start 20.894675 20.380325)
		(end 20.894675 17.122013)
		(width 0.12065)
		(layer "In3.Cu")
		(net "CPLD_SMBUS_SCL")
	)
	(segment
		(start 21.336 21.325154)
		(end 20.883829 21.777325)
		(width 0.12065)
		(layer "In3.Cu")
		(net "CPLD_SMBUS_SCL")
	)
	(segment
		(start 31.623 19.558)
		(end 22.987 19.558)
		(width 0.12065)
		(layer "In3.Cu")
		(net "CPLD_SMBUS_SCL")
	)
	(segment
		(start 20.894675 17.122013)
		(end 20.918018 17.09867)
		(width 0.12065)
		(layer "In3.Cu")
		(net "CPLD_SMBUS_SCL")
	)
	(segment
		(start 20.894675 16.659987)
		(end 20.894675 15.748)
		(width 0.12065)
		(layer "In3.Cu")
		(net "CPLD_SMBUS_SCL")
	)
	(segment
		(start 20.500975 21.777325)
		(end 20.193 21.46935)
		(width 0.12065)
		(layer "In3.Cu")
		(net "CPLD_SMBUS_SCL")
	)
	(segment
		(start 22.987 19.558)
		(end 21.336 21.209)
		(width 0.12065)
		(layer "In3.Cu")
		(net "CPLD_SMBUS_SCL")
	)
	(segment
		(start 20.883829 21.777325)
		(end 20.500975 21.777325)
		(width 0.12065)
		(layer "In3.Cu")
		(net "CPLD_SMBUS_SCL")
	)
	(segment
		(start 20.193 21.082)
		(end 20.894675 20.380325)
		(width 0.12065)
		(layer "In3.Cu")
		(net "CPLD_SMBUS_SCL")
	)
	(segment
		(start 21.336 21.209)
		(end 21.336 21.325154)
		(width 0.12065)
		(layer "In3.Cu")
		(net "CPLD_SMBUS_SCL")
	)
	(segment
		(start 15.494 0.254)
		(end 15.494 2.159)
		(width 0.12065)
		(layer "In6.Cu")
		(net "CPLD_SMBUS_SCL")
	)
	(segment
		(start 20.035215 10.795)
		(end 20.543215 11.303)
		(width 0.12065)
		(layer "In6.Cu")
		(net "CPLD_SMBUS_SCL")
	)
	(segment
		(start 15.494 2.159)
		(end 16.002 2.667)
		(width 0.12065)
		(layer "In6.Cu")
		(net "CPLD_SMBUS_SCL")
	)
	(segment
		(start 16.002 2.667)
		(end 16.002 8.636)
		(width 0.12065)
		(layer "In6.Cu")
		(net "CPLD_SMBUS_SCL")
	)
	(segment
		(start 17.103725 9.610725)
		(end 18.288 10.795)
		(width 0.12065)
		(layer "In6.Cu")
		(net "CPLD_SMBUS_SCL")
	)
	(segment
		(start 16.002 8.636)
		(end 16.411575 9.045575)
		(width 0.12065)
		(layer "In6.Cu")
		(net "CPLD_SMBUS_SCL")
	)
	(segment
		(start 16.845229 9.045575)
		(end 17.103725 9.304071)
		(width 0.12065)
		(layer "In6.Cu")
		(net "CPLD_SMBUS_SCL")
	)
	(segment
		(start 18.288 10.795)
		(end 20.035215 10.795)
		(width 0.12065)
		(layer "In6.Cu")
		(net "CPLD_SMBUS_SCL")
	)
	(segment
		(start 17.103725 9.304071)
		(end 17.103725 9.610725)
		(width 0.12065)
		(layer "In6.Cu")
		(net "CPLD_SMBUS_SCL")
	)
	(segment
		(start 16.411575 9.045575)
		(end 16.845229 9.045575)
		(width 0.12065)
		(layer "In6.Cu")
		(net "CPLD_SMBUS_SCL")
	)
	(via
		(at 2.921 20.32)
		(size 0.762)
		(drill 0.381)
		(layers "F.Cu" "B.Cu")
		(net "13N4351")
	)
	(segment
		(start 4.2418 13.966012)
		(end 4.2418 15.0368)
		(width 0.254)
		(layer "B.Cu")
		(net "13N4351")
	)
	(segment
		(start 3.429 19.812)
		(end 3.429 18.796)
		(width 0.14732)
		(layer "B.Cu")
		(net "13N4351")
	)
	(segment
		(start 4.572 15.367)
		(end 4.572 17.0307)
		(width 0.254)
		(layer "B.Cu")
		(net "13N4351")
	)
	(segment
		(start 2.921 20.32)
		(end 3.429 19.812)
		(width 0.14732)
		(layer "B.Cu")
		(net "13N4351")
	)
	(segment
		(start 5.139512 13.966012)
		(end 5.334 14.1605)
		(width 0.254)
		(layer "B.Cu")
		(net "13N4351")
	)
	(segment
		(start 3.175 18.542)
		(end 3.175 17.399)
		(width 0.14732)
		(layer "B.Cu")
		(net "13N4351")
	)
	(segment
		(start 3.5433 17.0307)
		(end 3.683 17.0307)
		(width 0.14732)
		(layer "B.Cu")
		(net "13N4351")
	)
	(segment
		(start 4.822012 13.966012)
		(end 5.139512 13.966012)
		(width 0.254)
		(layer "B.Cu")
		(net "13N4351")
	)
	(segment
		(start 3.175 17.399)
		(end 3.5433 17.0307)
		(width 0.14732)
		(layer "B.Cu")
		(net "13N4351")
	)
	(segment
		(start 4.2418 15.0368)
		(end 4.572 15.367)
		(width 0.254)
		(layer "B.Cu")
		(net "13N4351")
	)
	(segment
		(start 3.429 18.796)
		(end 3.175 18.542)
		(width 0.14732)
		(layer "B.Cu")
		(net "13N4351")
	)
	(segment
		(start 3.683 17.0307)
		(end 4.572 17.0307)
		(width 0.254)
		(layer "B.Cu")
		(net "13N4351")
	)
	(segment
		(start 4.2418 13.966012)
		(end 4.822012 13.966012)
		(width 0.254)
		(layer "B.Cu")
		(net "13N4351")
	)
	(via
		(at -0.254 8.382)
		(size 0.762)
		(drill 0.381)
		(layers "F.Cu" "B.Cu")
		(net "13N4347")
	)
	(segment
		(start 4.055618 10.668)
		(end 3.302 10.668)
		(width 0.14732)
		(layer "B.Cu")
		(net "13N4347")
	)
	(segment
		(start 3.79001 12.21199)
		(end 4.191 11.811)
		(width 0.14732)
		(layer "B.Cu")
		(net "13N4347")
	)
	(segment
		(start 4.445 11.557)
		(end 4.445 11.057382)
		(width 0.14732)
		(layer "B.Cu")
		(net "13N4347")
	)
	(segment
		(start 4.25196 10.838866)
		(end 4.134434 10.72134)
		(width 0.14732)
		(layer "B.Cu")
		(net "13N4347")
	)
	(segment
		(start 4.25196 10.847934)
		(end 4.25196 10.838866)
		(width 0.14732)
		(layer "B.Cu")
		(net "13N4347")
	)
	(segment
		(start 4.39166 10.987634)
		(end 4.25196 10.847934)
		(width 0.14732)
		(layer "B.Cu")
		(net "13N4347")
	)
	(segment
		(start 4.134434 10.72134)
		(end 4.108958 10.72134)
		(width 0.14732)
		(layer "B.Cu")
		(net "13N4347")
	)
	(segment
		(start 4.108958 10.72134)
		(end 4.055618 10.668)
		(width 0.14732)
		(layer "B.Cu")
		(net "13N4347")
	)
	(segment
		(start 3.1369 9.736506)
		(end 3.1369 10.16)
		(width 0.14732)
		(layer "B.Cu")
		(net "13N4347")
	)
	(segment
		(start 0.32766 8.96366)
		(end 2.364054 8.96366)
		(width 0.14732)
		(layer "B.Cu")
		(net "13N4347")
	)
	(segment
		(start 3.79001 12.5222)
		(end 3.79001 12.21199)
		(width 0.14732)
		(layer "B.Cu")
		(net "13N4347")
	)
	(segment
		(start 3.1369 10.5029)
		(end 3.1369 10.16)
		(width 0.14732)
		(layer "B.Cu")
		(net "13N4347")
	)
	(segment
		(start 4.39166 11.004042)
		(end 4.39166 10.987634)
		(width 0.14732)
		(layer "B.Cu")
		(net "13N4347")
	)
	(segment
		(start -0.254 8.382)
		(end 0.32766 8.96366)
		(width 0.14732)
		(layer "B.Cu")
		(net "13N4347")
	)
	(segment
		(start 4.445 11.057382)
		(end 4.39166 11.004042)
		(width 0.14732)
		(layer "B.Cu")
		(net "13N4347")
	)
	(segment
		(start 2.364054 8.96366)
		(end 3.1369 9.736506)
		(width 0.14732)
		(layer "B.Cu")
		(net "13N4347")
	)
	(segment
		(start 4.191 11.811)
		(end 4.445 11.557)
		(width 0.14732)
		(layer "B.Cu")
		(net "13N4347")
	)
	(segment
		(start 3.302 10.668)
		(end 3.1369 10.5029)
		(width 0.14732)
		(layer "B.Cu")
		(net "13N4347")
	)
	(segment
		(start 20.069988 4.187012)
		(end 19.939 4.318)
		(width 0.254)
		(layer "F.Cu")
		(net "13N4321")
	)
	(segment
		(start 20.6502 4.187012)
		(end 20.069988 4.187012)
		(width 0.254)
		(layer "F.Cu")
		(net "13N4321")
	)
	(segment
		(start 19.6723 6.1087)
		(end 19.685 6.1087)
		(width 0.14732)
		(layer "F.Cu")
		(net "13N4321")
	)
	(segment
		(start 18.97634 7.82066)
		(end 18.97634 6.80466)
		(width 0.14732)
		(layer "F.Cu")
		(net "13N4321")
	)
	(segment
		(start 19.939 4.318)
		(end 19.5961 4.318)
		(width 0.254)
		(layer "F.Cu")
		(net "13N4321")
	)
	(segment
		(start 19.5961 4.318)
		(end 19.5961 5.08)
		(width 0.254)
		(layer "F.Cu")
		(net "13N4321")
	)
	(segment
		(start 19.685 6.1087)
		(end 19.685 5.2451)
		(width 0.254)
		(layer "F.Cu")
		(net "13N4321")
	)
	(segment
		(start 18.97634 6.80466)
		(end 19.6723 6.1087)
		(width 0.14732)
		(layer "F.Cu")
		(net "13N4321")
	)
	(segment
		(start 19.5961 5.08)
		(end 19.7231 5.207)
		(width 0.254)
		(layer "F.Cu")
		(net "13N4321")
	)
	(segment
		(start 18.669 8.128)
		(end 18.97634 7.82066)
		(width 0.14732)
		(layer "F.Cu")
		(net "13N4321")
	)
	(segment
		(start 19.685 5.2451)
		(end 19.7231 5.207)
		(width 0.254)
		(layer "F.Cu")
		(net "13N4321")
	)
	(via
		(at 18.669 8.128)
		(size 0.762)
		(drill 0.381)
		(layers "F.Cu" "B.Cu")
		(net "13N4321")
	)
	(segment
		(start 21.10199 2.43299)
		(end 20.701 2.032)
		(width 0.14732)
		(layer "F.Cu")
		(net "13N4315")
	)
	(segment
		(start 19.7231 1.397)
		(end 19.7231 0.2921)
		(width 0.14732)
		(layer "F.Cu")
		(net "13N4315")
	)
	(segment
		(start 20.701 2.032)
		(end 20.3581 2.032)
		(width 0.14732)
		(layer "F.Cu")
		(net "13N4315")
	)
	(segment
		(start 21.10199 2.7432)
		(end 21.10199 2.43299)
		(width 0.14732)
		(layer "F.Cu")
		(net "13N4315")
	)
	(segment
		(start 20.3581 2.032)
		(end 19.7231 1.397)
		(width 0.14732)
		(layer "F.Cu")
		(net "13N4315")
	)
	(via
		(at 19.7231 0.2921)
		(size 0.762)
		(drill 0.381)
		(layers "F.Cu" "B.Cu")
		(net "13N4315")
	)
	(segment
		(start 10.922 3.7973)
		(end 11.5824 3.1369)
		(width 0.14732)
		(layer "F.Cu")
		(net "SMBUS_ALERT_L")
	)
	(segment
		(start 17.78 4.191025)
		(end 17.78 3.95732)
		(width 0.14732)
		(layer "F.Cu")
		(net "SMBUS_ALERT_L")
	)
	(segment
		(start 18.41754 6.05536)
		(end 18.41754 4.828565)
		(width 0.14732)
		(layer "F.Cu")
		(net "SMBUS_ALERT_L")
	)
	(segment
		(start 13.29182 4.94792)
		(end 11.17092 4.94792)
		(width 0.14732)
		(layer "F.Cu")
		(net "SMBUS_ALERT_L")
	)
	(segment
		(start 18.415 6.1849)
		(end 18.01876 6.1849)
		(width 0.14732)
		(layer "F.Cu")
		(net "SMBUS_ALERT_L")
	)
	(segment
		(start 17.78 3.95732)
		(end 17.63268 3.81)
		(width 0.14732)
		(layer "F.Cu")
		(net "SMBUS_ALERT_L")
	)
	(segment
		(start 18.01876 6.1849)
		(end 17.85366 6.35)
		(width 0.14732)
		(layer "F.Cu")
		(net "SMBUS_ALERT_L")
	)
	(segment
		(start 18.41754 4.828565)
		(end 17.78 4.191025)
		(width 0.14732)
		(layer "F.Cu")
		(net "SMBUS_ALERT_L")
	)
	(segment
		(start 13.462 4.77774)
		(end 13.29182 4.94792)
		(width 0.14732)
		(layer "F.Cu")
		(net "SMBUS_ALERT_L")
	)
	(segment
		(start 10.922 4.699)
		(end 10.922 3.7973)
		(width 0.14732)
		(layer "F.Cu")
		(net "SMBUS_ALERT_L")
	)
	(segment
		(start 17.85366 6.94944)
		(end 17.399 7.4041)
		(width 0.14732)
		(layer "F.Cu")
		(net "SMBUS_ALERT_L")
	)
	(segment
		(start 13.462 4.064025)
		(end 13.462 4.77774)
		(width 0.14732)
		(layer "F.Cu")
		(net "SMBUS_ALERT_L")
	)
	(segment
		(start 13.716025 3.81)
		(end 13.462 4.064025)
		(width 0.14732)
		(layer "F.Cu")
		(net "SMBUS_ALERT_L")
	)
	(segment
		(start 11.17092 4.94792)
		(end 10.922 4.699)
		(width 0.14732)
		(layer "F.Cu")
		(net "SMBUS_ALERT_L")
	)
	(segment
		(start 17.63268 3.81)
		(end 13.716025 3.81)
		(width 0.14732)
		(layer "F.Cu")
		(net "SMBUS_ALERT_L")
	)
	(segment
		(start 17.85366 6.35)
		(end 17.85366 6.94944)
		(width 0.14732)
		(layer "F.Cu")
		(net "SMBUS_ALERT_L")
	)
	(segment
		(start 18.415 6.1849)
		(end 18.41754 6.05536)
		(width 0.14732)
		(layer "F.Cu")
		(net "SMBUS_ALERT_L")
	)
	(via
		(at 11.5824 3.1369)
		(size 0.508)
		(drill 0.254)
		(layers "F.Cu" "B.Cu")
		(net "SMBUS_ALERT_L")
	)
	(via
		(at 17.63268 3.81)
		(size 0.762)
		(drill 0.381)
		(layers "F.Cu" "B.Cu")
		(net "SMBUS_ALERT_L")
	)
	(segment
		(start 10.9474 3.7719)
		(end 11.5824 3.1369)
		(width 0.254)
		(layer "B.Cu")
		(net "SMBUS_ALERT_L")
	)
	(segment
		(start 22.098 1.397)
		(end 22.602012 1.901012)
		(width 0.14732)
		(layer "F.Cu")
		(net "NFP_PCIE0_WAKE_L")
	)
	(segment
		(start 22.602012 1.901012)
		(end 22.602012 2.7432)
		(width 0.14732)
		(layer "F.Cu")
		(net "NFP_PCIE0_WAKE_L")
	)
	(segment
		(start 11.303 0.9779)
		(end 11.303 0.254)
		(width 0.14732)
		(layer "F.Cu")
		(net "NFP_PCIE0_WAKE_L")
	)
	(via
		(at 22.098 1.397)
		(size 0.508)
		(drill 0.25654)
		(layers "F.Cu" "B.Cu")
		(net "NFP_PCIE0_WAKE_L")
	)
	(via
		(at 11.303 0.254)
		(size 0.508)
		(drill 0.254)
		(layers "F.Cu" "B.Cu")
		(net "NFP_PCIE0_WAKE_L")
	)
	(segment
		(start 22.098 1.397)
		(end 22.098 2.1209)
		(width 0.14732)
		(layer "B.Cu")
		(net "NFP_PCIE0_WAKE_L")
	)
	(segment
		(start 22.098 2.1209)
		(end 22.352 2.3749)
		(width 0.14732)
		(layer "B.Cu")
		(net "NFP_PCIE0_WAKE_L")
	)
	(segment
		(start 15.28605 -0.24765)
		(end 14.99235 0.04605)
		(width 0.12065)
		(layer "In6.Cu")
		(net "NFP_PCIE0_WAKE_L")
	)
	(segment
		(start 22.098 1.397)
		(end 20.513675 -0.187325)
		(width 0.12065)
		(layer "In6.Cu")
		(net "NFP_PCIE0_WAKE_L")
	)
	(segment
		(start 14.5526 0.762)
		(end 14.097 0.762)
		(width 0.12065)
		(layer "In6.Cu")
		(net "NFP_PCIE0_WAKE_L")
	)
	(segment
		(start 14.097 0.762)
		(end 13.589 0.254)
		(width 0.12065)
		(layer "In6.Cu")
		(net "NFP_PCIE0_WAKE_L")
	)
	(segment
		(start 15.694025 -0.187325)
		(end 15.6337 -0.24765)
		(width 0.12065)
		(layer "In6.Cu")
		(net "NFP_PCIE0_WAKE_L")
	)
	(segment
		(start 15.6337 -0.24765)
		(end 15.28605 -0.24765)
		(width 0.12065)
		(layer "In6.Cu")
		(net "NFP_PCIE0_WAKE_L")
	)
	(segment
		(start 14.99235 0.04605)
		(end 14.99235 0.32225)
		(width 0.12065)
		(layer "In6.Cu")
		(net "NFP_PCIE0_WAKE_L")
	)
	(segment
		(start 14.99235 0.32225)
		(end 14.5526 0.762)
		(width 0.12065)
		(layer "In6.Cu")
		(net "NFP_PCIE0_WAKE_L")
	)
	(segment
		(start 20.513675 -0.187325)
		(end 15.694025 -0.187325)
		(width 0.12065)
		(layer "In6.Cu")
		(net "NFP_PCIE0_WAKE_L")
	)
	(segment
		(start 13.589 0.254)
		(end 11.303 0.254)
		(width 0.12065)
		(layer "In6.Cu")
		(net "NFP_PCIE0_WAKE_L")
	)
	(segment
		(start 7.366 5.207)
		(end 6.59384 4.43484)
		(width 0.14732)
		(layer "F.Cu")
		(net "CPLD_SMBUS_ALERT_L")
	)
	(segment
		(start 14.36337 5.09524)
		(end 13.88143 5.09524)
		(width 0.14732)
		(layer "F.Cu")
		(net "CPLD_SMBUS_ALERT_L")
	)
	(segment
		(start 6.59384 4.43484)
		(end 6.59384 3.5306)
		(width 0.14732)
		(layer "F.Cu")
		(net "CPLD_SMBUS_ALERT_L")
	)
	(segment
		(start 11.04204 5.207)
		(end 7.366 5.207)
		(width 0.14732)
		(layer "F.Cu")
		(net "CPLD_SMBUS_ALERT_L")
	)
	(segment
		(start 17.63776 5.85724)
		(end 17.63776 5.09524)
		(width 0.14732)
		(layer "F.Cu")
		(net "CPLD_SMBUS_ALERT_L")
	)
	(segment
		(start 11.05728 5.22224)
		(end 11.04204 5.207)
		(width 0.14732)
		(layer "F.Cu")
		(net "CPLD_SMBUS_ALERT_L")
	)
	(segment
		(start 16.42143 5.09524)
		(end 16.30967 5.207)
		(width 0.14732)
		(layer "F.Cu")
		(net "CPLD_SMBUS_ALERT_L")
	)
	(segment
		(start 4.5339 3.0099)
		(end 4.5339 2.413)
		(width 0.14732)
		(layer "F.Cu")
		(net "CPLD_SMBUS_ALERT_L")
	)
	(segment
		(start 6.59384 3.5306)
		(end 6.35 3.28676)
		(width 0.14732)
		(layer "F.Cu")
		(net "CPLD_SMBUS_ALERT_L")
	)
	(segment
		(start 13.88143 5.09524)
		(end 13.75443 5.22224)
		(width 0.14732)
		(layer "F.Cu")
		(net "CPLD_SMBUS_ALERT_L")
	)
	(segment
		(start 17.653 5.08)
		(end 17.63776 5.09524)
		(width 0.14732)
		(layer "F.Cu")
		(net "CPLD_SMBUS_ALERT_L")
	)
	(segment
		(start 17.399 6.096)
		(end 17.63776 5.85724)
		(width 0.14732)
		(layer "F.Cu")
		(net "CPLD_SMBUS_ALERT_L")
	)
	(segment
		(start 13.75443 5.22224)
		(end 11.05728 5.22224)
		(width 0.14732)
		(layer "F.Cu")
		(net "CPLD_SMBUS_ALERT_L")
	)
	(segment
		(start 16.30967 5.207)
		(end 14.47513 5.207)
		(width 0.14732)
		(layer "F.Cu")
		(net "CPLD_SMBUS_ALERT_L")
	)
	(segment
		(start 17.399 6.5659)
		(end 17.399 6.096)
		(width 0.14732)
		(layer "F.Cu")
		(net "CPLD_SMBUS_ALERT_L")
	)
	(segment
		(start 4.81076 3.28676)
		(end 4.5339 3.0099)
		(width 0.14732)
		(layer "F.Cu")
		(net "CPLD_SMBUS_ALERT_L")
	)
	(segment
		(start 6.35 3.28676)
		(end 4.81076 3.28676)
		(width 0.14732)
		(layer "F.Cu")
		(net "CPLD_SMBUS_ALERT_L")
	)
	(segment
		(start 17.63776 5.09524)
		(end 16.42143 5.09524)
		(width 0.14732)
		(layer "F.Cu")
		(net "CPLD_SMBUS_ALERT_L")
	)
	(segment
		(start 14.47513 5.207)
		(end 14.36337 5.09524)
		(width 0.14732)
		(layer "F.Cu")
		(net "CPLD_SMBUS_ALERT_L")
	)
	(via
		(at 26.924 23.495)
		(size 0.4572)
		(drill 0.20574)
		(layers "F.Cu" "B.Cu")
		(net "CPLD_SMBUS_ALERT_L")
	)
	(via
		(at 17.653 5.08)
		(size 0.762)
		(drill 0.381)
		(layers "F.Cu" "B.Cu")
		(net "CPLD_SMBUS_ALERT_L")
	)
	(via
		(at 4.5339 2.413)
		(size 0.508)
		(drill 0.254)
		(layers "F.Cu" "B.Cu")
		(net "CPLD_SMBUS_ALERT_L")
	)
	(segment
		(start 27.980818 23.835208)
		(end 28.194 24.04839)
		(width 0.127)
		(layer "In1.Cu")
		(net "CPLD_SMBUS_ALERT_L")
	)
	(segment
		(start 27.264208 23.835208)
		(end 27.980818 23.835208)
		(width 0.127)
		(layer "In1.Cu")
		(net "CPLD_SMBUS_ALERT_L")
	)
	(segment
		(start 28.194 24.04839)
		(end 28.745993 24.04839)
		(width 0.127)
		(layer "In1.Cu")
		(net "CPLD_SMBUS_ALERT_L")
	)
	(segment
		(start 26.924 23.495)
		(end 27.264208 23.835208)
		(width 0.127)
		(layer "In1.Cu")
		(net "CPLD_SMBUS_ALERT_L")
	)
	(segment
		(start 14.859 26.444575)
		(end 14.478 26.825575)
		(width 0.12065)
		(layer "In7.Cu")
		(net "CPLD_SMBUS_ALERT_L")
	)
	(segment
		(start 6.603924 23.240924)
		(end 6.603924 21.843924)
		(width 0.12065)
		(layer "In7.Cu")
		(net "CPLD_SMBUS_ALERT_L")
	)
	(segment
		(start 5.842 12.065)
		(end 5.08 11.303)
		(width 0.12065)
		(layer "In7.Cu")
		(net "CPLD_SMBUS_ALERT_L")
	)
	(segment
		(start 17.145 23.241)
		(end 16.891 22.987)
		(width 0.12065)
		(layer "In7.Cu")
		(net "CPLD_SMBUS_ALERT_L")
	)
	(segment
		(start 15.748 24.257)
		(end 15.113 24.257)
		(width 0.12065)
		(layer "In7.Cu")
		(net "CPLD_SMBUS_ALERT_L")
	)
	(segment
		(start 26.477341 23.941659)
		(end 25.338659 23.941659)
		(width 0.12065)
		(layer "In7.Cu")
		(net "CPLD_SMBUS_ALERT_L")
	)
	(segment
		(start 7.261225 23.898225)
		(end 6.603924 23.240924)
		(width 0.12065)
		(layer "In7.Cu")
		(net "CPLD_SMBUS_ALERT_L")
	)
	(segment
		(start 21.59 24.892)
		(end 19.928154 24.892)
		(width 0.12065)
		(layer "In7.Cu")
		(net "CPLD_SMBUS_ALERT_L")
	)
	(segment
		(start 19.928154 24.892)
		(end 19.740829 25.079325)
		(width 0.12065)
		(layer "In7.Cu")
		(net "CPLD_SMBUS_ALERT_L")
	)
	(segment
		(start 16.891 22.987)
		(end 16.508146 22.987)
		(width 0.12065)
		(layer "In7.Cu")
		(net "CPLD_SMBUS_ALERT_L")
	)
	(segment
		(start 8.382 23.876)
		(end 7.977454 23.876)
		(width 0.12065)
		(layer "In7.Cu")
		(net "CPLD_SMBUS_ALERT_L")
	)
	(segment
		(start 16.508146 22.987)
		(end 16.221075 23.274071)
		(width 0.12065)
		(layer "In7.Cu")
		(net "CPLD_SMBUS_ALERT_L")
	)
	(segment
		(start 7.955229 23.898225)
		(end 7.261225 23.898225)
		(width 0.12065)
		(layer "In7.Cu")
		(net "CPLD_SMBUS_ALERT_L")
	)
	(segment
		(start 15.113 24.257)
		(end 14.859 24.511)
		(width 0.12065)
		(layer "In7.Cu")
		(net "CPLD_SMBUS_ALERT_L")
	)
	(segment
		(start 6.603924 21.843924)
		(end 5.842 21.082)
		(width 0.12065)
		(layer "In7.Cu")
		(net "CPLD_SMBUS_ALERT_L")
	)
	(segment
		(start 5.08 2.921)
		(end 4.572 2.413)
		(width 0.12065)
		(layer "In7.Cu")
		(net "CPLD_SMBUS_ALERT_L")
	)
	(segment
		(start 16.221075 23.783925)
		(end 15.748 24.257)
		(width 0.12065)
		(layer "In7.Cu")
		(net "CPLD_SMBUS_ALERT_L")
	)
	(segment
		(start 17.78 24.892)
		(end 17.145 24.257)
		(width 0.12065)
		(layer "In7.Cu")
		(net "CPLD_SMBUS_ALERT_L")
	)
	(segment
		(start 9.525 24.585346)
		(end 9.225229 24.285575)
		(width 0.12065)
		(layer "In7.Cu")
		(net "CPLD_SMBUS_ALERT_L")
	)
	(segment
		(start 5.842 21.082)
		(end 5.842 12.065)
		(width 0.12065)
		(layer "In7.Cu")
		(net "CPLD_SMBUS_ALERT_L")
	)
	(segment
		(start 8.791575 24.285575)
		(end 8.382 23.876)
		(width 0.12065)
		(layer "In7.Cu")
		(net "CPLD_SMBUS_ALERT_L")
	)
	(segment
		(start 4.572 2.413)
		(end 4.5339 2.413)
		(width 0.12065)
		(layer "In7.Cu")
		(net "CPLD_SMBUS_ALERT_L")
	)
	(segment
		(start 25.338659 23.941659)
		(end 24.384 22.987)
		(width 0.12065)
		(layer "In7.Cu")
		(net "CPLD_SMBUS_ALERT_L")
	)
	(segment
		(start 9.225229 24.285575)
		(end 8.791575 24.285575)
		(width 0.12065)
		(layer "In7.Cu")
		(net "CPLD_SMBUS_ALERT_L")
	)
	(segment
		(start 5.08 11.303)
		(end 5.08 2.921)
		(width 0.12065)
		(layer "In7.Cu")
		(net "CPLD_SMBUS_ALERT_L")
	)
	(segment
		(start 26.924 23.495)
		(end 26.477341 23.941659)
		(width 0.12065)
		(layer "In7.Cu")
		(net "CPLD_SMBUS_ALERT_L")
	)
	(segment
		(start 23.495 22.987)
		(end 21.59 24.892)
		(width 0.12065)
		(layer "In7.Cu")
		(net "CPLD_SMBUS_ALERT_L")
	)
	(segment
		(start 19.187846 24.892)
		(end 17.78 24.892)
		(width 0.12065)
		(layer "In7.Cu")
		(net "CPLD_SMBUS_ALERT_L")
	)
	(segment
		(start 19.375171 25.079325)
		(end 19.187846 24.892)
		(width 0.12065)
		(layer "In7.Cu")
		(net "CPLD_SMBUS_ALERT_L")
	)
	(segment
		(start 14.859 24.511)
		(end 14.859 26.444575)
		(width 0.12065)
		(layer "In7.Cu")
		(net "CPLD_SMBUS_ALERT_L")
	)
	(segment
		(start 14.478 26.825575)
		(end 9.807575 26.825575)
		(width 0.12065)
		(layer "In7.Cu")
		(net "CPLD_SMBUS_ALERT_L")
	)
	(segment
		(start 9.807575 26.825575)
		(end 9.525 26.543)
		(width 0.12065)
		(layer "In7.Cu")
		(net "CPLD_SMBUS_ALERT_L")
	)
	(segment
		(start 16.221075 23.274071)
		(end 16.221075 23.783925)
		(width 0.12065)
		(layer "In7.Cu")
		(net "CPLD_SMBUS_ALERT_L")
	)
	(segment
		(start 24.384 22.987)
		(end 23.495 22.987)
		(width 0.12065)
		(layer "In7.Cu")
		(net "CPLD_SMBUS_ALERT_L")
	)
	(segment
		(start 9.525 26.543)
		(end 9.525 24.585346)
		(width 0.12065)
		(layer "In7.Cu")
		(net "CPLD_SMBUS_ALERT_L")
	)
	(segment
		(start 19.740829 25.079325)
		(end 19.375171 25.079325)
		(width 0.12065)
		(layer "In7.Cu")
		(net "CPLD_SMBUS_ALERT_L")
	)
	(segment
		(start 7.977454 23.876)
		(end 7.955229 23.898225)
		(width 0.12065)
		(layer "In7.Cu")
		(net "CPLD_SMBUS_ALERT_L")
	)
	(segment
		(start 17.145 24.257)
		(end 17.145 23.241)
		(width 0.12065)
		(layer "In7.Cu")
		(net "CPLD_SMBUS_ALERT_L")
	)
	(segment
		(start 33.655 21.221167)
		(end 33.246009 21.630157)
		(width 0.127)
		(layer "F.Cu")
		(net "CPLD_PCIE0_WAKE_L")
	)
	(segment
		(start 33.246009 21.630157)
		(end 33.246009 22.048394)
		(width 0.127)
		(layer "F.Cu")
		(net "CPLD_PCIE0_WAKE_L")
	)
	(segment
		(start 33.655 21.1074)
		(end 33.655 21.221167)
		(width 0.127)
		(layer "F.Cu")
		(net "CPLD_PCIE0_WAKE_L")
	)
	(segment
		(start 10.16 0.9779)
		(end 10.16 0.254)
		(width 0.14732)
		(layer "F.Cu")
		(net "CPLD_PCIE0_WAKE_L")
	)
	(via
		(at 18.542 13.462)
		(size 0.762)
		(drill 0.2667)
		(layers "F.Cu" "B.Cu")
		(net "CPLD_PCIE0_WAKE_L")
	)
	(via
		(at 10.16 0.254)
		(size 0.508)
		(drill 0.254)
		(layers "F.Cu" "B.Cu")
		(net "CPLD_PCIE0_WAKE_L")
	)
	(via
		(at 19.685 23.241)
		(size 0.508)
		(drill 0.254)
		(layers "F.Cu" "B.Cu")
		(net "CPLD_PCIE0_WAKE_L")
	)
	(via
		(at 33.655 21.1074)
		(size 0.4572)
		(drill 0.20574)
		(layers "F.Cu" "B.Cu")
		(net "CPLD_PCIE0_WAKE_L")
	)
	(segment
		(start 33.5026 21.1074)
		(end 33.655 21.1074)
		(width 0.14732)
		(layer "B.Cu")
		(net "CPLD_PCIE0_WAKE_L")
	)
	(segment
		(start 33.2359 21.3741)
		(end 33.5026 21.1074)
		(width 0.14732)
		(layer "B.Cu")
		(net "CPLD_PCIE0_WAKE_L")
	)
	(segment
		(start 33.2359 21.844)
		(end 33.2359 21.3741)
		(width 0.14732)
		(layer "B.Cu")
		(net "CPLD_PCIE0_WAKE_L")
	)
	(segment
		(start 33.655 21.1074)
		(end 32.5374 22.225)
		(width 0.12065)
		(layer "In3.Cu")
		(net "CPLD_PCIE0_WAKE_L")
	)
	(segment
		(start 26.713155 21.336)
		(end 25.273 21.336)
		(width 0.12065)
		(layer "In3.Cu")
		(net "CPLD_PCIE0_WAKE_L")
	)
	(segment
		(start 26.761796 21.384641)
		(end 26.713155 21.336)
		(width 0.12065)
		(layer "In3.Cu")
		(net "CPLD_PCIE0_WAKE_L")
	)
	(segment
		(start 21.717025 24.003)
		(end 20.447 24.003)
		(width 0.12065)
		(layer "In3.Cu")
		(net "CPLD_PCIE0_WAKE_L")
	)
	(segment
		(start 27.043786 21.384641)
		(end 26.761796 21.384641)
		(width 0.12065)
		(layer "In3.Cu")
		(net "CPLD_PCIE0_WAKE_L")
	)
	(segment
		(start 25.273 21.336)
		(end 24.765 21.844)
		(width 0.12065)
		(layer "In3.Cu")
		(net "CPLD_PCIE0_WAKE_L")
	)
	(segment
		(start 27.884145 22.225)
		(end 27.043786 21.384641)
		(width 0.12065)
		(layer "In3.Cu")
		(net "CPLD_PCIE0_WAKE_L")
	)
	(segment
		(start 23.876025 21.844)
		(end 21.717025 24.003)
		(width 0.12065)
		(layer "In3.Cu")
		(net "CPLD_PCIE0_WAKE_L")
	)
	(segment
		(start 24.765 21.844)
		(end 23.876025 21.844)
		(width 0.12065)
		(layer "In3.Cu")
		(net "CPLD_PCIE0_WAKE_L")
	)
	(segment
		(start 20.447 24.003)
		(end 19.685 23.241)
		(width 0.12065)
		(layer "In3.Cu")
		(net "CPLD_PCIE0_WAKE_L")
	)
	(segment
		(start 32.5374 22.225)
		(end 27.884145 22.225)
		(width 0.12065)
		(layer "In3.Cu")
		(net "CPLD_PCIE0_WAKE_L")
	)
	(segment
		(start 10.414 8.636)
		(end 10.414 6.35)
		(width 0.12065)
		(layer "In6.Cu")
		(net "CPLD_PCIE0_WAKE_L")
	)
	(segment
		(start 10.922 9.144)
		(end 10.414 8.636)
		(width 0.12065)
		(layer "In6.Cu")
		(net "CPLD_PCIE0_WAKE_L")
	)
	(segment
		(start 17.018 11.557)
		(end 11.684 11.557)
		(width 0.12065)
		(layer "In6.Cu")
		(net "CPLD_PCIE0_WAKE_L")
	)
	(segment
		(start 10.414 6.35)
		(end 10.922 5.842)
		(width 0.12065)
		(layer "In6.Cu")
		(net "CPLD_PCIE0_WAKE_L")
	)
	(segment
		(start 11.684 11.557)
		(end 10.922 10.795)
		(width 0.12065)
		(layer "In6.Cu")
		(net "CPLD_PCIE0_WAKE_L")
	)
	(segment
		(start 10.922 1.778)
		(end 10.16 1.016)
		(width 0.12065)
		(layer "In6.Cu")
		(net "CPLD_PCIE0_WAKE_L")
	)
	(segment
		(start 10.922 10.795)
		(end 10.922 9.144)
		(width 0.12065)
		(layer "In6.Cu")
		(net "CPLD_PCIE0_WAKE_L")
	)
	(segment
		(start 10.16 1.016)
		(end 10.16 0.254)
		(width 0.12065)
		(layer "In6.Cu")
		(net "CPLD_PCIE0_WAKE_L")
	)
	(segment
		(start 18.542 13.462)
		(end 18.542 13.081)
		(width 0.12065)
		(layer "In6.Cu")
		(net "CPLD_PCIE0_WAKE_L")
	)
	(segment
		(start 18.542 13.081)
		(end 17.018 11.557)
		(width 0.12065)
		(layer "In6.Cu")
		(net "CPLD_PCIE0_WAKE_L")
	)
	(segment
		(start 10.922 5.842)
		(end 10.922 1.778)
		(width 0.12065)
		(layer "In6.Cu")
		(net "CPLD_PCIE0_WAKE_L")
	)
	(segment
		(start 19.370675 22.926675)
		(end 19.685 23.241)
		(width 0.12065)
		(layer "In7.Cu")
		(net "CPLD_PCIE0_WAKE_L")
	)
	(segment
		(start 19.431 14.351)
		(end 19.431 15.758846)
		(width 0.12065)
		(layer "In7.Cu")
		(net "CPLD_PCIE0_WAKE_L")
	)
	(segment
		(start 18.542 13.462)
		(end 19.431 14.351)
		(width 0.12065)
		(layer "In7.Cu")
		(net "CPLD_PCIE0_WAKE_L")
	)
	(segment
		(start 19.431 15.758846)
		(end 19.370675 15.819171)
		(width 0.12065)
		(layer "In7.Cu")
		(net "CPLD_PCIE0_WAKE_L")
	)
	(segment
		(start 19.370675 15.819171)
		(end 19.370675 22.926675)
		(width 0.12065)
		(layer "In7.Cu")
		(net "CPLD_PCIE0_WAKE_L")
	)
	(segment
		(start 43.236998 13.042011)
		(end 42.736999 12.542012)
		(width 0.13208)
		(layer "F.Cu")
		(net "_PSU_I2C_SDA")
	)
	(via
		(at 42.736999 12.542012)
		(size 0.4826)
		(drill 0.20574)
		(layers "F.Cu" "B.Cu")
		(net "_PSU_I2C_SDA")
	)
	(via
		(at 27.559 12.827)
		(size 0.508)
		(drill 0.25654)
		(layers "F.Cu" "B.Cu")
		(net "_PSU_I2C_SDA")
	)
	(segment
		(start 33.745424 9.477375)
		(end 33.799399 9.53135)
		(width 0.12065)
		(layer "In3.Cu")
		(net "_PSU_I2C_SDA")
	)
	(segment
		(start 42.291 12.065)
		(end 42.736999 12.510999)
		(width 0.12065)
		(layer "In3.Cu")
		(net "_PSU_I2C_SDA")
	)
	(segment
		(start 33.799399 9.53135)
		(end 34.383726 9.53135)
		(width 0.12065)
		(layer "In3.Cu")
		(net "_PSU_I2C_SDA")
	)
	(segment
		(start 38.862 13.081)
		(end 39.243 12.7)
		(width 0.12065)
		(layer "In3.Cu")
		(net "_PSU_I2C_SDA")
	)
	(segment
		(start 28.26225 11.115675)
		(end 28.27495 11.102975)
		(width 0.12065)
		(layer "In3.Cu")
		(net "_PSU_I2C_SDA")
	)
	(segment
		(start 28.27495 11.102975)
		(end 28.60642 11.102975)
		(width 0.12065)
		(layer "In3.Cu")
		(net "_PSU_I2C_SDA")
	)
	(segment
		(start 32.548728 9.477375)
		(end 33.745424 9.477375)
		(width 0.12065)
		(layer "In3.Cu")
		(net "_PSU_I2C_SDA")
	)
	(segment
		(start 34.383726 9.53135)
		(end 37.933376 13.081)
		(width 0.12065)
		(layer "In3.Cu")
		(net "_PSU_I2C_SDA")
	)
	(segment
		(start 27.4701 12.7381)
		(end 27.4701 11.783746)
		(width 0.12065)
		(layer "In3.Cu")
		(net "_PSU_I2C_SDA")
	)
	(segment
		(start 28.138171 11.115675)
		(end 28.26225 11.115675)
		(width 0.12065)
		(layer "In3.Cu")
		(net "_PSU_I2C_SDA")
	)
	(segment
		(start 39.497 12.065)
		(end 42.291 12.065)
		(width 0.12065)
		(layer "In3.Cu")
		(net "_PSU_I2C_SDA")
	)
	(segment
		(start 39.243 12.319)
		(end 39.497 12.065)
		(width 0.12065)
		(layer "In3.Cu")
		(net "_PSU_I2C_SDA")
	)
	(segment
		(start 30.461407 10.485171)
		(end 30.461407 9.977171)
		(width 0.12065)
		(layer "In3.Cu")
		(net "_PSU_I2C_SDA")
	)
	(segment
		(start 29.891228 11.05535)
		(end 30.461407 10.485171)
		(width 0.12065)
		(layer "In3.Cu")
		(net "_PSU_I2C_SDA")
	)
	(segment
		(start 27.559 12.827)
		(end 27.4701 12.7381)
		(width 0.12065)
		(layer "In3.Cu")
		(net "_PSU_I2C_SDA")
	)
	(segment
		(start 37.933376 13.081)
		(end 38.862 13.081)
		(width 0.12065)
		(layer "In3.Cu")
		(net "_PSU_I2C_SDA")
	)
	(segment
		(start 32.494753 9.53135)
		(end 32.548728 9.477375)
		(width 0.12065)
		(layer "In3.Cu")
		(net "_PSU_I2C_SDA")
	)
	(segment
		(start 28.654045 11.05535)
		(end 29.891228 11.05535)
		(width 0.12065)
		(layer "In3.Cu")
		(net "_PSU_I2C_SDA")
	)
	(segment
		(start 27.4701 11.783746)
		(end 28.138171 11.115675)
		(width 0.12065)
		(layer "In3.Cu")
		(net "_PSU_I2C_SDA")
	)
	(segment
		(start 30.907228 9.53135)
		(end 32.494753 9.53135)
		(width 0.12065)
		(layer "In3.Cu")
		(net "_PSU_I2C_SDA")
	)
	(segment
		(start 39.243 12.7)
		(end 39.243 12.319)
		(width 0.12065)
		(layer "In3.Cu")
		(net "_PSU_I2C_SDA")
	)
	(segment
		(start 28.60642 11.102975)
		(end 28.654045 11.05535)
		(width 0.12065)
		(layer "In3.Cu")
		(net "_PSU_I2C_SDA")
	)
	(segment
		(start 42.736999 12.510999)
		(end 42.736999 12.542012)
		(width 0.12065)
		(layer "In3.Cu")
		(net "_PSU_I2C_SDA")
	)
	(segment
		(start 30.461407 9.977171)
		(end 30.907228 9.53135)
		(width 0.12065)
		(layer "In3.Cu")
		(net "_PSU_I2C_SDA")
	)
	(segment
		(start 27.5971 11.557)
		(end 28.321 11.557)
		(width 0.14732)
		(layer "F.Cu")
		(net "_PSU_I2C_SCL")
	)
	(segment
		(start 42.237 13.042011)
		(end 41.737001 12.542012)
		(width 0.13208)
		(layer "F.Cu")
		(net "_PSU_I2C_SCL")
	)
	(via
		(at 41.737001 12.542012)
		(size 0.4826)
		(drill 0.20574)
		(layers "F.Cu" "B.Cu")
		(net "_PSU_I2C_SCL")
	)
	(via
		(at 28.321 11.557)
		(size 0.508)
		(drill 0.25654)
		(layers "F.Cu" "B.Cu")
		(net "_PSU_I2C_SCL")
	)
	(segment
		(start 32.756373 9.979025)
		(end 33.537627 9.979025)
		(width 0.12065)
		(layer "In3.Cu")
		(net "_PSU_I2C_SCL")
	)
	(segment
		(start 28.321 11.557)
		(end 30.099025 11.557)
		(width 0.12065)
		(layer "In3.Cu")
		(net "_PSU_I2C_SCL")
	)
	(segment
		(start 37.512676 13.369747)
		(end 37.512676 13.465988)
		(width 0.12065)
		(layer "In3.Cu")
		(net "_PSU_I2C_SCL")
	)
	(segment
		(start 40.309013 13.97)
		(end 41.737001 12.542012)
		(width 0.12065)
		(layer "In3.Cu")
		(net "_PSU_I2C_SCL")
	)
	(segment
		(start 37.512676 13.465988)
		(end 38.016688 13.97)
		(width 0.12065)
		(layer "In3.Cu")
		(net "_PSU_I2C_SCL")
	)
	(segment
		(start 33.591602 10.033)
		(end 34.175929 10.033)
		(width 0.12065)
		(layer "In3.Cu")
		(net "_PSU_I2C_SCL")
	)
	(segment
		(start 31.623025 10.033)
		(end 32.702398 10.033)
		(width 0.12065)
		(layer "In3.Cu")
		(net "_PSU_I2C_SCL")
	)
	(segment
		(start 32.702398 10.033)
		(end 32.756373 9.979025)
		(width 0.12065)
		(layer "In3.Cu")
		(net "_PSU_I2C_SCL")
	)
	(segment
		(start 33.537627 9.979025)
		(end 33.591602 10.033)
		(width 0.12065)
		(layer "In3.Cu")
		(net "_PSU_I2C_SCL")
	)
	(segment
		(start 30.099025 11.557)
		(end 31.623025 10.033)
		(width 0.12065)
		(layer "In3.Cu")
		(net "_PSU_I2C_SCL")
	)
	(segment
		(start 34.175929 10.033)
		(end 37.512676 13.369747)
		(width 0.12065)
		(layer "In3.Cu")
		(net "_PSU_I2C_SCL")
	)
	(segment
		(start 38.016688 13.97)
		(end 40.309013 13.97)
		(width 0.12065)
		(layer "In3.Cu")
		(net "_PSU_I2C_SCL")
	)
	(segment
		(start 39.237006 12.041988)
		(end 38.737007 11.541989)
		(width 0.13208)
		(layer "F.Cu")
		(net "_PGRM_JTAG_TDO")
	)
	(segment
		(start 27.5971 10.414)
		(end 28.321 10.414)
		(width 0.14732)
		(layer "F.Cu")
		(net "_PGRM_JTAG_TDO")
	)
	(via
		(at 38.737007 11.541989)
		(size 0.4826)
		(drill 0.20574)
		(layers "F.Cu" "B.Cu")
		(net "_PGRM_JTAG_TDO")
	)
	(via
		(at 28.321 10.414)
		(size 0.508)
		(drill 0.2667)
		(layers "F.Cu" "B.Cu")
		(net "_PGRM_JTAG_TDO")
	)
	(segment
		(start 31.158536 8.382)
		(end 33.624241 8.382)
		(width 0.12065)
		(layer "In3.Cu")
		(net "_PGRM_JTAG_TDO")
	)
	(segment
		(start 37.404675 9.337675)
		(end 37.592 9.525)
		(width 0.12065)
		(layer "In3.Cu")
		(net "_PGRM_JTAG_TDO")
	)
	(segment
		(start 34.967266 7.038975)
		(end 35.838409 7.038975)
		(width 0.12065)
		(layer "In3.Cu")
		(net "_PGRM_JTAG_TDO")
	)
	(segment
		(start 33.624241 8.382)
		(end 34.967266 7.038975)
		(width 0.12065)
		(layer "In3.Cu")
		(net "_PGRM_JTAG_TDO")
	)
	(segment
		(start 36.464875 8.245373)
		(end 36.464875 9.002141)
		(width 0.12065)
		(layer "In3.Cu")
		(net "_PGRM_JTAG_TDO")
	)
	(segment
		(start 28.321 10.414)
		(end 28.321 10.033025)
		(width 0.12065)
		(layer "In3.Cu")
		(net "_PGRM_JTAG_TDO")
	)
	(segment
		(start 31.038317 8.502218)
		(end 31.158536 8.382)
		(width 0.12065)
		(layer "In3.Cu")
		(net "_PGRM_JTAG_TDO")
	)
	(segment
		(start 37.592 9.747225)
		(end 38.227 10.382225)
		(width 0.12065)
		(layer "In3.Cu")
		(net "_PGRM_JTAG_TDO")
	)
	(segment
		(start 36.32835 8.108848)
		(end 36.464875 8.245373)
		(width 0.12065)
		(layer "In3.Cu")
		(net "_PGRM_JTAG_TDO")
	)
	(segment
		(start 35.838409 7.038975)
		(end 36.32835 7.528916)
		(width 0.12065)
		(layer "In3.Cu")
		(net "_PGRM_JTAG_TDO")
	)
	(segment
		(start 36.464875 9.002141)
		(end 36.800409 9.337675)
		(width 0.12065)
		(layer "In3.Cu")
		(net "_PGRM_JTAG_TDO")
	)
	(segment
		(start 38.227 10.382225)
		(end 38.227 11.031982)
		(width 0.12065)
		(layer "In3.Cu")
		(net "_PGRM_JTAG_TDO")
	)
	(segment
		(start 37.592 9.525)
		(end 37.592 9.747225)
		(width 0.12065)
		(layer "In3.Cu")
		(net "_PGRM_JTAG_TDO")
	)
	(segment
		(start 36.32835 7.528916)
		(end 36.32835 8.108848)
		(width 0.12065)
		(layer "In3.Cu")
		(net "_PGRM_JTAG_TDO")
	)
	(segment
		(start 38.227 11.031982)
		(end 38.737007 11.541989)
		(width 0.12065)
		(layer "In3.Cu")
		(net "_PGRM_JTAG_TDO")
	)
	(segment
		(start 29.851807 8.502218)
		(end 31.038317 8.502218)
		(width 0.12065)
		(layer "In3.Cu")
		(net "_PGRM_JTAG_TDO")
	)
	(segment
		(start 28.321 10.033025)
		(end 29.851807 8.502218)
		(width 0.12065)
		(layer "In3.Cu")
		(net "_PGRM_JTAG_TDO")
	)
	(segment
		(start 36.800409 9.337675)
		(end 37.404675 9.337675)
		(width 0.12065)
		(layer "In3.Cu")
		(net "_PGRM_JTAG_TDO")
	)
	(segment
		(start 42.237 18.042001)
		(end 41.737001 17.542002)
		(width 0.13208)
		(layer "F.Cu")
		(net "_NFP_SPI2_MOSI")
	)
	(via
		(at 41.737001 17.542002)
		(size 0.4826)
		(drill 0.25654)
		(layers "F.Cu" "B.Cu")
		(net "_NFP_SPI2_MOSI")
	)
	(segment
		(start 41.6941 18.558002)
		(end 41.656127 17.622876)
		(width 0.14732)
		(layer "B.Cu")
		(net "_NFP_SPI2_MOSI")
	)
	(segment
		(start 41.656127 17.622876)
		(end 41.737001 17.542002)
		(width 0.14732)
		(layer "B.Cu")
		(net "_NFP_SPI2_MOSI")
	)
	(segment
		(start 41.237002 18.042001)
		(end 40.737003 17.542002)
		(width 0.13208)
		(layer "F.Cu")
		(net "_NFP_CFG_SPI_FLASH_MOSI")
	)
	(via
		(at 40.737003 17.542002)
		(size 0.4826)
		(drill 0.25654)
		(layers "F.Cu" "B.Cu")
		(net "_NFP_CFG_SPI_FLASH_MOSI")
	)
	(segment
		(start 38.0111 19.267932)
		(end 38.0111 19.304)
		(width 0.14732)
		(layer "B.Cu")
		(net "_NFP_CFG_SPI_FLASH_MOSI")
	)
	(segment
		(start 38.237033 19.041999)
		(end 38.0111 19.267932)
		(width 0.14732)
		(layer "B.Cu")
		(net "_NFP_CFG_SPI_FLASH_MOSI")
	)
	(segment
		(start 40.737003 17.542002)
		(end 39.237006 19.041999)
		(width 0.14732)
		(layer "B.Cu")
		(net "_NFP_CFG_SPI_FLASH_MOSI")
	)
	(segment
		(start 39.237006 19.041999)
		(end 38.237033 19.041999)
		(width 0.14732)
		(layer "B.Cu")
		(net "_NFP_CFG_SPI_FLASH_MOSI")
	)
	(segment
		(start 40.237004 18.042001)
		(end 39.737005 17.542002)
		(width 0.13208)
		(layer "F.Cu")
		(net "_NFP_ARM_SPI_FLASH_MOSI")
	)
	(via
		(at 39.737005 17.542002)
		(size 0.4826)
		(drill 0.25654)
		(layers "F.Cu" "B.Cu")
		(net "_NFP_ARM_SPI_FLASH_MOSI")
	)
	(segment
		(start 38.864007 18.415)
		(end 38.3921 18.415)
		(width 0.14732)
		(layer "B.Cu")
		(net "_NFP_ARM_SPI_FLASH_MOSI")
	)
	(segment
		(start 39.737005 17.542002)
		(end 38.864007 18.415)
		(width 0.14732)
		(layer "B.Cu")
		(net "_NFP_ARM_SPI_FLASH_MOSI")
	)
	(segment
		(start 64.77 47.0281)
		(end 64.77 47.625)
		(width 0.14732)
		(layer "F.Cu")
		(net "VDD_5.0V_PGOOD")
	)
	(segment
		(start 64.859916 47.714916)
		(end 64.859916 49.033938)
		(width 0.14732)
		(layer "F.Cu")
		(net "VDD_5.0V_PGOOD")
	)
	(segment
		(start 64.77 47.625)
		(end 64.859916 47.714916)
		(width 0.14732)
		(layer "F.Cu")
		(net "VDD_5.0V_PGOOD")
	)
	(via
		(at 35.433 28.321)
		(size 0.4572)
		(drill 0.20574)
		(layers "F.Cu" "B.Cu")
		(net "VDD_5.0V_PGOOD")
	)
	(via
		(at 33.274 48.641)
		(size 0.508)
		(drill 0.25654)
		(layers "F.Cu" "B.Cu")
		(net "VDD_5.0V_PGOOD")
	)
	(via
		(at 64.77 47.0027)
		(size 0.508)
		(drill 0.25654)
		(layers "F.Cu" "B.Cu")
		(net "VDD_5.0V_PGOOD")
	)
	(segment
		(start 34.967799 28.2702)
		(end 34.246007 27.548408)
		(width 0.127)
		(layer "In1.Cu")
		(net "VDD_5.0V_PGOOD")
	)
	(segment
		(start 35.433 28.321)
		(end 34.967799 28.2702)
		(width 0.127)
		(layer "In1.Cu")
		(net "VDD_5.0V_PGOOD")
	)
	(segment
		(start 62.738 48.387)
		(end 64.262 48.387)
		(width 0.12065)
		(layer "In7.Cu")
		(net "VDD_5.0V_PGOOD")
	)
	(segment
		(start 32.794575 42.727829)
		(end 33.734375 43.667629)
		(width 0.12065)
		(layer "In7.Cu")
		(net "VDD_5.0V_PGOOD")
	)
	(segment
		(start 34.991675 34.971203)
		(end 34.991675 35.239325)
		(width 0.12065)
		(layer "In7.Cu")
		(net "VDD_5.0V_PGOOD")
	)
	(segment
		(start 32.591248 40.448103)
		(end 32.591248 40.863444)
		(width 0.12065)
		(layer "In7.Cu")
		(net "VDD_5.0V_PGOOD")
	)
	(segment
		(start 36.449 29.337)
		(end 36.449 30.998846)
		(width 0.12065)
		(layer "In7.Cu")
		(net "VDD_5.0V_PGOOD")
	)
	(segment
		(start 36.449 30.998846)
		(end 36.763325 31.313171)
		(width 0.12065)
		(layer "In7.Cu")
		(net "VDD_5.0V_PGOOD")
	)
	(segment
		(start 33.734375 43.667629)
		(end 33.734375 47.291625)
		(width 0.12065)
		(layer "In7.Cu")
		(net "VDD_5.0V_PGOOD")
	)
	(segment
		(start 56.007 49.022)
		(end 62.103 49.022)
		(width 0.12065)
		(layer "In7.Cu")
		(net "VDD_5.0V_PGOOD")
	)
	(segment
		(start 35.931475 33.529321)
		(end 36.001325 33.599171)
		(width 0.12065)
		(layer "In7.Cu")
		(net "VDD_5.0V_PGOOD")
	)
	(segment
		(start 33.734375 47.291625)
		(end 33.274 47.752)
		(width 0.12065)
		(layer "In7.Cu")
		(net "VDD_5.0V_PGOOD")
	)
	(segment
		(start 32.591375 41.644824)
		(end 32.794575 41.848024)
		(width 0.12065)
		(layer "In7.Cu")
		(net "VDD_5.0V_PGOOD")
	)
	(segment
		(start 34.29 37.638711)
		(end 34.263178 37.665533)
		(width 0.12065)
		(layer "In7.Cu")
		(net "VDD_5.0V_PGOOD")
	)
	(segment
		(start 64.262 48.387)
		(end 64.77 47.879)
		(width 0.12065)
		(layer "In7.Cu")
		(net "VDD_5.0V_PGOOD")
	)
	(segment
		(start 32.794575 41.848024)
		(end 32.794575 42.727829)
		(width 0.12065)
		(layer "In7.Cu")
		(net "VDD_5.0V_PGOOD")
	)
	(segment
		(start 45.847 49.657)
		(end 55.372 49.657)
		(width 0.12065)
		(layer "In7.Cu")
		(net "VDD_5.0V_PGOOD")
	)
	(segment
		(start 35.167672 49.264672)
		(end 45.454672 49.264672)
		(width 0.12065)
		(layer "In7.Cu")
		(net "VDD_5.0V_PGOOD")
	)
	(segment
		(start 34.263025 37.665533)
		(end 33.969325 37.959233)
		(width 0.12065)
		(layer "In7.Cu")
		(net "VDD_5.0V_PGOOD")
	)
	(segment
		(start 33.969325 37.959233)
		(end 33.969325 38.536626)
		(width 0.12065)
		(layer "In7.Cu")
		(net "VDD_5.0V_PGOOD")
	)
	(segment
		(start 33.734375 39.304976)
		(end 32.591248 40.448103)
		(width 0.12065)
		(layer "In7.Cu")
		(net "VDD_5.0V_PGOOD")
	)
	(segment
		(start 34.29 35.941)
		(end 34.29 37.638711)
		(width 0.12065)
		(layer "In7.Cu")
		(net "VDD_5.0V_PGOOD")
	)
	(segment
		(start 34.544 48.641)
		(end 35.167672 49.264672)
		(width 0.12065)
		(layer "In7.Cu")
		(net "VDD_5.0V_PGOOD")
	)
	(segment
		(start 33.969325 38.536626)
		(end 33.734375 38.771576)
		(width 0.12065)
		(layer "In7.Cu")
		(net "VDD_5.0V_PGOOD")
	)
	(segment
		(start 33.274 47.752)
		(end 33.274 48.641)
		(width 0.12065)
		(layer "In7.Cu")
		(net "VDD_5.0V_PGOOD")
	)
	(segment
		(start 33.274 48.641)
		(end 34.544 48.641)
		(width 0.12065)
		(layer "In7.Cu")
		(net "VDD_5.0V_PGOOD")
	)
	(segment
		(start 62.103 49.022)
		(end 62.738 48.387)
		(width 0.12065)
		(layer "In7.Cu")
		(net "VDD_5.0V_PGOOD")
	)
	(segment
		(start 32.591375 40.863571)
		(end 32.591375 41.644824)
		(width 0.12065)
		(layer "In7.Cu")
		(net "VDD_5.0V_PGOOD")
	)
	(segment
		(start 35.739553 34.223325)
		(end 34.991675 34.971203)
		(width 0.12065)
		(layer "In7.Cu")
		(net "VDD_5.0V_PGOOD")
	)
	(segment
		(start 36.001325 33.964829)
		(end 35.742829 34.223325)
		(width 0.12065)
		(layer "In7.Cu")
		(net "VDD_5.0V_PGOOD")
	)
	(segment
		(start 64.77 47.879)
		(end 64.77 47.0027)
		(width 0.12065)
		(layer "In7.Cu")
		(net "VDD_5.0V_PGOOD")
	)
	(segment
		(start 36.001325 33.599171)
		(end 36.001325 33.964829)
		(width 0.12065)
		(layer "In7.Cu")
		(net "VDD_5.0V_PGOOD")
	)
	(segment
		(start 45.454672 49.264672)
		(end 45.847 49.657)
		(width 0.12065)
		(layer "In7.Cu")
		(net "VDD_5.0V_PGOOD")
	)
	(segment
		(start 33.734375 38.771576)
		(end 33.734375 39.304976)
		(width 0.12065)
		(layer "In7.Cu")
		(net "VDD_5.0V_PGOOD")
	)
	(segment
		(start 36.763325 31.678829)
		(end 35.931475 32.510679)
		(width 0.12065)
		(layer "In7.Cu")
		(net "VDD_5.0V_PGOOD")
	)
	(segment
		(start 34.263178 37.665533)
		(end 34.263025 37.665533)
		(width 0.12065)
		(layer "In7.Cu")
		(net "VDD_5.0V_PGOOD")
	)
	(segment
		(start 32.591248 40.863444)
		(end 32.591375 40.863571)
		(width 0.12065)
		(layer "In7.Cu")
		(net "VDD_5.0V_PGOOD")
	)
	(segment
		(start 34.991675 35.239325)
		(end 34.29 35.941)
		(width 0.12065)
		(layer "In7.Cu")
		(net "VDD_5.0V_PGOOD")
	)
	(segment
		(start 35.433 28.321)
		(end 36.449 29.337)
		(width 0.12065)
		(layer "In7.Cu")
		(net "VDD_5.0V_PGOOD")
	)
	(segment
		(start 55.372 49.657)
		(end 56.007 49.022)
		(width 0.12065)
		(layer "In7.Cu")
		(net "VDD_5.0V_PGOOD")
	)
	(segment
		(start 35.931475 32.510679)
		(end 35.931475 33.529321)
		(width 0.12065)
		(layer "In7.Cu")
		(net "VDD_5.0V_PGOOD")
	)
	(segment
		(start 36.763325 31.313171)
		(end 36.763325 31.678829)
		(width 0.12065)
		(layer "In7.Cu")
		(net "VDD_5.0V_PGOOD")
	)
	(segment
		(start 35.742829 34.223325)
		(end 35.739553 34.223325)
		(width 0.12065)
		(layer "In7.Cu")
		(net "VDD_5.0V_PGOOD")
	)
	(segment
		(start 64.250062 48.424084)
		(end 64.250062 47.737776)
		(width 0.14732)
		(layer "F.Cu")
		(net "VDD_5.0V_EN")
	)
	(segment
		(start 66.802 56.134)
		(end 66.802 54.864)
		(width 0.14732)
		(layer "F.Cu")
		(net "VDD_5.0V_EN")
	)
	(via
		(at 42.737024 27.542007)
		(size 0.4826)
		(drill 0.20574)
		(layers "F.Cu" "B.Cu")
		(net "VDD_5.0V_EN")
	)
	(via
		(at 64.250062 47.737776)
		(size 0.508)
		(drill 0.254)
		(layers "F.Cu" "B.Cu")
		(net "VDD_5.0V_EN")
	)
	(via
		(at 26.924 24.3332)
		(size 0.4572)
		(drill 0.20574)
		(layers "F.Cu" "B.Cu")
		(net "VDD_5.0V_EN")
	)
	(via
		(at 66.802 54.864)
		(size 0.508)
		(drill 0.254)
		(layers "F.Cu" "B.Cu")
		(net "VDD_5.0V_EN")
	)
	(via
		(at 47.9171 46.609)
		(size 0.508)
		(drill 0.25654)
		(layers "F.Cu" "B.Cu")
		(net "VDD_5.0V_EN")
	)
	(segment
		(start 26.924 24.3332)
		(end 27.877211 24.3586)
		(width 0.127)
		(layer "In1.Cu")
		(net "VDD_5.0V_EN")
	)
	(segment
		(start 28.067 24.548389)
		(end 28.745993 24.548389)
		(width 0.127)
		(layer "In1.Cu")
		(net "VDD_5.0V_EN")
	)
	(segment
		(start 27.877211 24.3586)
		(end 28.067 24.548389)
		(width 0.127)
		(layer "In1.Cu")
		(net "VDD_5.0V_EN")
	)
	(segment
		(start 26.924 24.3332)
		(end 27.4828 24.3332)
		(width 0.12065)
		(layer "In2.Cu")
		(net "VDD_5.0V_EN")
	)
	(segment
		(start 38.904062 22.138767)
		(end 39.140232 22.374936)
		(width 0.12065)
		(layer "In2.Cu")
		(net "VDD_5.0V_EN")
	)
	(segment
		(start 39.140232 22.374936)
		(end 39.140232 22.709048)
		(width 0.12065)
		(layer "In2.Cu")
		(net "VDD_5.0V_EN")
	)
	(segment
		(start 38.440233 22.138767)
		(end 38.904062 22.138767)
		(width 0.12065)
		(layer "In2.Cu")
		(net "VDD_5.0V_EN")
	)
	(segment
		(start 39.140232 22.709048)
		(end 38.710514 23.138765)
		(width 0.12065)
		(layer "In2.Cu")
		(net "VDD_5.0V_EN")
	)
	(segment
		(start 38.710514 23.138765)
		(end 38.569951 23.138765)
		(width 0.12065)
		(layer "In2.Cu")
		(net "VDD_5.0V_EN")
	)
	(segment
		(start 38.227 24.229746)
		(end 38.354 24.356746)
		(width 0.12065)
		(layer "In2.Cu")
		(net "VDD_5.0V_EN")
	)
	(segment
		(start 38.227 23.481716)
		(end 38.227 24.229746)
		(width 0.12065)
		(layer "In2.Cu")
		(net "VDD_5.0V_EN")
	)
	(segment
		(start 42.246017 27.051)
		(end 42.737024 27.542007)
		(width 0.12065)
		(layer "In2.Cu")
		(net "VDD_5.0V_EN")
	)
	(segment
		(start 35.062541 23.357459)
		(end 37.221541 23.357459)
		(width 0.12065)
		(layer "In2.Cu")
		(net "VDD_5.0V_EN")
	)
	(segment
		(start 27.4828 24.3332)
		(end 28.702 23.114)
		(width 0.12065)
		(layer "In2.Cu")
		(net "VDD_5.0V_EN")
	)
	(segment
		(start 34.819082 23.114)
		(end 35.062541 23.357459)
		(width 0.12065)
		(layer "In2.Cu")
		(net "VDD_5.0V_EN")
	)
	(segment
		(start 28.702 23.114)
		(end 34.819082 23.114)
		(width 0.12065)
		(layer "In2.Cu")
		(net "VDD_5.0V_EN")
	)
	(segment
		(start 38.354 24.356746)
		(end 38.354 25.781)
		(width 0.12065)
		(layer "In2.Cu")
		(net "VDD_5.0V_EN")
	)
	(segment
		(start 38.354 25.781)
		(end 39.624 27.051)
		(width 0.12065)
		(layer "In2.Cu")
		(net "VDD_5.0V_EN")
	)
	(segment
		(start 39.624 27.051)
		(end 42.246017 27.051)
		(width 0.12065)
		(layer "In2.Cu")
		(net "VDD_5.0V_EN")
	)
	(segment
		(start 37.221541 23.357459)
		(end 38.440233 22.138767)
		(width 0.12065)
		(layer "In2.Cu")
		(net "VDD_5.0V_EN")
	)
	(segment
		(start 38.569951 23.138765)
		(end 38.227 23.481716)
		(width 0.12065)
		(layer "In2.Cu")
		(net "VDD_5.0V_EN")
	)
	(segment
		(start 66.802 51.943)
		(end 66.802 54.864)
		(width 0.12065)
		(layer "In6.Cu")
		(net "VDD_5.0V_EN")
	)
	(segment
		(start 64.250062 47.737776)
		(end 65.278 48.765714)
		(width 0.12065)
		(layer "In6.Cu")
		(net "VDD_5.0V_EN")
	)
	(segment
		(start 65.278 50.419)
		(end 66.802 51.943)
		(width 0.12065)
		(layer "In6.Cu")
		(net "VDD_5.0V_EN")
	)
	(segment
		(start 65.278 48.765714)
		(end 65.278 50.419)
		(width 0.12065)
		(layer "In6.Cu")
		(net "VDD_5.0V_EN")
	)
	(segment
		(start 43.053 38.608)
		(end 43.053 35.259239)
		(width 0.12065)
		(layer "In7.Cu")
		(net "VDD_5.0V_EN")
	)
	(segment
		(start 43.214925 35.097314)
		(end 43.214925 34.752686)
		(width 0.12065)
		(layer "In7.Cu")
		(net "VDD_5.0V_EN")
	)
	(segment
		(start 57.912 46.609)
		(end 47.9171 46.609)
		(width 0.12065)
		(layer "In7.Cu")
		(net "VDD_5.0V_EN")
	)
	(segment
		(start 43.815 42.926)
		(end 43.815 39.37)
		(width 0.12065)
		(layer "In7.Cu")
		(net "VDD_5.0V_EN")
	)
	(segment
		(start 43.214925 34.752686)
		(end 42.926 34.463761)
		(width 0.12065)
		(layer "In7.Cu")
		(net "VDD_5.0V_EN")
	)
	(segment
		(start 43.053 35.259239)
		(end 43.214925 35.097314)
		(width 0.12065)
		(layer "In7.Cu")
		(net "VDD_5.0V_EN")
	)
	(segment
		(start 43.140224 27.945207)
		(end 42.737024 27.542007)
		(width 0.12065)
		(layer "In7.Cu")
		(net "VDD_5.0V_EN")
	)
	(segment
		(start 64.250062 47.737776)
		(end 62.260861 45.748575)
		(width 0.12065)
		(layer "In7.Cu")
		(net "VDD_5.0V_EN")
	)
	(segment
		(start 42.926 32.004)
		(end 43.140224 31.789776)
		(width 0.12065)
		(layer "In7.Cu")
		(net "VDD_5.0V_EN")
	)
	(segment
		(start 47.9171 46.609)
		(end 47.498 46.609)
		(width 0.12065)
		(layer "In7.Cu")
		(net "VDD_5.0V_EN")
	)
	(segment
		(start 43.815 39.37)
		(end 43.053 38.608)
		(width 0.12065)
		(layer "In7.Cu")
		(net "VDD_5.0V_EN")
	)
	(segment
		(start 58.772425 45.748575)
		(end 57.912 46.609)
		(width 0.12065)
		(layer "In7.Cu")
		(net "VDD_5.0V_EN")
	)
	(segment
		(start 42.926 34.463761)
		(end 42.926 32.004)
		(width 0.12065)
		(layer "In7.Cu")
		(net "VDD_5.0V_EN")
	)
	(segment
		(start 47.498 46.609)
		(end 43.815 42.926)
		(width 0.12065)
		(layer "In7.Cu")
		(net "VDD_5.0V_EN")
	)
	(segment
		(start 62.260861 45.748575)
		(end 58.772425 45.748575)
		(width 0.12065)
		(layer "In7.Cu")
		(net "VDD_5.0V_EN")
	)
	(segment
		(start 43.140224 31.789776)
		(end 43.140224 27.945207)
		(width 0.12065)
		(layer "In7.Cu")
		(net "VDD_5.0V_EN")
	)
	(segment
		(start 13.278104 35.0393)
		(end 13.278104 34.195004)
		(width 0.2032)
		(layer "F.Cu")
		(net "VDD_5.0V")
	)
	(segment
		(start 15.4813 35.8394)
		(end 15.2781 35.5727)
		(width 0.2032)
		(layer "F.Cu")
		(net "VDD_5.0V")
	)
	(segment
		(start 15.875 40.005)
		(end 15.677896 39.807896)
		(width 0.2032)
		(layer "F.Cu")
		(net "VDD_5.0V")
	)
	(segment
		(start 15.2781 35.5727)
		(end 15.2781 35.0393)
		(width 0.2032)
		(layer "F.Cu")
		(net "VDD_5.0V")
	)
	(segment
		(start 15.680614 33.562214)
		(end 15.4559 33.3375)
		(width 0.508)
		(layer "F.Cu")
		(net "VDD_5.0V")
	)
	(segment
		(start 48.641 53.848)
		(end 48.641 54.3814)
		(width 0.508)
		(layer "F.Cu")
		(net "VDD_5.0V")
	)
	(segment
		(start 58.039 49.4538)
		(end 57.7088 49.784)
		(width 0.508)
		(layer "F.Cu")
		(net "VDD_5.0V")
	)
	(segment
		(start 15.680614 33.752714)
		(end 15.680614 34.090178)
		(width 0.508)
		(layer "F.Cu")
		(net "VDD_5.0V")
	)
	(segment
		(start 14.07795 34.2392)
		(end 14.078001 34.309101)
		(width 0.2032)
		(layer "F.Cu")
		(net "VDD_5.0V")
	)
	(segment
		(start 14.078001 39.3827)
		(end 14.078001 40.747899)
		(width 0.2032)
		(layer "F.Cu")
		(net "VDD_5.0V")
	)
	(segment
		(start 48.641 54.3814)
		(end 48.2346 55.0164)
		(width 0.508)
		(layer "F.Cu")
		(net "VDD_5.0V")
	)
	(segment
		(start 13.208 31.6611)
		(end 12.6111 32.258)
		(width 0.508)
		(layer "F.Cu")
		(net "VDD_5.0V")
	)
	(segment
		(start 14.078001 40.747899)
		(end 13.9319 40.894)
		(width 0.2032)
		(layer "F.Cu")
		(net "VDD_5.0V")
	)
	(segment
		(start 47.371 54.3814)
		(end 47.371 53.848)
		(width 0.508)
		(layer "F.Cu")
		(net "VDD_5.0V")
	)
	(segment
		(start 4.191 33.7439)
		(end 4.191 33.02)
		(width 0.2032)
		(layer "F.Cu")
		(net "VDD_5.0V")
	)
	(segment
		(start 14.078001 34.309101)
		(end 14.078001 35.0393)
		(width 0.2032)
		(layer "F.Cu")
		(net "VDD_5.0V")
	)
	(segment
		(start 11.194999 36.811001)
		(end 12.3063 36.811001)
		(width 0.2032)
		(layer "F.Cu")
		(net "VDD_5.0V")
	)
	(segment
		(start 11.176 36.83)
		(end 11.194999 36.811001)
		(width 0.2032)
		(layer "F.Cu")
		(net "VDD_5.0V")
	)
	(segment
		(start 10.033 36.7919)
		(end 9.1567 36.7919)
		(width 0.508)
		(layer "F.Cu")
		(net "VDD_5.0V")
	)
	(segment
		(start 5.08 33.7439)
		(end 5.08 33.02)
		(width 0.2032)
		(layer "F.Cu")
		(net "VDD_5.0V")
	)
	(segment
		(start 13.081 40.132)
		(end 13.278104 39.934896)
		(width 0.2032)
		(layer "F.Cu")
		(net "VDD_5.0V")
	)
	(segment
		(start 59.3725 47.0281)
		(end 59.3725 47.443568)
		(width 0.508)
		(layer "F.Cu")
		(net "VDD_5.0V")
	)
	(segment
		(start 13.208 30.607)
		(end 13.208 31.6611)
		(width 0.508)
		(layer "F.Cu")
		(net "VDD_5.0V")
	)
	(segment
		(start 15.677896 34.219896)
		(end 15.677896 34.7853)
		(width 0.2032)
		(layer "F.Cu")
		(net "VDD_5.0V")
	)
	(segment
		(start 10.033 36.7919)
		(end 10.05205 36.81095)
		(width 0.508)
		(layer "F.Cu")
		(net "VDD_5.0V")
	)
	(segment
		(start 15.680614 33.752714)
		(end 15.680614 33.562214)
		(width 0.508)
		(layer "F.Cu")
		(net "VDD_5.0V")
	)
	(segment
		(start 58.039 48.777068)
		(end 58.039 49.4538)
		(width 0.508)
		(layer "F.Cu")
		(net "VDD_5.0V")
	)
	(segment
		(start 16.637 40.03802)
		(end 16.60398 40.005)
		(width 0.381)
		(layer "F.Cu")
		(net "VDD_5.0V")
	)
	(segment
		(start 16.60398 40.005)
		(end 16.572408 40.036572)
		(width 0.381)
		(layer "F.Cu")
		(net "VDD_5.0V")
	)
	(segment
		(start 13.278104 39.934896)
		(end 13.278104 39.3827)
		(width 0.2032)
		(layer "F.Cu")
		(net "VDD_5.0V")
	)
	(segment
		(start 15.680614 34.090178)
		(end 15.677896 34.219896)
		(width 0.508)
		(layer "F.Cu")
		(net "VDD_5.0V")
	)
	(segment
		(start 48.2346 55.0164)
		(end 47.371 54.3814)
		(width 0.508)
		(layer "F.Cu")
		(net "VDD_5.0V")
	)
	(segment
		(start 16.60398 40.005)
		(end 15.875 40.005)
		(width 0.2032)
		(layer "F.Cu")
		(net "VDD_5.0V")
	)
	(segment
		(start 15.677896 39.807896)
		(end 15.677896 39.3827)
		(width 0.2032)
		(layer "F.Cu")
		(net "VDD_5.0V")
	)
	(segment
		(start 59.3725 47.443568)
		(end 58.039 48.777068)
		(width 0.508)
		(layer "F.Cu")
		(net "VDD_5.0V")
	)
	(segment
		(start 36.7411 36.195)
		(end 36.7665 37.0967)
		(width 0.508)
		(layer "F.Cu")
		(net "VDD_5.0V")
	)
	(segment
		(start 15.677896 35.0393)
		(end 15.677896 34.7853)
		(width 0.2032)
		(layer "F.Cu")
		(net "VDD_5.0V")
	)
	(segment
		(start 13.6779 35.0393)
		(end 13.6779 35.8394)
		(width 0.2032)
		(layer "F.Cu")
		(net "VDD_5.0V")
	)
	(via
		(at 5.08 33.02)
		(size 0.508)
		(drill 0.254)
		(layers "F.Cu" "B.Cu")
		(net "VDD_5.0V")
	)
	(via
		(at 12.1031 40.894)
		(size 0.508)
		(drill 0.25654)
		(layers "F.Cu" "B.Cu")
		(net "VDD_5.0V")
	)
	(via
		(at 56.388 52.197)
		(size 0.508)
		(drill 0.254)
		(layers "F.Cu" "B.Cu")
		(net "VDD_5.0V")
	)
	(via
		(at 56.388 54.737)
		(size 0.508)
		(drill 0.254)
		(layers "F.Cu" "B.Cu")
		(net "VDD_5.0V")
	)
	(via
		(at 65.786 36.0553)
		(size 0.508)
		(drill 0.25654)
		(layers "F.Cu" "B.Cu")
		(net "VDD_5.0V")
	)
	(via
		(at 12.1031 41.783)
		(size 0.508)
		(drill 0.254)
		(layers "F.Cu" "B.Cu")
		(net "VDD_5.0V")
	)
	(via
		(at 12.6111 33.528)
		(size 0.508)
		(drill 0.25654)
		(layers "F.Cu" "B.Cu")
		(net "VDD_5.0V")
	)
	(via
		(at 56.388 53.467)
		(size 0.508)
		(drill 0.254)
		(layers "F.Cu" "B.Cu")
		(net "VDD_5.0V")
	)
	(via
		(at 56.388 50.927)
		(size 0.508)
		(drill 0.254)
		(layers "F.Cu" "B.Cu")
		(net "VDD_5.0V")
	)
	(via
		(at 15.4813 35.8394)
		(size 0.508)
		(drill 0.254)
		(layers "F.Cu" "B.Cu")
		(net "VDD_5.0V")
	)
	(via
		(at 4.191 33.02)
		(size 0.508)
		(drill 0.254)
		(layers "F.Cu" "B.Cu")
		(net "VDD_5.0V")
	)
	(via
		(at 12.6111 32.258)
		(size 0.508)
		(drill 0.254)
		(layers "F.Cu" "B.Cu")
		(net "VDD_5.0V")
	)
	(via
		(at 13.6779 35.8394)
		(size 0.508)
		(drill 0.254)
		(layers "F.Cu" "B.Cu")
		(net "VDD_5.0V")
	)
	(via
		(at 14.07795 34.2392)
		(size 0.508)
		(drill 0.254)
		(layers "F.Cu" "B.Cu")
		(net "VDD_5.0V")
	)
	(via
		(at 8.1407 36.7919)
		(size 0.508)
		(drill 0.254)
		(layers "F.Cu" "B.Cu")
		(net "VDD_5.0V")
	)
	(via
		(at 9.1567 36.7919)
		(size 0.508)
		(drill 0.254)
		(layers "F.Cu" "B.Cu")
		(net "VDD_5.0V")
	)
	(via
		(at 47.371 53.848)
		(size 0.508)
		(drill 0.254)
		(layers "F.Cu" "B.Cu")
		(net "VDD_5.0V")
	)
	(via
		(at 48.641 53.848)
		(size 0.508)
		(drill 0.254)
		(layers "F.Cu" "B.Cu")
		(net "VDD_5.0V")
	)
	(via
		(at 15.4559 33.3375)
		(size 0.508)
		(drill 0.25654)
		(layers "F.Cu" "B.Cu")
		(net "VDD_5.0V")
	)
	(via
		(at 83.058 39.243)
		(size 0.508)
		(drill 0.254)
		(layers "F.Cu" "B.Cu")
		(net "VDD_5.0V")
	)
	(via
		(at 56.388 49.657)
		(size 0.508)
		(drill 0.254)
		(layers "F.Cu" "B.Cu")
		(net "VDD_5.0V")
	)
	(via
		(at 14.097 33.3502)
		(size 0.508)
		(drill 0.254)
		(layers "F.Cu" "B.Cu")
		(net "VDD_5.0V")
	)
	(via
		(at 56.388 48.387)
		(size 0.508)
		(drill 0.254)
		(layers "F.Cu" "B.Cu")
		(net "VDD_5.0V")
	)
	(via
		(at 13.208 41.783)
		(size 0.508)
		(drill 0.254)
		(layers "F.Cu" "B.Cu")
		(net "VDD_5.0V")
	)
	(via
		(at 13.9319 40.894)
		(size 0.508)
		(drill 0.25654)
		(layers "F.Cu" "B.Cu")
		(net "VDD_5.0V")
	)
	(via
		(at 46.1899 36.0553)
		(size 0.508)
		(drill 0.25654)
		(layers "F.Cu" "B.Cu")
		(net "VDD_5.0V")
	)
	(via
		(at 16.637 40.03802)
		(size 0.508)
		(drill 0.254)
		(layers "F.Cu" "B.Cu")
		(net "VDD_5.0V")
	)
	(via
		(at 17.2593 40.894)
		(size 0.508)
		(drill 0.25654)
		(layers "F.Cu" "B.Cu")
		(net "VDD_5.0V")
	)
	(via
		(at 65.659 46.6979)
		(size 0.508)
		(drill 0.25654)
		(layers "F.Cu" "B.Cu")
		(net "VDD_5.0V")
	)
	(via
		(at 36.7665 37.0967)
		(size 0.508)
		(drill 0.25654)
		(layers "F.Cu" "B.Cu")
		(net "VDD_5.0V")
	)
	(segment
		(start 46.1899 36.0553)
		(end 46.1899 36.0299)
		(width 0.254)
		(layer "B.Cu")
		(net "VDD_5.0V")
	)
	(segment
		(start 47.0027 36.0553)
		(end 47.0789 36.1315)
		(width 0.254)
		(layer "B.Cu")
		(net "VDD_5.0V")
	)
	(segment
		(start 45.360768 35.2679)
		(end 45.3009 35.2679)
		(width 0.254)
		(layer "B.Cu")
		(net "VDD_5.0V")
	)
	(segment
		(start 83.058 39.243)
		(end 82.296 39.243)
		(width 0.508)
		(layer "B.Cu")
		(net "VDD_5.0V")
	)
	(segment
		(start 81.7499 39.7891)
		(end 81.7499 40.132)
		(width 0.508)
		(layer "B.Cu")
		(net "VDD_5.0V")
	)
	(segment
		(start 46.1899 36.802009)
		(end 46.471891 37.084)
		(width 0.254)
		(layer "B.Cu")
		(net "VDD_5.0V")
	)
	(segment
		(start 45.8978 35.7378)
		(end 45.830668 35.7378)
		(width 0.254)
		(layer "B.Cu")
		(net "VDD_5.0V")
	)
	(segment
		(start 65.437309 35.7124)
		(end 65.4431 35.7124)
		(width 0.2032)
		(layer "B.Cu")
		(net "VDD_5.0V")
	)
	(segment
		(start 65.786 36.421009)
		(end 66.067991 36.703)
		(width 0.254)
		(layer "B.Cu")
		(net "VDD_5.0V")
	)
	(segment
		(start 64.897 35.2679)
		(end 64.992809 35.2679)
		(width 0.2032)
		(layer "B.Cu")
		(net "VDD_5.0V")
	)
	(segment
		(start 64.992809 35.2679)
		(end 65.437309 35.7124)
		(width 0.2032)
		(layer "B.Cu")
		(net "VDD_5.0V")
	)
	(segment
		(start 82.296 39.243)
		(end 81.7499 39.7891)
		(width 0.508)
		(layer "B.Cu")
		(net "VDD_5.0V")
	)
	(segment
		(start 46.1899 36.0299)
		(end 45.8978 35.7378)
		(width 0.254)
		(layer "B.Cu")
		(net "VDD_5.0V")
	)
	(segment
		(start 65.786 36.0553)
		(end 66.675 36.0553)
		(width 0.254)
		(layer "B.Cu")
		(net "VDD_5.0V")
	)
	(segment
		(start 46.471891 37.084)
		(end 46.471891 37.6936)
		(width 0.254)
		(layer "B.Cu")
		(net "VDD_5.0V")
	)
	(segment
		(start 46.1899 36.0553)
		(end 47.0027 36.0553)
		(width 0.254)
		(layer "B.Cu")
		(net "VDD_5.0V")
	)
	(segment
		(start 65.786 36.0553)
		(end 65.786 36.421009)
		(width 0.254)
		(layer "B.Cu")
		(net "VDD_5.0V")
	)
	(segment
		(start 46.1899 36.0553)
		(end 46.1899 36.802009)
		(width 0.254)
		(layer "B.Cu")
		(net "VDD_5.0V")
	)
	(segment
		(start 45.830668 35.7378)
		(end 45.360768 35.2679)
		(width 0.254)
		(layer "B.Cu")
		(net "VDD_5.0V")
	)
	(segment
		(start 66.067991 36.703)
		(end 66.067991 37.6936)
		(width 0.254)
		(layer "B.Cu")
		(net "VDD_5.0V")
	)
	(segment
		(start 65.4431 35.7124)
		(end 65.786 36.0553)
		(width 0.2032)
		(layer "B.Cu")
		(net "VDD_5.0V")
	)
	(segment
		(start 46.1899 35.8521)
		(end 46.1899 36.0553)
		(width 0.508)
		(layer "In2.Cu")
		(net "VDD_5.0V")
	)
	(segment
		(start 65.786 35.814)
		(end 65.405 35.433)
		(width 0.508)
		(layer "In2.Cu")
		(net "VDD_5.0V")
	)
	(segment
		(start 46.609 35.433)
		(end 46.1899 35.8521)
		(width 0.508)
		(layer "In2.Cu")
		(net "VDD_5.0V")
	)
	(segment
		(start 65.405 35.433)
		(end 46.609 35.433)
		(width 0.508)
		(layer "In2.Cu")
		(net "VDD_5.0V")
	)
	(segment
		(start 65.786 36.0553)
		(end 65.786 35.814)
		(width 0.508)
		(layer "In2.Cu")
		(net "VDD_5.0V")
	)
	(segment
		(start 83.058 39.243)
		(end 83.058 44.704)
		(width 0.508)
		(layer "In3.Cu")
		(net "VDD_5.0V")
	)
	(segment
		(start 69.469 46.355)
		(end 72.136 46.355)
		(width 0.508)
		(layer "In3.Cu")
		(net "VDD_5.0V")
	)
	(segment
		(start 65.786 36.0553)
		(end 66.5353 35.306)
		(width 0.508)
		(layer "In3.Cu")
		(net "VDD_5.0V")
	)
	(segment
		(start 72.136 46.355)
		(end 72.517 45.974)
		(width 0.508)
		(layer "In3.Cu")
		(net "VDD_5.0V")
	)
	(segment
		(start 44.0309 37.338)
		(end 45.3136 36.0553)
		(width 0.508)
		(layer "In3.Cu")
		(net "VDD_5.0V")
	)
	(segment
		(start 40.005 37.338)
		(end 44.0309 37.338)
		(width 0.508)
		(layer "In3.Cu")
		(net "VDD_5.0V")
	)
	(segment
		(start 82.423 45.339)
		(end 74.549 45.339)
		(width 0.508)
		(layer "In3.Cu")
		(net "VDD_5.0V")
	)
	(segment
		(start 39.624 37.719)
		(end 40.005 37.338)
		(width 0.508)
		(layer "In3.Cu")
		(net "VDD_5.0V")
	)
	(segment
		(start 36.957 37.211)
		(end 37.465 37.719)
		(width 0.508)
		(layer "In3.Cu")
		(net "VDD_5.0V")
	)
	(segment
		(start 37.465 37.719)
		(end 39.624 37.719)
		(width 0.508)
		(layer "In3.Cu")
		(net "VDD_5.0V")
	)
	(segment
		(start 73.914 45.974)
		(end 72.517 45.974)
		(width 0.508)
		(layer "In3.Cu")
		(net "VDD_5.0V")
	)
	(segment
		(start 66.5353 35.306)
		(end 68.834 35.306)
		(width 0.508)
		(layer "In3.Cu")
		(net "VDD_5.0V")
	)
	(segment
		(start 74.549 45.339)
		(end 73.914 45.974)
		(width 0.508)
		(layer "In3.Cu")
		(net "VDD_5.0V")
	)
	(segment
		(start 72.136 40.259)
		(end 72.136 43.043932)
		(width 0.508)
		(layer "In3.Cu")
		(net "VDD_5.0V")
	)
	(segment
		(start 69.4309 46.3931)
		(end 69.469 46.355)
		(width 0.508)
		(layer "In3.Cu")
		(net "VDD_5.0V")
	)
	(segment
		(start 69.85 36.322)
		(end 69.85 37.973)
		(width 0.508)
		(layer "In3.Cu")
		(net "VDD_5.0V")
	)
	(segment
		(start 65.659 46.6979)
		(end 65.9638 46.3931)
		(width 0.508)
		(layer "In3.Cu")
		(net "VDD_5.0V")
	)
	(segment
		(start 72.136 43.043932)
		(end 72.517 43.424932)
		(width 0.508)
		(layer "In3.Cu")
		(net "VDD_5.0V")
	)
	(segment
		(start 45.3136 36.0553)
		(end 46.1899 36.0553)
		(width 0.508)
		(layer "In3.Cu")
		(net "VDD_5.0V")
	)
	(segment
		(start 36.7665 37.0967)
		(end 36.957 37.211)
		(width 0.508)
		(layer "In3.Cu")
		(net "VDD_5.0V")
	)
	(segment
		(start 83.058 44.704)
		(end 82.423 45.339)
		(width 0.508)
		(layer "In3.Cu")
		(net "VDD_5.0V")
	)
	(segment
		(start 69.85 37.973)
		(end 72.136 40.259)
		(width 0.508)
		(layer "In3.Cu")
		(net "VDD_5.0V")
	)
	(segment
		(start 65.9638 46.3931)
		(end 69.4309 46.3931)
		(width 0.508)
		(layer "In3.Cu")
		(net "VDD_5.0V")
	)
	(segment
		(start 68.834 35.306)
		(end 69.85 36.322)
		(width 0.508)
		(layer "In3.Cu")
		(net "VDD_5.0V")
	)
	(segment
		(start 72.517 43.424932)
		(end 72.517 45.974)
		(width 0.508)
		(layer "In3.Cu")
		(net "VDD_5.0V")
	)
	(segment
		(start 20.701 17.272)
		(end 20.922336 17.272)
		(width 0.508)
		(layer "F.Cu")
		(net "VDD_3.3V")
	)
	(segment
		(start 23.241 16.4338)
		(end 23.2029 16.4719)
		(width 0.508)
		(layer "F.Cu")
		(net "VDD_3.3V")
	)
	(segment
		(start 45.236994 16.042005)
		(end 44.736995 15.542006)
		(width 0.254)
		(layer "F.Cu")
		(net "VDD_3.3V")
	)
	(segment
		(start 23.2029 16.4719)
		(end 21.971 16.4719)
		(width 0.508)
		(layer "F.Cu")
		(net "VDD_3.3V")
	)
	(segment
		(start 19.939 9.271)
		(end 20.955 9.271)
		(width 0.508)
		(layer "F.Cu")
		(net "VDD_3.3V")
	)
	(segment
		(start 47.752 35.56)
		(end 56.388 35.56)
		(width 0.508)
		(layer "F.Cu")
		(net "VDD_3.3V")
	)
	(segment
		(start 44.236996 14.042009)
		(end 43.736997 13.54201)
		(width 0.254)
		(layer "F.Cu")
		(net "VDD_3.3V")
	)
	(segment
		(start 20.2438 17.7292)
		(end 20.701 17.272)
		(width 0.508)
		(layer "F.Cu")
		(net "VDD_3.3V")
	)
	(segment
		(start 20.2438 18.8341)
		(end 19.3421 18.8341)
		(width 0.2032)
		(layer "F.Cu")
		(net "VDD_3.3V")
	)
	(segment
		(start 24.511 16.4719)
		(end 23.2791 16.4719)
		(width 0.508)
		(layer "F.Cu")
		(net "VDD_3.3V")
	)
	(segment
		(start 18.1483 30.167936)
		(end 18.1483 31.3055)
		(width 0.508)
		(layer "F.Cu")
		(net "VDD_3.3V")
	)
	(segment
		(start 20.2438 20.396175)
		(end 19.939 20.700975)
		(width 0.508)
		(layer "F.Cu")
		(net "VDD_3.3V")
	)
	(segment
		(start 18.6309 28.448)
		(end 17.7165 28.448)
		(width 0.508)
		(layer "F.Cu")
		(net "VDD_3.3V")
	)
	(segment
		(start 19.431 7.62)
		(end 19.431 8.763)
		(width 0.508)
		(layer "F.Cu")
		(net "VDD_3.3V")
	)
	(segment
		(start 21.559164 16.6243)
		(end 21.570036 16.6243)
		(width 0.508)
		(layer "F.Cu")
		(net "VDD_3.3V")
	)
	(segment
		(start 19.685 6.9469)
		(end 19.685 7.366)
		(width 0.254)
		(layer "F.Cu")
		(net "VDD_3.3V")
	)
	(segment
		(start 7.3279 17.7419)
		(end 6.731 17.145)
		(width 0.2032)
		(layer "F.Cu")
		(net "VDD_3.3V")
	)
	(segment
		(start 20.922336 17.272)
		(end 21.336 16.858336)
		(width 0.508)
		(layer "F.Cu")
		(net "VDD_3.3V")
	)
	(segment
		(start 45.236994 15.042007)
		(end 44.736995 14.542008)
		(width 0.254)
		(layer "F.Cu")
		(net "VDD_3.3V")
	)
	(segment
		(start 19.939 22.479)
		(end 20.701 23.241)
		(width 0.508)
		(layer "F.Cu")
		(net "VDD_3.3V")
	)
	(segment
		(start 44.236996 11.04199)
		(end 43.736997 10.541991)
		(width 0.254)
		(layer "F.Cu")
		(net "VDD_3.3V")
	)
	(segment
		(start 17.272 28.8925)
		(end 17.272 29.291636)
		(width 0.508)
		(layer "F.Cu")
		(net "VDD_3.3V")
	)
	(segment
		(start 21.336 16.858336)
		(end 21.336 16.847464)
		(width 0.508)
		(layer "F.Cu")
		(net "VDD_3.3V")
	)
	(segment
		(start 57.3659 36.5379)
		(end 63.119 36.5379)
		(width 0.508)
		(layer "F.Cu")
		(net "VDD_3.3V")
	)
	(segment
		(start 20.2438 18.8341)
		(end 20.2438 17.7292)
		(width 0.508)
		(layer "F.Cu")
		(net "VDD_3.3V")
	)
	(segment
		(start 56.388 35.56)
		(end 57.3659 36.5379)
		(width 0.508)
		(layer "F.Cu")
		(net "VDD_3.3V")
	)
	(segment
		(start 17.272 29.291636)
		(end 18.1483 30.167936)
		(width 0.508)
		(layer "F.Cu")
		(net "VDD_3.3V")
	)
	(segment
		(start 18.6309 27.813)
		(end 17.907 27.0891)
		(width 0.508)
		(layer "F.Cu")
		(net "VDD_3.3V")
	)
	(segment
		(start 19.939 20.700975)
		(end 19.939 22.479)
		(width 0.508)
		(layer "F.Cu")
		(net "VDD_3.3V")
	)
	(segment
		(start 21.722436 16.4719)
		(end 21.971 16.4719)
		(width 0.508)
		(layer "F.Cu")
		(net "VDD_3.3V")
	)
	(segment
		(start 18.6309 28.448)
		(end 18.6309 27.813)
		(width 0.508)
		(layer "F.Cu")
		(net "VDD_3.3V")
	)
	(segment
		(start 19.431 8.763)
		(end 19.939 9.271)
		(width 0.508)
		(layer "F.Cu")
		(net "VDD_3.3V")
	)
	(segment
		(start 45.236994 13.042011)
		(end 44.736995 12.542012)
		(width 0.254)
		(layer "F.Cu")
		(net "VDD_3.3V")
	)
	(segment
		(start 43.5229 36.5379)
		(end 44.860032 35.200768)
		(width 0.508)
		(layer "F.Cu")
		(net "VDD_3.3V")
	)
	(segment
		(start 20.2438 18.8341)
		(end 20.2438 20.396175)
		(width 0.508)
		(layer "F.Cu")
		(net "VDD_3.3V")
	)
	(segment
		(start 44.236996 17.042003)
		(end 43.736997 16.542004)
		(width 0.254)
		(layer "F.Cu")
		(net "VDD_3.3V")
	)
	(segment
		(start 23.2791 16.4719)
		(end 23.241 16.4338)
		(width 0.508)
		(layer "F.Cu")
		(net "VDD_3.3V")
	)
	(segment
		(start 19.685 7.366)
		(end 19.431 7.62)
		(width 0.254)
		(layer "F.Cu")
		(net "VDD_3.3V")
	)
	(segment
		(start 21.336 16.847464)
		(end 21.559164 16.6243)
		(width 0.508)
		(layer "F.Cu")
		(net "VDD_3.3V")
	)
	(segment
		(start 19.3421 18.8341)
		(end 18.2499 17.7419)
		(width 0.2032)
		(layer "F.Cu")
		(net "VDD_3.3V")
	)
	(segment
		(start 17.874996 36.011104)
		(end 17.389348 36.011104)
		(width 0.508)
		(layer "F.Cu")
		(net "VDD_3.3V")
	)
	(segment
		(start 21.570036 16.6243)
		(end 21.722436 16.4719)
		(width 0.508)
		(layer "F.Cu")
		(net "VDD_3.3V")
	)
	(segment
		(start 17.7165 28.448)
		(end 17.272 28.8925)
		(width 0.508)
		(layer "F.Cu")
		(net "VDD_3.3V")
	)
	(segment
		(start 47.392768 35.200768)
		(end 47.752 35.56)
		(width 0.508)
		(layer "F.Cu")
		(net "VDD_3.3V")
	)
	(segment
		(start 44.860032 35.200768)
		(end 47.392768 35.200768)
		(width 0.508)
		(layer "F.Cu")
		(net "VDD_3.3V")
	)
	(segment
		(start 18.2499 17.7419)
		(end 7.3279 17.7419)
		(width 0.2032)
		(layer "F.Cu")
		(net "VDD_3.3V")
	)
	(segment
		(start 17.389348 36.011104)
		(end 16.6497 36.011104)
		(width 0.2032)
		(layer "F.Cu")
		(net "VDD_3.3V")
	)
	(via
		(at 43.736997 16.542004)
		(size 0.4826)
		(drill 0.20574)
		(layers "F.Cu" "B.Cu")
		(net "VDD_3.3V")
	)
	(via
		(at 43.736997 13.54201)
		(size 0.4826)
		(drill 0.20574)
		(layers "F.Cu" "B.Cu")
		(net "VDD_3.3V")
	)
	(via
		(at 20.955 9.271)
		(size 0.508)
		(drill 0.25654)
		(layers "F.Cu" "B.Cu")
		(net "VDD_3.3V")
	)
	(via
		(at 6.731 17.145)
		(size 0.508)
		(drill 0.254)
		(layers "F.Cu" "B.Cu")
		(net "VDD_3.3V")
	)
	(via
		(at 43.5229 36.5379)
		(size 0.508)
		(drill 0.25654)
		(layers "F.Cu" "B.Cu")
		(net "VDD_3.3V")
	)
	(via
		(at 19.685 33.528)
		(size 0.508)
		(drill 0.254)
		(layers "F.Cu" "B.Cu")
		(net "VDD_3.3V")
	)
	(via
		(at 20.701 23.241)
		(size 0.508)
		(drill 0.254)
		(layers "F.Cu" "B.Cu")
		(net "VDD_3.3V")
	)
	(via
		(at 23.749 36.1315)
		(size 0.508)
		(drill 0.25654)
		(layers "F.Cu" "B.Cu")
		(net "VDD_3.3V")
	)
	(via
		(at 43.736997 10.541991)
		(size 0.4826)
		(drill 0.20574)
		(layers "F.Cu" "B.Cu")
		(net "VDD_3.3V")
	)
	(via
		(at 44.736995 12.542012)
		(size 0.4826)
		(drill 0.20574)
		(layers "F.Cu" "B.Cu")
		(net "VDD_3.3V")
	)
	(via
		(at 24.511 16.4719)
		(size 0.508)
		(drill 0.25654)
		(layers "F.Cu" "B.Cu")
		(net "VDD_3.3V")
	)
	(via
		(at 44.736995 15.542006)
		(size 0.4826)
		(drill 0.20574)
		(layers "F.Cu" "B.Cu")
		(net "VDD_3.3V")
	)
	(via
		(at 63.119 36.5379)
		(size 0.508)
		(drill 0.25654)
		(layers "F.Cu" "B.Cu")
		(net "VDD_3.3V")
	)
	(via
		(at 19.685 32.258)
		(size 0.508)
		(drill 0.254)
		(layers "F.Cu" "B.Cu")
		(net "VDD_3.3V")
	)
	(via
		(at 40.737003 25.542011)
		(size 0.4826)
		(drill 0.20574)
		(layers "F.Cu" "B.Cu")
		(net "VDD_3.3V")
	)
	(via
		(at 18.288 35.0901)
		(size 0.508)
		(drill 0.25654)
		(layers "F.Cu" "B.Cu")
		(net "VDD_3.3V")
	)
	(via
		(at 38.737007 9.541993)
		(size 0.4826)
		(drill 0.20574)
		(layers "F.Cu" "B.Cu")
		(net "VDD_3.3V")
	)
	(via
		(at 21.971 16.4719)
		(size 0.508)
		(drill 0.25654)
		(layers "F.Cu" "B.Cu")
		(net "VDD_3.3V")
	)
	(via
		(at 21.082 36.1315)
		(size 0.508)
		(drill 0.25654)
		(layers "F.Cu" "B.Cu")
		(net "VDD_3.3V")
	)
	(via
		(at 44.736995 14.542008)
		(size 0.4826)
		(drill 0.20574)
		(layers "F.Cu" "B.Cu")
		(net "VDD_3.3V")
	)
	(segment
		(start 21.59 7.874)
		(end 21.59 8.367471)
		(width 0.254)
		(layer "B.Cu")
		(net "VDD_3.3V")
	)
	(segment
		(start 21.336 9.906)
		(end 20.955 9.525)
		(width 0.508)
		(layer "B.Cu")
		(net "VDD_3.3V")
	)
	(segment
		(start 41.2369 25.042114)
		(end 40.737003 25.542011)
		(width 0.2032)
		(layer "B.Cu")
		(net "VDD_3.3V")
	)
	(segment
		(start 43.736997 16.542004)
		(end 44.236894 16.042107)
		(width 0.254)
		(layer "B.Cu")
		(net "VDD_3.3V")
	)
	(segment
		(start 20.1041 28.184932)
		(end 20.1041 30.6959)
		(width 0.508)
		(layer "B.Cu")
		(net "VDD_3.3V")
	)
	(segment
		(start 23.241 16.4719)
		(end 24.511 16.4719)
		(width 0.508)
		(layer "B.Cu")
		(net "VDD_3.3V")
	)
	(segment
		(start 24.765 7.4549)
		(end 23.495 7.4549)
		(width 0.254)
		(layer "B.Cu")
		(net "VDD_3.3V")
	)
	(segment
		(start 20.1041 30.6959)
		(end 19.685 31.115)
		(width 0.508)
		(layer "B.Cu")
		(net "VDD_3.3V")
	)
	(segment
		(start 25.8699 8.509)
		(end 25.8699 9.525)
		(width 0.254)
		(layer "B.Cu")
		(net "VDD_3.3V")
	)
	(segment
		(start 22.225 7.7089)
		(end 21.7551 7.7089)
		(width 0.254)
		(layer "B.Cu")
		(net "VDD_3.3V")
	)
	(segment
		(start 44.237123 12.04214)
		(end 44.237021 12.04214)
		(width 0.254)
		(layer "B.Cu")
		(net "VDD_3.3V")
	)
	(segment
		(start 20.701 23.241)
		(end 20.701 25.019)
		(width 0.508)
		(layer "B.Cu")
		(net "VDD_3.3V")
	)
	(segment
		(start 20.447 26.8859)
		(end 20.066 27.2669)
		(width 0.508)
		(layer "B.Cu")
		(net "VDD_3.3V")
	)
	(segment
		(start 24.892 14.360068)
		(end 24.892 14.097)
		(width 0.508)
		(layer "B.Cu")
		(net "VDD_3.3V")
	)
	(segment
		(start 23.495 11.684)
		(end 23.495 13.1699)
		(width 0.508)
		(layer "B.Cu")
		(net "VDD_3.3V")
	)
	(segment
		(start 25.8699 8.2169)
		(end 25.8699 8.509)
		(width 0.254)
		(layer "B.Cu")
		(net "VDD_3.3V")
	)
	(segment
		(start 5.969 18.669)
		(end 6.731 17.907)
		(width 0.254)
		(layer "B.Cu")
		(net "VDD_3.3V")
	)
	(segment
		(start 44.236843 10.042144)
		(end 44.237021 10.042144)
		(width 0.254)
		(layer "B.Cu")
		(net "VDD_3.3V")
	)
	(segment
		(start 44.736995 12.542012)
		(end 44.237123 12.04214)
		(width 0.254)
		(layer "B.Cu")
		(net "VDD_3.3V")
	)
	(segment
		(start 3.683 18.288)
		(end 4.064 18.669)
		(width 0.254)
		(layer "B.Cu")
		(net "VDD_3.3V")
	)
	(segment
		(start 45.236994 14.042009)
		(end 45.237146 14.042009)
		(width 0.254)
		(layer "B.Cu")
		(net "VDD_3.3V")
	)
	(segment
		(start 20.955 9.525)
		(end 20.955 9.271)
		(width 0.508)
		(layer "B.Cu")
		(net "VDD_3.3V")
	)
	(segment
		(start 20.32 32.258)
		(end 19.685 32.258)
		(width 0.2032)
		(layer "B.Cu")
		(net "VDD_3.3V")
	)
	(segment
		(start 24.892 14.097)
		(end 23.9649 13.1699)
		(width 0.508)
		(layer "B.Cu")
		(net "VDD_3.3V")
	)
	(segment
		(start 19.685 31.115)
		(end 19.685 32.258)
		(width 0.508)
		(layer "B.Cu")
		(net "VDD_3.3V")
	)
	(segment
		(start 22.8219 9.906)
		(end 21.336 9.906)
		(width 0.508)
		(layer "B.Cu")
		(net "VDD_3.3V")
	)
	(segment
		(start 23.3299 10.414)
		(end 22.8219 9.906)
		(width 0.508)
		(layer "B.Cu")
		(net "VDD_3.3V")
	)
	(segment
		(start 25.019 7.7089)
		(end 25.3619 7.7089)
		(width 0.254)
		(layer "B.Cu")
		(net "VDD_3.3V")
	)
	(segment
		(start 40.237029 11.041888)
		(end 39.237031 11.041888)
		(width 0.254)
		(layer "B.Cu")
		(net "VDD_3.3V")
	)
	(segment
		(start 38.737007 9.541993)
		(end 39.237031 10.042017)
		(width 0.254)
		(layer "B.Cu")
		(net "VDD_3.3V")
	)
	(segment
		(start 25.527 15.9639)
		(end 25.527 14.995068)
		(width 0.508)
		(layer "B.Cu")
		(net "VDD_3.3V")
	)
	(segment
		(start 22.3139 30.861)
		(end 21.717 30.861)
		(width 0.2032)
		(layer "B.Cu")
		(net "VDD_3.3V")
	)
	(segment
		(start 21.7551 7.7089)
		(end 21.59 7.874)
		(width 0.254)
		(layer "B.Cu")
		(net "VDD_3.3V")
	)
	(segment
		(start 44.736995 14.542008)
		(end 45.236994 14.042009)
		(width 0.254)
		(layer "B.Cu")
		(net "VDD_3.3V")
	)
	(segment
		(start 20.701 25.019)
		(end 20.701 26.8859)
		(width 0.508)
		(layer "B.Cu")
		(net "VDD_3.3V")
	)
	(segment
		(start 25.527 14.995068)
		(end 24.892 14.360068)
		(width 0.508)
		(layer "B.Cu")
		(net "VDD_3.3V")
	)
	(segment
		(start 24.765 7.4549)
		(end 25.019 7.7089)
		(width 0.254)
		(layer "B.Cu")
		(net "VDD_3.3V")
	)
	(segment
		(start 20.955 9.271)
		(end 20.955 8.5471)
		(width 0.508)
		(layer "B.Cu")
		(net "VDD_3.3V")
	)
	(segment
		(start 44.236996 15.042007)
		(end 44.236894 15.042007)
		(width 0.254)
		(layer "B.Cu")
		(net "VDD_3.3V")
	)
	(segment
		(start 21.59 8.367471)
		(end 21.410371 8.5471)
		(width 0.254)
		(layer "B.Cu")
		(net "VDD_3.3V")
	)
	(segment
		(start 44.236894 13.042011)
		(end 44.236996 13.042011)
		(width 0.254)
		(layer "B.Cu")
		(net "VDD_3.3V")
	)
	(segment
		(start 20.701 26.8859)
		(end 20.447 26.8859)
		(width 0.508)
		(layer "B.Cu")
		(net "VDD_3.3V")
	)
	(segment
		(start 43.736997 10.541991)
		(end 44.236843 10.042144)
		(width 0.254)
		(layer "B.Cu")
		(net "VDD_3.3V")
	)
	(segment
		(start 6.731 17.907)
		(end 6.731 17.145)
		(width 0.254)
		(layer "B.Cu")
		(net "VDD_3.3V")
	)
	(segment
		(start 25.3619 7.7089)
		(end 25.8699 8.2169)
		(width 0.254)
		(layer "B.Cu")
		(net "VDD_3.3V")
	)
	(segment
		(start 20.066 27.2669)
		(end 20.066 28.146832)
		(width 0.508)
		(layer "B.Cu")
		(net "VDD_3.3V")
	)
	(segment
		(start 23.3299 11.303)
		(end 23.3299 10.414)
		(width 0.508)
		(layer "B.Cu")
		(net "VDD_3.3V")
	)
	(segment
		(start 23.9649 13.1699)
		(end 23.495 13.1699)
		(width 0.508)
		(layer "B.Cu")
		(net "VDD_3.3V")
	)
	(segment
		(start 23.495 7.4549)
		(end 22.225 7.7089)
		(width 0.254)
		(layer "B.Cu")
		(net "VDD_3.3V")
	)
	(segment
		(start 40.3606 9.9695)
		(end 40.3606 10.011232)
		(width 0.254)
		(layer "B.Cu")
		(net "VDD_3.3V")
	)
	(segment
		(start 40.237105 25.042114)
		(end 40.237029 25.042114)
		(width 0.254)
		(layer "B.Cu")
		(net "VDD_3.3V")
	)
	(segment
		(start 21.410371 8.5471)
		(end 20.955 8.5471)
		(width 0.254)
		(layer "B.Cu")
		(net "VDD_3.3V")
	)
	(segment
		(start 23.3299 11.303)
		(end 23.3299 11.5189)
		(width 0.508)
		(layer "B.Cu")
		(net "VDD_3.3V")
	)
	(segment
		(start 40.3606 10.011232)
		(end 40.237029 10.134803)
		(width 0.254)
		(layer "B.Cu")
		(net "VDD_3.3V")
	)
	(segment
		(start 40.237029 26.041985)
		(end 40.737003 25.542011)
		(width 0.254)
		(layer "B.Cu")
		(net "VDD_3.3V")
	)
	(segment
		(start 40.737003 25.542011)
		(end 40.237105 25.042114)
		(width 0.254)
		(layer "B.Cu")
		(net "VDD_3.3V")
	)
	(segment
		(start 22.352 13.1699)
		(end 23.495 13.1699)
		(width 0.508)
		(layer "B.Cu")
		(net "VDD_3.3V")
	)
	(segment
		(start 44.736995 15.542006)
		(end 44.236996 15.042007)
		(width 0.254)
		(layer "B.Cu")
		(net "VDD_3.3V")
	)
	(segment
		(start 4.064 18.669)
		(end 5.969 18.669)
		(width 0.254)
		(layer "B.Cu")
		(net "VDD_3.3V")
	)
	(segment
		(start 20.066 28.146832)
		(end 20.1041 28.184932)
		(width 0.508)
		(layer "B.Cu")
		(net "VDD_3.3V")
	)
	(segment
		(start 24.511 16.4719)
		(end 25.019 16.4719)
		(width 0.508)
		(layer "B.Cu")
		(net "VDD_3.3V")
	)
	(segment
		(start 3.683 17.8689)
		(end 3.683 18.288)
		(width 0.254)
		(layer "B.Cu")
		(net "VDD_3.3V")
	)
	(segment
		(start 40.237029 26.042112)
		(end 40.237029 26.041985)
		(width 0.254)
		(layer "B.Cu")
		(net "VDD_3.3V")
	)
	(segment
		(start 21.336 13.1699)
		(end 22.352 13.1699)
		(width 0.508)
		(layer "B.Cu")
		(net "VDD_3.3V")
	)
	(segment
		(start 39.237031 10.042017)
		(end 39.237031 11.041888)
		(width 0.254)
		(layer "B.Cu")
		(net "VDD_3.3V")
	)
	(segment
		(start 23.3299 11.5189)
		(end 23.495 11.684)
		(width 0.508)
		(layer "B.Cu")
		(net "VDD_3.3V")
	)
	(segment
		(start 44.236894 16.042107)
		(end 44.236894 16.042005)
		(width 0.254)
		(layer "B.Cu")
		(net "VDD_3.3V")
	)
	(segment
		(start 21.717 30.861)
		(end 20.32 32.258)
		(width 0.2032)
		(layer "B.Cu")
		(net "VDD_3.3V")
	)
	(segment
		(start 41.237027 25.042114)
		(end 41.2369 25.042114)
		(width 0.2032)
		(layer "B.Cu")
		(net "VDD_3.3V")
	)
	(segment
		(start 25.019 16.4719)
		(end 25.527 15.9639)
		(width 0.508)
		(layer "B.Cu")
		(net "VDD_3.3V")
	)
	(segment
		(start 40.237029 10.134803)
		(end 40.237029 11.041888)
		(width 0.254)
		(layer "B.Cu")
		(net "VDD_3.3V")
	)
	(segment
		(start 40.6781 9.652)
		(end 40.3606 9.9695)
		(width 0.254)
		(layer "B.Cu")
		(net "VDD_3.3V")
	)
	(segment
		(start 44.236996 13.042011)
		(end 44.736995 12.542012)
		(width 0.254)
		(layer "B.Cu")
		(net "VDD_3.3V")
	)
	(segment
		(start 43.18 10.033)
		(end 43.688991 10.541991)
		(width 0.254)
		(layer "In3.Cu")
		(net "VDD_3.3V")
	)
	(segment
		(start 41.402 10.033)
		(end 43.18 10.033)
		(width 0.254)
		(layer "In3.Cu")
		(net "VDD_3.3V")
	)
	(segment
		(start 43.688991 10.541991)
		(end 43.736997 10.541991)
		(width 0.254)
		(layer "In3.Cu")
		(net "VDD_3.3V")
	)
	(segment
		(start 38.737007 9.541993)
		(end 40.910993 9.541993)
		(width 0.254)
		(layer "In3.Cu")
		(net "VDD_3.3V")
	)
	(segment
		(start 40.910993 9.541993)
		(end 41.402 10.033)
		(width 0.254)
		(layer "In3.Cu")
		(net "VDD_3.3V")
	)
	(segment
		(start 45.236994 18.042001)
		(end 44.736995 17.542002)
		(width 0.254)
		(layer "F.Cu")
		(net "VDD_1.8V")
	)
	(segment
		(start 15.2781 39.3827)
		(end 15.2781 38.5826)
		(width 0.2032)
		(layer "F.Cu")
		(net "VDD_1.8V")
	)
	(segment
		(start 17.78 47.498)
		(end 17.78 45.9105)
		(width 0.508)
		(layer "F.Cu")
		(net "VDD_1.8V")
	)
	(segment
		(start 44.236996 18.042001)
		(end 43.736997 17.542002)
		(width 0.254)
		(layer "F.Cu")
		(net "VDD_1.8V")
	)
	(via
		(at 66.675 1.143)
		(size 0.762)
		(drill 0.381)
		(layers "F.Cu" "B.Cu")
		(net "VDD_1.8V")
	)
	(via
		(at 34.544 -1.143)
		(size 0.762)
		(drill 0.381)
		(layers "F.Cu" "B.Cu")
		(net "VDD_1.8V")
	)
	(via
		(at 17.145 42.037)
		(size 0.508)
		(drill 0.25654)
		(layers "F.Cu" "B.Cu")
		(net "VDD_1.8V")
	)
	(via
		(at 43.736997 17.542002)
		(size 0.4826)
		(drill 0.20574)
		(layers "F.Cu" "B.Cu")
		(net "VDD_1.8V")
	)
	(via
		(at 15.2781 38.5826)
		(size 0.508)
		(drill 0.254)
		(layers "F.Cu" "B.Cu")
		(net "VDD_1.8V")
	)
	(via
		(at 44.736995 17.542002)
		(size 0.4826)
		(drill 0.20574)
		(layers "F.Cu" "B.Cu")
		(net "VDD_1.8V")
	)
	(via
		(at 16.51 45.9105)
		(size 0.508)
		(drill 0.25654)
		(layers "F.Cu" "B.Cu")
		(net "VDD_1.8V")
	)
	(via
		(at -1.262888 35.541966)
		(size 0.508)
		(drill 0.2667)
		(layers "F.Cu" "B.Cu")
		(net "VDD_1.8V")
	)
	(via
		(at -1.262888 34.541968)
		(size 0.508)
		(drill 0.254)
		(layers "F.Cu" "B.Cu")
		(net "VDD_1.8V")
	)
	(via
		(at 17.78 45.9105)
		(size 0.508)
		(drill 0.25654)
		(layers "F.Cu" "B.Cu")
		(net "VDD_1.8V")
	)
	(segment
		(start 42.372001 4.695698)
		(end 42.241699 4.826)
		(width 0.254)
		(layer "B.Cu")
		(net "VDD_1.8V")
	)
	(segment
		(start 43.237023 -0.457962)
		(end 43.232299 -0.453238)
		(width 0.254)
		(layer "B.Cu")
		(net "VDD_1.8V")
	)
	(segment
		(start 42.241699 4.826)
		(end 42.241699 5.919699)
		(width 0.254)
		(layer "B.Cu")
		(net "VDD_1.8V")
	)
	(segment
		(start 43.736997 17.542002)
		(end 43.237125 18.041874)
		(width 0.254)
		(layer "B.Cu")
		(net "VDD_1.8V")
	)
	(segment
		(start 43.232299 1.524)
		(end 42.672 1.524)
		(width 0.254)
		(layer "B.Cu")
		(net "VDD_1.8V")
	)
	(segment
		(start 45.236892 17.042003)
		(end 45.236892 17.042105)
		(width 0.254)
		(layer "B.Cu")
		(net "VDD_1.8V")
	)
	(segment
		(start 43.053 7.620025)
		(end 43.232299 7.799324)
		(width 0.254)
		(layer "B.Cu")
		(net "VDD_1.8V")
	)
	(segment
		(start 43.232299 -0.453238)
		(end 43.232299 1.524)
		(width 0.254)
		(layer "B.Cu")
		(net "VDD_1.8V")
	)
	(segment
		(start 42.241699 5.919699)
		(end 43.053 6.731)
		(width 0.254)
		(layer "B.Cu")
		(net "VDD_1.8V")
	)
	(segment
		(start 43.237125 18.041874)
		(end 43.237023 18.041874)
		(width 0.254)
		(layer "B.Cu")
		(net "VDD_1.8V")
	)
	(segment
		(start 42.241699 2.794)
		(end 42.372001 2.924302)
		(width 0.254)
		(layer "B.Cu")
		(net "VDD_1.8V")
	)
	(segment
		(start 42.241699 1.954301)
		(end 42.241699 2.794)
		(width 0.254)
		(layer "B.Cu")
		(net "VDD_1.8V")
	)
	(segment
		(start 44.452007 17.82699)
		(end 44.021985 17.82699)
		(width 0.254)
		(layer "B.Cu")
		(net "VDD_1.8V")
	)
	(segment
		(start 45.236892 17.042105)
		(end 44.736995 17.542002)
		(width 0.254)
		(layer "B.Cu")
		(net "VDD_1.8V")
	)
	(segment
		(start 43.232299 7.799324)
		(end 43.232299 17.037304)
		(width 0.254)
		(layer "B.Cu")
		(net "VDD_1.8V")
	)
	(segment
		(start 42.672 1.524)
		(end 42.241699 1.954301)
		(width 0.254)
		(layer "B.Cu")
		(net "VDD_1.8V")
	)
	(segment
		(start 44.021985 17.82699)
		(end 43.736997 17.542002)
		(width 0.254)
		(layer "B.Cu")
		(net "VDD_1.8V")
	)
	(segment
		(start 42.372001 2.924302)
		(end 42.372001 4.695698)
		(width 0.254)
		(layer "B.Cu")
		(net "VDD_1.8V")
	)
	(segment
		(start 43.053 6.731)
		(end 43.053 7.620025)
		(width 0.254)
		(layer "B.Cu")
		(net "VDD_1.8V")
	)
	(segment
		(start 44.736995 17.542002)
		(end 44.452007 17.82699)
		(width 0.254)
		(layer "B.Cu")
		(net "VDD_1.8V")
	)
	(segment
		(start 43.232299 17.037304)
		(end 43.736997 17.542002)
		(width 0.254)
		(layer "B.Cu")
		(net "VDD_1.8V")
	)
	(segment
		(start 7.493 44.958)
		(end 7.366 46.228)
		(width 0.508)
		(layer "F.Cu")
		(net "VDD_1.5V")
	)
	(segment
		(start 7.62 44.831)
		(end 7.493 44.958)
		(width 0.508)
		(layer "F.Cu")
		(net "VDD_1.5V")
	)
	(segment
		(start 13.6779 39.3827)
		(end 13.6779 38.5826)
		(width 0.2032)
		(layer "F.Cu")
		(net "VDD_1.5V")
	)
	(via
		(at 7.62 44.831)
		(size 0.508)
		(drill 0.254)
		(layers "F.Cu" "B.Cu")
		(net "VDD_1.5V")
	)
	(via
		(at 37.846 24.4729)
		(size 0.508)
		(drill 0.25654)
		(layers "F.Cu" "B.Cu")
		(net "VDD_1.5V")
	)
	(via
		(at 13.6779 38.5826)
		(size 0.508)
		(drill 0.254)
		(layers "F.Cu" "B.Cu")
		(net "VDD_1.5V")
	)
	(via
		(at 37.86886 26.416)
		(size 0.508)
		(drill 0.25654)
		(layers "F.Cu" "B.Cu")
		(net "VDD_1.5V")
	)
	(via
		(at 7.62 43.434)
		(size 0.508)
		(drill 0.254)
		(layers "F.Cu" "B.Cu")
		(net "VDD_1.5V")
	)
	(via
		(at 7.62 42.291)
		(size 0.508)
		(drill 0.254)
		(layers "F.Cu" "B.Cu")
		(net "VDD_1.5V")
	)
	(segment
		(start 3.937 32.258)
		(end 3.429 31.75)
		(width 0.2032)
		(layer "F.Cu")
		(net "VDD_1.2V")
	)
	(segment
		(start 29.21 32.2199)
		(end 29.21 31.496)
		(width 0.254)
		(layer "F.Cu")
		(net "VDD_1.2V")
	)
	(segment
		(start 36.322 32.2199)
		(end 36.322 31.496)
		(width 0.2032)
		(layer "F.Cu")
		(net "VDD_1.2V")
	)
	(segment
		(start 43.236998 9.041994)
		(end 42.736999 8.541995)
		(width 0.254)
		(layer "F.Cu")
		(net "VDD_1.2V")
	)
	(segment
		(start 31.877 31.496)
		(end 31.877 32.2199)
		(width 0.254)
		(layer "F.Cu")
		(net "VDD_1.2V")
	)
	(segment
		(start 6.35 33.147)
		(end 6.096 33.147)
		(width 0.2032)
		(layer "F.Cu")
		(net "VDD_1.2V")
	)
	(segment
		(start 5.207 32.258)
		(end 3.937 32.258)
		(width 0.2032)
		(layer "F.Cu")
		(net "VDD_1.2V")
	)
	(segment
		(start 42.237 9.041994)
		(end 41.737001 8.541995)
		(width 0.254)
		(layer "F.Cu")
		(net "VDD_1.2V")
	)
	(segment
		(start 28.321 32.2199)
		(end 29.21 32.2199)
		(width 0.254)
		(layer "F.Cu")
		(net "VDD_1.2V")
	)
	(segment
		(start 12.3063 36.011104)
		(end 10.865104 36.011104)
		(width 0.2032)
		(layer "F.Cu")
		(net "VDD_1.2V")
	)
	(segment
		(start 34.544 31.496)
		(end 34.544 32.2199)
		(width 0.254)
		(layer "F.Cu")
		(net "VDD_1.2V")
	)
	(segment
		(start 25.8699 32.2199)
		(end 25.781 32.131)
		(width 0.254)
		(layer "F.Cu")
		(net "VDD_1.2V")
	)
	(segment
		(start 34.544 32.2199)
		(end 33.655 32.2199)
		(width 0.254)
		(layer "F.Cu")
		(net "VDD_1.2V")
	)
	(segment
		(start 26.543 32.2199)
		(end 25.8699 32.2199)
		(width 0.254)
		(layer "F.Cu")
		(net "VDD_1.2V")
	)
	(segment
		(start 6.096 33.147)
		(end 5.207 32.258)
		(width 0.2032)
		(layer "F.Cu")
		(net "VDD_1.2V")
	)
	(segment
		(start 31.877 32.2199)
		(end 30.988 32.2199)
		(width 0.254)
		(layer "F.Cu")
		(net "VDD_1.2V")
	)
	(via
		(at 8.8265 35.687)
		(size 0.508)
		(drill 0.2667)
		(layers "F.Cu" "B.Cu")
		(net "VDD_1.2V")
	)
	(via
		(at 41.737001 8.541995)
		(size 0.4826)
		(drill 0.20574)
		(layers "F.Cu" "B.Cu")
		(net "VDD_1.2V")
	)
	(via
		(at 42.736999 8.541995)
		(size 0.4826)
		(drill 0.20574)
		(layers "F.Cu" "B.Cu")
		(net "VDD_1.2V")
	)
	(via
		(at 31.877 31.496)
		(size 0.508)
		(drill 0.254)
		(layers "F.Cu" "B.Cu")
		(net "VDD_1.2V")
	)
	(via
		(at 8.8265 34.417)
		(size 0.508)
		(drill 0.2667)
		(layers "F.Cu" "B.Cu")
		(net "VDD_1.2V")
	)
	(via
		(at 25.781 32.131)
		(size 0.508)
		(drill 0.254)
		(layers "F.Cu" "B.Cu")
		(net "VDD_1.2V")
	)
	(via
		(at 34.544 31.496)
		(size 0.508)
		(drill 0.254)
		(layers "F.Cu" "B.Cu")
		(net "VDD_1.2V")
	)
	(via
		(at 36.322 31.496)
		(size 0.508)
		(drill 0.254)
		(layers "F.Cu" "B.Cu")
		(net "VDD_1.2V")
	)
	(via
		(at 29.21 31.496)
		(size 0.508)
		(drill 0.254)
		(layers "F.Cu" "B.Cu")
		(net "VDD_1.2V")
	)
	(via
		(at 8.8265 33.147)
		(size 0.508)
		(drill 0.254)
		(layers "F.Cu" "B.Cu")
		(net "VDD_1.2V")
	)
	(segment
		(start 39.118007 8.128)
		(end 39.372007 8.382)
		(width 0.254)
		(layer "B.Cu")
		(net "VDD_1.2V")
	)
	(segment
		(start 26.8351 14.233068)
		(end 26.8351 12.652832)
		(width 0.254)
		(layer "B.Cu")
		(net "VDD_1.2V")
	)
	(segment
		(start 38.942188 8.046695)
		(end 39.023493 8.128)
		(width 0.254)
		(layer "B.Cu")
		(net "VDD_1.2V")
	)
	(segment
		(start 27.305 12.192)
		(end 27.686 11.811)
		(width 0.254)
		(layer "B.Cu")
		(net "VDD_1.2V")
	)
	(segment
		(start 27.295932 12.192)
		(end 27.305 12.192)
		(width 0.254)
		(layer "B.Cu")
		(net "VDD_1.2V")
	)
	(segment
		(start 26.289 30.226)
		(end 26.289 27.051)
		(width 0.254)
		(layer "B.Cu")
		(net "VDD_1.2V")
	)
	(segment
		(start 25.781 32.131)
		(end 25.781 30.734)
		(width 0.254)
		(layer "B.Cu")
		(net "VDD_1.2V")
	)
	(segment
		(start 28.057932 9.779)
		(end 28.829 9.779)
		(width 0.254)
		(layer "B.Cu")
		(net "VDD_1.2V")
	)
	(segment
		(start 35.052 5.715)
		(end 37.465 5.715)
		(width 0.254)
		(layer "B.Cu")
		(net "VDD_1.2V")
	)
	(segment
		(start 41.237027 8.042148)
		(end 41.736874 8.541995)
		(width 0.254)
		(layer "B.Cu")
		(net "VDD_1.2V")
	)
	(segment
		(start 37.909373 7.798562)
		(end 38.157506 8.046695)
		(width 0.254)
		(layer "B.Cu")
		(net "VDD_1.2V")
	)
	(segment
		(start 25.781 30.734)
		(end 26.289 30.226)
		(width 0.254)
		(layer "B.Cu")
		(net "VDD_1.2V")
	)
	(segment
		(start 39.372007 8.763)
		(end 39.626007 9.017)
		(width 0.254)
		(layer "B.Cu")
		(net "VDD_1.2V")
	)
	(segment
		(start 27.686 11.811)
		(end 27.686 10.150932)
		(width 0.254)
		(layer "B.Cu")
		(net "VDD_1.2V")
	)
	(segment
		(start 38.157506 8.046695)
		(end 38.942188 8.046695)
		(width 0.254)
		(layer "B.Cu")
		(net "VDD_1.2V")
	)
	(segment
		(start 26.289 27.051)
		(end 25.273 26.035)
		(width 0.254)
		(layer "B.Cu")
		(net "VDD_1.2V")
	)
	(segment
		(start 29.591 9.017)
		(end 33.274 9.017)
		(width 0.254)
		(layer "B.Cu")
		(net "VDD_1.2V")
	)
	(segment
		(start 42.236847 8.042148)
		(end 42.237025 8.042148)
		(width 0.254)
		(layer "B.Cu")
		(net "VDD_1.2V")
	)
	(segment
		(start 39.372007 8.382)
		(end 39.372007 8.763)
		(width 0.254)
		(layer "B.Cu")
		(net "VDD_1.2V")
	)
	(segment
		(start 33.274 9.017)
		(end 34.29 8.001)
		(width 0.254)
		(layer "B.Cu")
		(net "VDD_1.2V")
	)
	(segment
		(start 34.29 6.477)
		(end 35.052 5.715)
		(width 0.254)
		(layer "B.Cu")
		(net "VDD_1.2V")
	)
	(segment
		(start 25.273 19.05)
		(end 26.9621 17.3609)
		(width 0.254)
		(layer "B.Cu")
		(net "VDD_1.2V")
	)
	(segment
		(start 41.736874 8.541995)
		(end 41.737001 8.541995)
		(width 0.254)
		(layer "B.Cu")
		(net "VDD_1.2V")
	)
	(segment
		(start 26.9621 17.3609)
		(end 26.9621 14.360068)
		(width 0.254)
		(layer "B.Cu")
		(net "VDD_1.2V")
	)
	(segment
		(start 26.8351 12.652832)
		(end 27.295932 12.192)
		(width 0.254)
		(layer "B.Cu")
		(net "VDD_1.2V")
	)
	(segment
		(start 39.626007 9.017)
		(end 41.261995 9.017)
		(width 0.254)
		(layer "B.Cu")
		(net "VDD_1.2V")
	)
	(segment
		(start 41.261995 9.017)
		(end 41.737001 8.541995)
		(width 0.254)
		(layer "B.Cu")
		(net "VDD_1.2V")
	)
	(segment
		(start 34.29 8.001)
		(end 34.29 6.477)
		(width 0.254)
		(layer "B.Cu")
		(net "VDD_1.2V")
	)
	(segment
		(start 42.736872 8.541995)
		(end 42.237025 8.042148)
		(width 0.254)
		(layer "B.Cu")
		(net "VDD_1.2V")
	)
	(segment
		(start 26.9621 14.360068)
		(end 26.8351 14.233068)
		(width 0.254)
		(layer "B.Cu")
		(net "VDD_1.2V")
	)
	(segment
		(start 39.023493 8.128)
		(end 39.118007 8.128)
		(width 0.254)
		(layer "B.Cu")
		(net "VDD_1.2V")
	)
	(segment
		(start 42.736999 8.541995)
		(end 42.736872 8.541995)
		(width 0.254)
		(layer "B.Cu")
		(net "VDD_1.2V")
	)
	(segment
		(start 37.909373 6.159373)
		(end 37.909373 7.798562)
		(width 0.254)
		(layer "B.Cu")
		(net "VDD_1.2V")
	)
	(segment
		(start 37.465 5.715)
		(end 37.909373 6.159373)
		(width 0.254)
		(layer "B.Cu")
		(net "VDD_1.2V")
	)
	(segment
		(start 27.686 10.150932)
		(end 28.057932 9.779)
		(width 0.254)
		(layer "B.Cu")
		(net "VDD_1.2V")
	)
	(segment
		(start 41.737001 8.541995)
		(end 42.236847 8.042148)
		(width 0.254)
		(layer "B.Cu")
		(net "VDD_1.2V")
	)
	(segment
		(start 28.829 9.779)
		(end 29.591 9.017)
		(width 0.254)
		(layer "B.Cu")
		(net "VDD_1.2V")
	)
	(segment
		(start 25.273 26.035)
		(end 25.273 19.05)
		(width 0.254)
		(layer "B.Cu")
		(net "VDD_1.2V")
	)
	(segment
		(start 39.237006 23.041991)
		(end 38.737007 23.54199)
		(width 0.254)
		(layer "F.Cu")
		(net "VDDA_TS0")
	)
	(via
		(at 38.737007 23.54199)
		(size 0.4826)
		(drill 0.20574)
		(layers "F.Cu" "B.Cu")
		(net "VDDA_TS0")
	)
	(via
		(at 34.575547 24.738305)
		(size 0.762)
		(drill 0.381)
		(layers "F.Cu" "B.Cu")
		(net "VDDA_TS0")
	)
	(segment
		(start 36.6649 24.083366)
		(end 36.6649 23.702366)
		(width 0.127)
		(layer "B.Cu")
		(net "VDDA_TS0")
	)
	(segment
		(start 39.237006 23.041991)
		(end 38.737007 23.54199)
		(width 0.254)
		(layer "B.Cu")
		(net "VDDA_TS0")
	)
	(segment
		(start 37.7698 23.4569)
		(end 37.846 23.5331)
		(width 0.127)
		(layer "B.Cu")
		(net "VDDA_TS0")
	)
	(segment
		(start 37.85489 23.54199)
		(end 37.846 23.5331)
		(width 0.254)
		(layer "B.Cu")
		(net "VDDA_TS0")
	)
	(segment
		(start 40.236902 23.041991)
		(end 39.237006 23.041991)
		(width 0.254)
		(layer "B.Cu")
		(net "VDDA_TS0")
	)
	(segment
		(start 35.082251 24.2316)
		(end 36.516666 24.2316)
		(width 0.127)
		(layer "B.Cu")
		(net "VDDA_TS0")
	)
	(segment
		(start 36.6649 23.702366)
		(end 36.910366 23.4569)
		(width 0.127)
		(layer "B.Cu")
		(net "VDDA_TS0")
	)
	(segment
		(start 38.737007 23.54199)
		(end 39.236879 24.041862)
		(width 0.254)
		(layer "B.Cu")
		(net "VDDA_TS0")
	)
	(segment
		(start 34.575547 24.738305)
		(end 35.082251 24.2316)
		(width 0.127)
		(layer "B.Cu")
		(net "VDDA_TS0")
	)
	(segment
		(start 36.516666 24.2316)
		(end 36.6649 24.083366)
		(width 0.127)
		(layer "B.Cu")
		(net "VDDA_TS0")
	)
	(segment
		(start 39.236879 24.041862)
		(end 39.237031 24.041862)
		(width 0.254)
		(layer "B.Cu")
		(net "VDDA_TS0")
	)
	(segment
		(start 36.910366 23.4569)
		(end 37.7698 23.4569)
		(width 0.127)
		(layer "B.Cu")
		(net "VDDA_TS0")
	)
	(segment
		(start 38.737007 23.54199)
		(end 37.85489 23.54199)
		(width 0.254)
		(layer "B.Cu")
		(net "VDDA_TS0")
	)
	(segment
		(start 61.737011 17.542002)
		(end 61.237012 18.042001)
		(width 0.254)
		(layer "F.Cu")
		(net "VDDA_PLL")
	)
	(segment
		(start 44.236996 25.042012)
		(end 43.736997 25.542011)
		(width 0.254)
		(layer "F.Cu")
		(net "VDDA_PLL")
	)
	(segment
		(start 44.236996 22.041993)
		(end 43.736997 22.541992)
		(width 0.254)
		(layer "F.Cu")
		(net "VDDA_PLL")
	)
	(segment
		(start 44.236996 23.041991)
		(end 43.736997 23.54199)
		(width 0.254)
		(layer "F.Cu")
		(net "VDDA_PLL")
	)
	(segment
		(start 53.237003 12.041988)
		(end 52.737004 11.541989)
		(width 0.254)
		(layer "F.Cu")
		(net "VDDA_PLL")
	)
	(via
		(at 43.736997 23.54199)
		(size 0.4826)
		(drill 0.20574)
		(layers "F.Cu" "B.Cu")
		(net "VDDA_PLL")
	)
	(via
		(at 43.736997 25.542011)
		(size 0.4826)
		(drill 0.20574)
		(layers "F.Cu" "B.Cu")
		(net "VDDA_PLL")
	)
	(via
		(at 43.736997 22.541992)
		(size 0.4826)
		(drill 0.20574)
		(layers "F.Cu" "B.Cu")
		(net "VDDA_PLL")
	)
	(via
		(at 52.737004 11.541989)
		(size 0.4826)
		(drill 0.20574)
		(layers "F.Cu" "B.Cu")
		(net "VDDA_PLL")
	)
	(via
		(at 37.592 28.702)
		(size 0.508)
		(drill 0.25654)
		(layers "F.Cu" "B.Cu")
		(net "VDDA_PLL")
	)
	(via
		(at 61.737011 17.542002)
		(size 0.4826)
		(drill 0.20574)
		(layers "F.Cu" "B.Cu")
		(net "VDDA_PLL")
	)
	(via
		(at 37.592 27.559)
		(size 0.508)
		(drill 0.25654)
		(layers "F.Cu" "B.Cu")
		(net "VDDA_PLL")
	)
	(via
		(at 39.751 30.607)
		(size 0.762)
		(drill 0.381)
		(layers "F.Cu" "B.Cu")
		(net "VDDA_PLL")
	)
	(segment
		(start 39.751 30.607)
		(end 39.116 29.972)
		(width 0.254)
		(layer "B.Cu")
		(net "VDDA_PLL")
	)
	(segment
		(start 43.236998 23.041991)
		(end 43.236896 23.041991)
		(width 0.254)
		(layer "B.Cu")
		(net "VDDA_PLL")
	)
	(segment
		(start 39.116 29.972)
		(end 39.116 29.21)
		(width 0.254)
		(layer "B.Cu")
		(net "VDDA_PLL")
	)
	(segment
		(start 43.736997 22.541992)
		(end 43.236998 22.041993)
		(width 0.254)
		(layer "B.Cu")
		(net "VDDA_PLL")
	)
	(segment
		(start 61.237114 17.042105)
		(end 61.237114 17.042003)
		(width 0.254)
		(layer "B.Cu")
		(net "VDDA_PLL")
	)
	(segment
		(start 38.608 28.702)
		(end 37.592 28.702)
		(width 0.254)
		(layer "B.Cu")
		(net "VDDA_PLL")
	)
	(segment
		(start 39.116 29.21)
		(end 38.608 28.702)
		(width 0.254)
		(layer "B.Cu")
		(net "VDDA_PLL")
	)
	(segment
		(start 43.236972 25.041987)
		(end 43.236896 25.041987)
		(width 0.254)
		(layer "B.Cu")
		(net "VDDA_PLL")
	)
	(segment
		(start 43.736997 23.54199)
		(end 43.236998 23.041991)
		(width 0.254)
		(layer "B.Cu")
		(net "VDDA_PLL")
	)
	(segment
		(start 53.237003 11.04199)
		(end 53.237003 11.041888)
		(width 0.254)
		(layer "B.Cu")
		(net "VDDA_PLL")
	)
	(segment
		(start 43.736997 25.542011)
		(end 43.236972 25.041987)
		(width 0.254)
		(layer "B.Cu")
		(net "VDDA_PLL")
	)
	(segment
		(start 43.236998 22.041993)
		(end 43.236896 22.041993)
		(width 0.254)
		(layer "B.Cu")
		(net "VDDA_PLL")
	)
	(segment
		(start 52.737004 11.541989)
		(end 53.237003 11.04199)
		(width 0.254)
		(layer "B.Cu")
		(net "VDDA_PLL")
	)
	(segment
		(start 61.737011 17.542002)
		(end 61.237114 17.042105)
		(width 0.254)
		(layer "B.Cu")
		(net "VDDA_PLL")
	)
	(segment
		(start 58.736992 8.541995)
		(end 58.236993 9.041994)
		(width 0.254)
		(layer "F.Cu")
		(net "VDDA_PCIE0")
	)
	(segment
		(start 59.73699 8.541995)
		(end 59.236991 9.041994)
		(width 0.254)
		(layer "F.Cu")
		(net "VDDA_PCIE0")
	)
	(segment
		(start 57.736994 8.541995)
		(end 57.236995 9.041994)
		(width 0.254)
		(layer "F.Cu")
		(net "VDDA_PCIE0")
	)
	(via
		(at 58.736992 8.541995)
		(size 0.4826)
		(drill 0.20574)
		(layers "F.Cu" "B.Cu")
		(net "VDDA_PCIE0")
	)
	(via
		(at 53.737002 8.541995)
		(size 0.508)
		(drill 0.25654)
		(layers "F.Cu" "B.Cu")
		(net "VDDA_PCIE0")
	)
	(via
		(at 54.737 7.541997)
		(size 0.508)
		(drill 0.25654)
		(layers "F.Cu" "B.Cu")
		(net "VDDA_PCIE0")
	)
	(via
		(at 61.736986 4.542003)
		(size 0.4826)
		(drill 0.20574)
		(layers "F.Cu" "B.Cu")
		(net "VDDA_PCIE0")
	)
	(via
		(at 64.516 1.524)
		(size 0.762)
		(drill 0.381)
		(layers "F.Cu" "B.Cu")
		(net "VDDA_PCIE0")
	)
	(via
		(at 57.736994 8.541995)
		(size 0.4826)
		(drill 0.20574)
		(layers "F.Cu" "B.Cu")
		(net "VDDA_PCIE0")
	)
	(via
		(at 60.736988 5.542001)
		(size 0.4826)
		(drill 0.20574)
		(layers "F.Cu" "B.Cu")
		(net "VDDA_PCIE0")
	)
	(via
		(at 59.73699 8.541995)
		(size 0.4826)
		(drill 0.20574)
		(layers "F.Cu" "B.Cu")
		(net "VDDA_PCIE0")
	)
	(segment
		(start 59.73699 8.541995)
		(end 60.236837 8.042148)
		(width 0.254)
		(layer "B.Cu")
		(net "VDDA_PCIE0")
	)
	(segment
		(start 57.736994 8.541995)
		(end 58.236841 8.042148)
		(width 0.254)
		(layer "B.Cu")
		(net "VDDA_PCIE0")
	)
	(segment
		(start 59.236839 8.042148)
		(end 59.236991 8.042148)
		(width 0.254)
		(layer "B.Cu")
		(net "VDDA_PCIE0")
	)
	(segment
		(start 60.237116 9.042019)
		(end 60.236989 9.041892)
		(width 0.254)
		(layer "B.Cu")
		(net "VDDA_PCIE0")
	)
	(segment
		(start 60.736988 5.784088)
		(end 61.5569 6.604)
		(width 0.254)
		(layer "B.Cu")
		(net "VDDA_PCIE0")
	)
	(segment
		(start 58.736992 8.541995)
		(end 59.236839 8.042148)
		(width 0.254)
		(layer "B.Cu")
		(net "VDDA_PCIE0")
	)
	(segment
		(start 64.135 1.905)
		(end 63.119 1.905)
		(width 0.254)
		(layer "B.Cu")
		(net "VDDA_PCIE0")
	)
	(segment
		(start 53.80863 8.427542)
		(end 53.80863 8.260664)
		(width 0.381)
		(layer "B.Cu")
		(net "VDDA_PCIE0")
	)
	(segment
		(start 64.516 1.524)
		(end 64.135 1.905)
		(width 0.254)
		(layer "B.Cu")
		(net "VDDA_PCIE0")
	)
	(segment
		(start 61.236885 9.042019)
		(end 60.237116 9.042019)
		(width 0.254)
		(layer "B.Cu")
		(net "VDDA_PCIE0")
	)
	(segment
		(start 63.119 1.905)
		(end 61.6839 3.3401)
		(width 0.254)
		(layer "B.Cu")
		(net "VDDA_PCIE0")
	)
	(segment
		(start 60.236887 9.041892)
		(end 59.73699 8.541995)
		(width 0.254)
		(layer "B.Cu")
		(net "VDDA_PCIE0")
	)
	(segment
		(start 58.236841 8.042148)
		(end 58.236993 8.042148)
		(width 0.254)
		(layer "B.Cu")
		(net "VDDA_PCIE0")
	)
	(segment
		(start 60.236989 9.041892)
		(end 60.236887 9.041892)
		(width 0.254)
		(layer "B.Cu")
		(net "VDDA_PCIE0")
	)
	(segment
		(start 61.736986 4.542003)
		(end 61.6839 4.488917)
		(width 0.254)
		(layer "B.Cu")
		(net "VDDA_PCIE0")
	)
	(segment
		(start 53.737002 8.49917)
		(end 53.80863 8.427542)
		(width 0.381)
		(layer "B.Cu")
		(net "VDDA_PCIE0")
	)
	(segment
		(start 54.527298 7.541997)
		(end 54.737 7.541997)
		(width 0.381)
		(layer "B.Cu")
		(net "VDDA_PCIE0")
	)
	(segment
		(start 53.80863 8.260664)
		(end 54.527298 7.541997)
		(width 0.381)
		(layer "B.Cu")
		(net "VDDA_PCIE0")
	)
	(segment
		(start 60.736988 5.542001)
		(end 60.736988 5.784088)
		(width 0.254)
		(layer "B.Cu")
		(net "VDDA_PCIE0")
	)
	(segment
		(start 61.6839 3.3401)
		(end 61.6839 3.556)
		(width 0.254)
		(layer "B.Cu")
		(net "VDDA_PCIE0")
	)
	(segment
		(start 61.6839 4.488917)
		(end 61.6839 3.556)
		(width 0.254)
		(layer "B.Cu")
		(net "VDDA_PCIE0")
	)
	(segment
		(start 53.737002 8.541995)
		(end 53.737002 8.49917)
		(width 0.381)
		(layer "B.Cu")
		(net "VDDA_PCIE0")
	)
	(segment
		(start 60.236837 8.042148)
		(end 60.236989 8.042148)
		(width 0.254)
		(layer "B.Cu")
		(net "VDDA_PCIE0")
	)
	(segment
		(start 17.126001 37.610999)
		(end 16.6497 37.610999)
		(width 0.14732)
		(layer "F.Cu")
		(net "PSU_I2C_SDA")
	)
	(segment
		(start 3.302 34.5821)
		(end 3.302 35.306)
		(width 0.14732)
		(layer "F.Cu")
		(net "PSU_I2C_SDA")
	)
	(segment
		(start 25.527 12.827)
		(end 26.6319 12.827)
		(width 0.14732)
		(layer "F.Cu")
		(net "PSU_I2C_SDA")
	)
	(segment
		(start 17.653 37.43071)
		(end 17.30629 37.43071)
		(width 0.14732)
		(layer "F.Cu")
		(net "PSU_I2C_SDA")
	)
	(segment
		(start 17.30629 37.43071)
		(end 17.126001 37.610999)
		(width 0.14732)
		(layer "F.Cu")
		(net "PSU_I2C_SDA")
	)
	(segment
		(start 4.064 36.703)
		(end 3.302 35.941)
		(width 0.14732)
		(layer "F.Cu")
		(net "PSU_I2C_SDA")
	)
	(segment
		(start 4.064 36.83)
		(end 4.064 36.703)
		(width 0.14732)
		(layer "F.Cu")
		(net "PSU_I2C_SDA")
	)
	(segment
		(start 27.570989 37.349989)
		(end 27.178 36.957)
		(width 0.14732)
		(layer "F.Cu")
		(net "PSU_I2C_SDA")
	)
	(segment
		(start 28.1686 37.349989)
		(end 27.570989 37.349989)
		(width 0.14732)
		(layer "F.Cu")
		(net "PSU_I2C_SDA")
	)
	(segment
		(start 3.302 35.941)
		(end 3.302 35.306)
		(width 0.14732)
		(layer "F.Cu")
		(net "PSU_I2C_SDA")
	)
	(via
		(at 17.653 37.43071)
		(size 0.508)
		(drill 0.2667)
		(layers "F.Cu" "B.Cu")
		(net "PSU_I2C_SDA")
	)
	(via
		(at 25.527 12.827)
		(size 0.508)
		(drill 0.254)
		(layers "F.Cu" "B.Cu")
		(net "PSU_I2C_SDA")
	)
	(via
		(at 15.24 48.7045)
		(size 0.508)
		(drill 0.25654)
		(layers "F.Cu" "B.Cu")
		(net "PSU_I2C_SDA")
	)
	(via
		(at 29.4132 29.7434)
		(size 0.4572)
		(drill 0.20574)
		(layers "F.Cu" "B.Cu")
		(net "PSU_I2C_SDA")
	)
	(via
		(at 3.302 35.306)
		(size 0.508)
		(drill 0.254)
		(layers "F.Cu" "B.Cu")
		(net "PSU_I2C_SDA")
	)
	(via
		(at 27.178 36.957)
		(size 0.508)
		(drill 0.254)
		(layers "F.Cu" "B.Cu")
		(net "PSU_I2C_SDA")
	)
	(segment
		(start 30.592395 28.702)
		(end 30.4546 28.702)
		(width 0.12065)
		(layer "In1.Cu")
		(net "PSU_I2C_SDA")
	)
	(segment
		(start 31.245988 28.048407)
		(end 30.592395 28.702)
		(width 0.12065)
		(layer "In1.Cu")
		(net "PSU_I2C_SDA")
	)
	(segment
		(start 30.4546 28.702)
		(end 29.4132 29.7434)
		(width 0.12065)
		(layer "In1.Cu")
		(net "PSU_I2C_SDA")
	)
	(segment
		(start 17.907 36.095254)
		(end 17.907 37.17671)
		(width 0.12065)
		(layer "In6.Cu")
		(net "PSU_I2C_SDA")
	)
	(segment
		(start 17.51965 37.29736)
		(end 17.51965 34.082203)
		(width 0.12065)
		(layer "In6.Cu")
		(net "PSU_I2C_SDA")
	)
	(segment
		(start 17.399 33.147)
		(end 16.068675 31.816675)
		(width 0.12065)
		(layer "In6.Cu")
		(net "PSU_I2C_SDA")
	)
	(segment
		(start 26.509929 38.160325)
		(end 26.408228 38.160325)
		(width 0.12065)
		(layer "In6.Cu")
		(net "PSU_I2C_SDA")
	)
	(segment
		(start 7.112 34.036)
		(end 4.191 34.036)
		(width 0.12065)
		(layer "In6.Cu")
		(net "PSU_I2C_SDA")
	)
	(segment
		(start 23.24735 34.87895)
		(end 23.24735 34.55035)
		(width 0.12065)
		(layer "In6.Cu")
		(net "PSU_I2C_SDA")
	)
	(segment
		(start 17.399 33.961553)
		(end 17.399 33.147)
		(width 0.12065)
		(layer "In6.Cu")
		(net "PSU_I2C_SDA")
	)
	(segment
		(start 17.653 37.43071)
		(end 17.51965 37.29736)
		(width 0.12065)
		(layer "In6.Cu")
		(net "PSU_I2C_SDA")
	)
	(segment
		(start 28.503829 34.210625)
		(end 29.651325 33.063129)
		(width 0.12065)
		(layer "In6.Cu")
		(net "PSU_I2C_SDA")
	)
	(segment
		(start 23.513618 37.409171)
		(end 23.301325 37.196878)
		(width 0.12065)
		(layer "In6.Cu")
		(net "PSU_I2C_SDA")
	)
	(segment
		(start 23.301325 37.196878)
		(end 23.301325 34.932925)
		(width 0.12065)
		(layer "In6.Cu")
		(net "PSU_I2C_SDA")
	)
	(segment
		(start 26.341553 38.227)
		(end 24.9285 38.227)
		(width 0.12065)
		(layer "In6.Cu")
		(net "PSU_I2C_SDA")
	)
	(segment
		(start 26.768425 37.800128)
		(end 26.768425 37.901829)
		(width 0.12065)
		(layer "In6.Cu")
		(net "PSU_I2C_SDA")
	)
	(segment
		(start 22.86 34.163)
		(end 19.431 34.163)
		(width 0.12065)
		(layer "In6.Cu")
		(net "PSU_I2C_SDA")
	)
	(segment
		(start 27.178 36.957)
		(end 26.863675 37.271325)
		(width 0.12065)
		(layer "In6.Cu")
		(net "PSU_I2C_SDA")
	)
	(segment
		(start 26.768425 37.901829)
		(end 26.509929 38.160325)
		(width 0.12065)
		(layer "In6.Cu")
		(net "PSU_I2C_SDA")
	)
	(segment
		(start 29.651325 29.981525)
		(end 29.4132 29.7434)
		(width 0.12065)
		(layer "In6.Cu")
		(net "PSU_I2C_SDA")
	)
	(segment
		(start 23.815675 37.409171)
		(end 23.513618 37.409171)
		(width 0.12065)
		(layer "In6.Cu")
		(net "PSU_I2C_SDA")
	)
	(segment
		(start 17.907 37.17671)
		(end 17.653 37.43071)
		(width 0.12065)
		(layer "In6.Cu")
		(net "PSU_I2C_SDA")
	)
	(segment
		(start 24.698325 37.409171)
		(end 24.439829 37.150675)
		(width 0.12065)
		(layer "In6.Cu")
		(net "PSU_I2C_SDA")
	)
	(segment
		(start 24.439829 37.150675)
		(end 24.074171 37.150675)
		(width 0.12065)
		(layer "In6.Cu")
		(net "PSU_I2C_SDA")
	)
	(segment
		(start 19.431 34.163)
		(end 18.729325 34.864675)
		(width 0.12065)
		(layer "In6.Cu")
		(net "PSU_I2C_SDA")
	)
	(segment
		(start 18.729325 34.864675)
		(end 18.729325 35.272929)
		(width 0.12065)
		(layer "In6.Cu")
		(net "PSU_I2C_SDA")
	)
	(segment
		(start 26.797 35.305975)
		(end 27.632 34.470975)
		(width 0.12065)
		(layer "In6.Cu")
		(net "PSU_I2C_SDA")
	)
	(segment
		(start 26.863675 37.704878)
		(end 26.768425 37.800128)
		(width 0.12065)
		(layer "In6.Cu")
		(net "PSU_I2C_SDA")
	)
	(segment
		(start 9.331325 31.816675)
		(end 7.112 34.036)
		(width 0.12065)
		(layer "In6.Cu")
		(net "PSU_I2C_SDA")
	)
	(segment
		(start 17.51965 34.082203)
		(end 17.399 33.961553)
		(width 0.12065)
		(layer "In6.Cu")
		(net "PSU_I2C_SDA")
	)
	(segment
		(start 18.729325 35.272929)
		(end 17.907 36.095254)
		(width 0.12065)
		(layer "In6.Cu")
		(net "PSU_I2C_SDA")
	)
	(segment
		(start 26.797 36.576)
		(end 26.797 35.305975)
		(width 0.12065)
		(layer "In6.Cu")
		(net "PSU_I2C_SDA")
	)
	(segment
		(start 3.302 34.925)
		(end 3.302 35.306)
		(width 0.12065)
		(layer "In6.Cu")
		(net "PSU_I2C_SDA")
	)
	(segment
		(start 23.24735 34.55035)
		(end 22.86 34.163)
		(width 0.12065)
		(layer "In6.Cu")
		(net "PSU_I2C_SDA")
	)
	(segment
		(start 24.9285 38.227)
		(end 24.698325 37.996825)
		(width 0.12065)
		(layer "In6.Cu")
		(net "PSU_I2C_SDA")
	)
	(segment
		(start 24.074171 37.150675)
		(end 23.815675 37.409171)
		(width 0.12065)
		(layer "In6.Cu")
		(net "PSU_I2C_SDA")
	)
	(segment
		(start 27.71742 34.470975)
		(end 27.97777 34.210625)
		(width 0.12065)
		(layer "In6.Cu")
		(net "PSU_I2C_SDA")
	)
	(segment
		(start 27.178 36.957)
		(end 26.797 36.576)
		(width 0.12065)
		(layer "In6.Cu")
		(net "PSU_I2C_SDA")
	)
	(segment
		(start 4.191 34.036)
		(end 3.302 34.925)
		(width 0.12065)
		(layer "In6.Cu")
		(net "PSU_I2C_SDA")
	)
	(segment
		(start 26.863675 37.271325)
		(end 26.863675 37.704878)
		(width 0.12065)
		(layer "In6.Cu")
		(net "PSU_I2C_SDA")
	)
	(segment
		(start 24.698325 37.996825)
		(end 24.698325 37.409171)
		(width 0.12065)
		(layer "In6.Cu")
		(net "PSU_I2C_SDA")
	)
	(segment
		(start 27.97777 34.210625)
		(end 28.503829 34.210625)
		(width 0.12065)
		(layer "In6.Cu")
		(net "PSU_I2C_SDA")
	)
	(segment
		(start 23.301325 34.932925)
		(end 23.24735 34.87895)
		(width 0.12065)
		(layer "In6.Cu")
		(net "PSU_I2C_SDA")
	)
	(segment
		(start 16.068675 31.816675)
		(end 9.331325 31.816675)
		(width 0.12065)
		(layer "In6.Cu")
		(net "PSU_I2C_SDA")
	)
	(segment
		(start 29.651325 33.063129)
		(end 29.651325 29.981525)
		(width 0.12065)
		(layer "In6.Cu")
		(net "PSU_I2C_SDA")
	)
	(segment
		(start 27.632 34.470975)
		(end 27.71742 34.470975)
		(width 0.12065)
		(layer "In6.Cu")
		(net "PSU_I2C_SDA")
	)
	(segment
		(start 26.408228 38.160325)
		(end 26.341553 38.227)
		(width 0.12065)
		(layer "In6.Cu")
		(net "PSU_I2C_SDA")
	)
	(segment
		(start 25.527 12.827)
		(end 26.162 13.462)
		(width 0.12065)
		(layer "In7.Cu")
		(net "PSU_I2C_SDA")
	)
	(segment
		(start 29.4132 27.0002)
		(end 29.4132 29.7434)
		(width 0.12065)
		(layer "In7.Cu")
		(net "PSU_I2C_SDA")
	)
	(segment
		(start 26.162 18.333745)
		(end 28.488996 20.660741)
		(width 0.12065)
		(layer "In7.Cu")
		(net "PSU_I2C_SDA")
	)
	(segment
		(start 16.002 43.307)
		(end 16.002 46.609)
		(width 0.12065)
		(layer "In7.Cu")
		(net "PSU_I2C_SDA")
	)
	(segment
		(start 28.488996 20.660741)
		(end 28.788741 20.660741)
		(width 0.12065)
		(layer "In7.Cu")
		(net "PSU_I2C_SDA")
	)
	(segment
		(start 16.002 40.386)
		(end 16.51 40.894)
		(width 0.12065)
		(layer "In7.Cu")
		(net "PSU_I2C_SDA")
	)
	(segment
		(start 26.162 13.462)
		(end 26.162 18.333745)
		(width 0.12065)
		(layer "In7.Cu")
		(net "PSU_I2C_SDA")
	)
	(segment
		(start 16.51 42.799)
		(end 16.002 43.307)
		(width 0.12065)
		(layer "In7.Cu")
		(net "PSU_I2C_SDA")
	)
	(segment
		(start 16.002 39.624)
		(end 16.002 40.386)
		(width 0.12065)
		(layer "In7.Cu")
		(net "PSU_I2C_SDA")
	)
	(segment
		(start 17.653 37.973)
		(end 16.002 39.624)
		(width 0.12065)
		(layer "In7.Cu")
		(net "PSU_I2C_SDA")
	)
	(segment
		(start 28.829 26.416)
		(end 29.4132 27.0002)
		(width 0.12065)
		(layer "In7.Cu")
		(net "PSU_I2C_SDA")
	)
	(segment
		(start 28.829 21.457945)
		(end 28.829 26.416)
		(width 0.12065)
		(layer "In7.Cu")
		(net "PSU_I2C_SDA")
	)
	(segment
		(start 28.788741 20.660741)
		(end 29.017341 20.889341)
		(width 0.12065)
		(layer "In7.Cu")
		(net "PSU_I2C_SDA")
	)
	(segment
		(start 16.002 46.609)
		(end 15.24 47.371)
		(width 0.12065)
		(layer "In7.Cu")
		(net "PSU_I2C_SDA")
	)
	(segment
		(start 17.653 37.43071)
		(end 17.653 37.973)
		(width 0.12065)
		(layer "In7.Cu")
		(net "PSU_I2C_SDA")
	)
	(segment
		(start 29.017341 21.269604)
		(end 28.829 21.457945)
		(width 0.12065)
		(layer "In7.Cu")
		(net "PSU_I2C_SDA")
	)
	(segment
		(start 16.51 40.894)
		(end 16.51 42.799)
		(width 0.12065)
		(layer "In7.Cu")
		(net "PSU_I2C_SDA")
	)
	(segment
		(start 29.017341 20.889341)
		(end 29.017341 21.269604)
		(width 0.12065)
		(layer "In7.Cu")
		(net "PSU_I2C_SDA")
	)
	(segment
		(start 15.24 47.371)
		(end 15.24 48.7045)
		(width 0.12065)
		(layer "In7.Cu")
		(net "PSU_I2C_SDA")
	)
	(segment
		(start 17.272 36.957)
		(end 18.406974 36.957)
		(width 0.14732)
		(layer "F.Cu")
		(net "PSU_I2C_SCL")
	)
	(segment
		(start 19.558 36.83)
		(end 20.193 36.83)
		(width 0.14732)
		(layer "F.Cu")
		(net "PSU_I2C_SCL")
	)
	(segment
		(start 16.6497 36.811001)
		(end 17.126001 36.811001)
		(width 0.14732)
		(layer "F.Cu")
		(net "PSU_I2C_SCL")
	)
	(segment
		(start 31.3436 26.8986)
		(end 31.245988 27.097812)
		(width 0.127)
		(layer "F.Cu")
		(net "PSU_I2C_SCL")
	)
	(segment
		(start 19.111366 37.28466)
		(end 19.439026 36.957)
		(width 0.14732)
		(layer "F.Cu")
		(net "PSU_I2C_SCL")
	)
	(segment
		(start 2.159 35.56)
		(end 2.159 36.83)
		(width 0.14732)
		(layer "F.Cu")
		(net "PSU_I2C_SCL")
	)
	(segment
		(start 18.406974 36.957)
		(end 18.734634 37.28466)
		(width 0.14732)
		(layer "F.Cu")
		(net "PSU_I2C_SCL")
	)
	(segment
		(start 19.439026 36.948974)
		(end 19.558 36.83)
		(width 0.14732)
		(layer "F.Cu")
		(net "PSU_I2C_SCL")
	)
	(segment
		(start 2.413 35.306)
		(end 2.159 35.56)
		(width 0.14732)
		(layer "F.Cu")
		(net "PSU_I2C_SCL")
	)
	(segment
		(start 18.734634 37.28466)
		(end 19.111366 37.28466)
		(width 0.14732)
		(layer "F.Cu")
		(net "PSU_I2C_SCL")
	)
	(segment
		(start 2.413 34.5821)
		(end 2.413 35.306)
		(width 0.14732)
		(layer "F.Cu")
		(net "PSU_I2C_SCL")
	)
	(segment
		(start 19.439026 36.957)
		(end 19.439026 36.948974)
		(width 0.14732)
		(layer "F.Cu")
		(net "PSU_I2C_SCL")
	)
	(segment
		(start 31.245988 27.097812)
		(end 31.245988 27.548408)
		(width 0.127)
		(layer "F.Cu")
		(net "PSU_I2C_SCL")
	)
	(segment
		(start 17.126001 36.811001)
		(end 17.272 36.957)
		(width 0.14732)
		(layer "F.Cu")
		(net "PSU_I2C_SCL")
	)
	(segment
		(start 27.428012 37.849988)
		(end 27.305 37.973)
		(width 0.14732)
		(layer "F.Cu")
		(net "PSU_I2C_SCL")
	)
	(segment
		(start 28.1686 37.849988)
		(end 27.428012 37.849988)
		(width 0.14732)
		(layer "F.Cu")
		(net "PSU_I2C_SCL")
	)
	(via
		(at 2.413 35.306)
		(size 0.508)
		(drill 0.2667)
		(layers "F.Cu" "B.Cu")
		(net "PSU_I2C_SCL")
	)
	(via
		(at 20.193 36.83)
		(size 0.508)
		(drill 0.254)
		(layers "F.Cu" "B.Cu")
		(net "PSU_I2C_SCL")
	)
	(via
		(at 27.305 37.973)
		(size 0.508)
		(drill 0.25654)
		(layers "F.Cu" "B.Cu")
		(net "PSU_I2C_SCL")
	)
	(via
		(at 13.97 48.7045)
		(size 0.508)
		(drill 0.25654)
		(layers "F.Cu" "B.Cu")
		(net "PSU_I2C_SCL")
	)
	(via
		(at 26.7716 11.5443)
		(size 0.508)
		(drill 0.254)
		(layers "F.Cu" "B.Cu")
		(net "PSU_I2C_SCL")
	)
	(via
		(at 31.3436 26.8986)
		(size 0.4572)
		(drill 0.20574)
		(layers "F.Cu" "B.Cu")
		(net "PSU_I2C_SCL")
	)
	(segment
		(start 9.267825 33.329829)
		(end 9.267825 33.277175)
		(width 0.12065)
		(layer "In6.Cu")
		(net "PSU_I2C_SCL")
	)
	(segment
		(start 27.746325 35.089313)
		(end 28.291638 34.544)
		(width 0.12065)
		(layer "In6.Cu")
		(net "PSU_I2C_SCL")
	)
	(segment
		(start 26.717727 38.661975)
		(end 26.616025 38.661975)
		(width 0.12065)
		(layer "In6.Cu")
		(net "PSU_I2C_SCL")
	)
	(segment
		(start 30.546675 31.313171)
		(end 30.606898 31.252947)
		(width 0.12065)
		(layer "In6.Cu")
		(net "PSU_I2C_SCL")
	)
	(segment
		(start 7.319797 34.53765)
		(end 7.440447 34.417)
		(width 0.12065)
		(layer "In6.Cu")
		(net "PSU_I2C_SCL")
	)
	(segment
		(start 2.921 35.814)
		(end 3.429 35.814)
		(width 0.12065)
		(layer "In6.Cu")
		(net "PSU_I2C_SCL")
	)
	(segment
		(start 22.418675 35.626675)
		(end 22.418675 34.98469)
		(width 0.12065)
		(layer "In6.Cu")
		(net "PSU_I2C_SCL")
	)
	(segment
		(start 22.733 37.338)
		(end 22.733 35.941)
		(width 0.12065)
		(layer "In6.Cu")
		(net "PSU_I2C_SCL")
	)
	(segment
		(start 28.067 36.068)
		(end 27.746325 35.747325)
		(width 0.12065)
		(layer "In6.Cu")
		(net "PSU_I2C_SCL")
	)
	(segment
		(start 8.180654 34.417)
		(end 9.267825 33.329829)
		(width 0.12065)
		(layer "In6.Cu")
		(net "PSU_I2C_SCL")
	)
	(segment
		(start 27.746325 35.747325)
		(end 27.746325 35.089313)
		(width 0.12065)
		(layer "In6.Cu")
		(net "PSU_I2C_SCL")
	)
	(segment
		(start 26.416 38.862)
		(end 24.257 38.862)
		(width 0.12065)
		(layer "In6.Cu")
		(net "PSU_I2C_SCL")
	)
	(segment
		(start 31.3436 27.432)
		(end 31.3436 26.8986)
		(width 0.12065)
		(layer "In6.Cu")
		(net "PSU_I2C_SCL")
	)
	(segment
		(start 18.288 37.465)
		(end 18.288 37.4126)
		(width 0.12065)
		(layer "In6.Cu")
		(net "PSU_I2C_SCL")
	)
	(segment
		(start 4.398797 34.53765)
		(end 7.319797 34.53765)
		(width 0.12065)
		(layer "In6.Cu")
		(net "PSU_I2C_SCL")
	)
	(segment
		(start 3.43535 35.80765)
		(end 3.50995 35.80765)
		(width 0.12065)
		(layer "In6.Cu")
		(net "PSU_I2C_SCL")
	)
	(segment
		(start 3.429 35.814)
		(end 3.43535 35.80765)
		(width 0.12065)
		(layer "In6.Cu")
		(net "PSU_I2C_SCL")
	)
	(segment
		(start 7.440447 34.417)
		(end 8.180654 34.417)
		(width 0.12065)
		(layer "In6.Cu")
		(net "PSU_I2C_SCL")
	)
	(segment
		(start 17.018 34.798)
		(end 17.018 37.419864)
		(width 0.12065)
		(layer "In6.Cu")
		(net "PSU_I2C_SCL")
	)
	(segment
		(start 27.305 37.973)
		(end 28.067 37.211)
		(width 0.12065)
		(layer "In6.Cu")
		(net "PSU_I2C_SCL")
	)
	(segment
		(start 30.606898 32.893102)
		(end 30.606898 31.739053)
		(width 0.12065)
		(layer "In6.Cu")
		(net "PSU_I2C_SCL")
	)
	(segment
		(start 27.270075 38.109627)
		(end 26.717727 38.661975)
		(width 0.12065)
		(layer "In6.Cu")
		(net "PSU_I2C_SCL")
	)
	(segment
		(start 28.067 37.211)
		(end 28.067 36.068)
		(width 0.12065)
		(layer "In6.Cu")
		(net "PSU_I2C_SCL")
	)
	(segment
		(start 2.413 35.306)
		(end 2.921 35.814)
		(width 0.12065)
		(layer "In6.Cu")
		(net "PSU_I2C_SCL")
	)
	(segment
		(start 4.008171 34.864675)
		(end 4.071772 34.864675)
		(width 0.12065)
		(layer "In6.Cu")
		(net "PSU_I2C_SCL")
	)
	(segment
		(start 30.606898 29.845102)
		(end 30.672659 29.779341)
		(width 0.12065)
		(layer "In6.Cu")
		(net "PSU_I2C_SCL")
	)
	(segment
		(start 30.672659 29.779341)
		(end 30.672659 28.102941)
		(width 0.12065)
		(layer "In6.Cu")
		(net "PSU_I2C_SCL")
	)
	(segment
		(start 22.104985 34.671)
		(end 21.029346 34.671)
		(width 0.12065)
		(layer "In6.Cu")
		(net "PSU_I2C_SCL")
	)
	(segment
		(start 20.640675 35.059671)
		(end 20.640675 35.493325)
		(width 0.12065)
		(layer "In6.Cu")
		(net "PSU_I2C_SCL")
	)
	(segment
		(start 16.256 34.036)
		(end 17.018 34.798)
		(width 0.12065)
		(layer "In6.Cu")
		(net "PSU_I2C_SCL")
	)
	(segment
		(start 28.291638 34.544)
		(end 28.956 34.544)
		(width 0.12065)
		(layer "In6.Cu")
		(net "PSU_I2C_SCL")
	)
	(segment
		(start 3.749675 35.567925)
		(end 3.749675 35.123171)
		(width 0.12065)
		(layer "In6.Cu")
		(net "PSU_I2C_SCL")
	)
	(segment
		(start 20.193 35.941)
		(end 20.193 36.83)
		(width 0.12065)
		(layer "In6.Cu")
		(net "PSU_I2C_SCL")
	)
	(segment
		(start 22.733 35.941)
		(end 22.418675 35.626675)
		(width 0.12065)
		(layer "In6.Cu")
		(net "PSU_I2C_SCL")
	)
	(segment
		(start 27.305 37.973)
		(end 27.270075 38.007925)
		(width 0.12065)
		(layer "In6.Cu")
		(net "PSU_I2C_SCL")
	)
	(segment
		(start 18.669 36.322)
		(end 19.304 36.322)
		(width 0.12065)
		(layer "In6.Cu")
		(net "PSU_I2C_SCL")
	)
	(segment
		(start 9.777146 32.767854)
		(end 15.749829 32.767854)
		(width 0.12065)
		(layer "In6.Cu")
		(net "PSU_I2C_SCL")
	)
	(segment
		(start 17.880965 37.872035)
		(end 18.288 37.465)
		(width 0.12065)
		(layer "In6.Cu")
		(net "PSU_I2C_SCL")
	)
	(segment
		(start 4.071772 34.864675)
		(end 4.398797 34.53765)
		(width 0.12065)
		(layer "In6.Cu")
		(net "PSU_I2C_SCL")
	)
	(segment
		(start 19.304 36.322)
		(end 19.812 36.83)
		(width 0.12065)
		(layer "In6.Cu")
		(net "PSU_I2C_SCL")
	)
	(segment
		(start 9.267825 33.277175)
		(end 9.777146 32.767854)
		(width 0.12065)
		(layer "In6.Cu")
		(net "PSU_I2C_SCL")
	)
	(segment
		(start 30.546675 31.678829)
		(end 30.546675 31.313171)
		(width 0.12065)
		(layer "In6.Cu")
		(net "PSU_I2C_SCL")
	)
	(segment
		(start 27.270075 38.007925)
		(end 27.270075 38.109627)
		(width 0.12065)
		(layer "In6.Cu")
		(net "PSU_I2C_SCL")
	)
	(segment
		(start 30.606898 31.252947)
		(end 30.606898 29.845102)
		(width 0.12065)
		(layer "In6.Cu")
		(net "PSU_I2C_SCL")
	)
	(segment
		(start 21.029346 34.671)
		(end 20.640675 35.059671)
		(width 0.12065)
		(layer "In6.Cu")
		(net "PSU_I2C_SCL")
	)
	(segment
		(start 30.672659 28.102941)
		(end 31.3436 27.432)
		(width 0.12065)
		(layer "In6.Cu")
		(net "PSU_I2C_SCL")
	)
	(segment
		(start 18.40865 37.29195)
		(end 18.40865 36.58235)
		(width 0.12065)
		(layer "In6.Cu")
		(net "PSU_I2C_SCL")
	)
	(segment
		(start 3.749675 35.123171)
		(end 4.008171 34.864675)
		(width 0.12065)
		(layer "In6.Cu")
		(net "PSU_I2C_SCL")
	)
	(segment
		(start 15.749829 32.767854)
		(end 16.256 33.274025)
		(width 0.12065)
		(layer "In6.Cu")
		(net "PSU_I2C_SCL")
	)
	(segment
		(start 24.257 38.862)
		(end 22.733 37.338)
		(width 0.12065)
		(layer "In6.Cu")
		(net "PSU_I2C_SCL")
	)
	(segment
		(start 30.606898 31.739053)
		(end 30.546675 31.678829)
		(width 0.12065)
		(layer "In6.Cu")
		(net "PSU_I2C_SCL")
	)
	(segment
		(start 28.956 34.544)
		(end 30.606898 32.893102)
		(width 0.12065)
		(layer "In6.Cu")
		(net "PSU_I2C_SCL")
	)
	(segment
		(start 17.470171 37.872035)
		(end 17.880965 37.872035)
		(width 0.12065)
		(layer "In6.Cu")
		(net "PSU_I2C_SCL")
	)
	(segment
		(start 22.418675 34.98469)
		(end 22.104985 34.671)
		(width 0.12065)
		(layer "In6.Cu")
		(net "PSU_I2C_SCL")
	)
	(segment
		(start 26.616025 38.661975)
		(end 26.416 38.862)
		(width 0.12065)
		(layer "In6.Cu")
		(net "PSU_I2C_SCL")
	)
	(segment
		(start 20.640675 35.493325)
		(end 20.193 35.941)
		(width 0.12065)
		(layer "In6.Cu")
		(net "PSU_I2C_SCL")
	)
	(segment
		(start 19.812 36.83)
		(end 20.193 36.83)
		(width 0.12065)
		(layer "In6.Cu")
		(net "PSU_I2C_SCL")
	)
	(segment
		(start 18.40865 36.58235)
		(end 18.669 36.322)
		(width 0.12065)
		(layer "In6.Cu")
		(net "PSU_I2C_SCL")
	)
	(segment
		(start 16.256 33.274025)
		(end 16.256 34.036)
		(width 0.12065)
		(layer "In6.Cu")
		(net "PSU_I2C_SCL")
	)
	(segment
		(start 17.018 37.419864)
		(end 17.470171 37.872035)
		(width 0.12065)
		(layer "In6.Cu")
		(net "PSU_I2C_SCL")
	)
	(segment
		(start 18.288 37.4126)
		(end 18.40865 37.29195)
		(width 0.12065)
		(layer "In6.Cu")
		(net "PSU_I2C_SCL")
	)
	(segment
		(start 3.50995 35.80765)
		(end 3.749675 35.567925)
		(width 0.12065)
		(layer "In6.Cu")
		(net "PSU_I2C_SCL")
	)
	(segment
		(start 16.383 37.846)
		(end 16.383 38.350469)
		(width 0.12065)
		(layer "In7.Cu")
		(net "PSU_I2C_SCL")
	)
	(segment
		(start 29.626941 24.038941)
		(end 30.028312 24.038941)
		(width 0.12065)
		(layer "In7.Cu")
		(net "PSU_I2C_SCL")
	)
	(segment
		(start 30.952059 26.507059)
		(end 31.3436 26.8986)
		(width 0.12065)
		(layer "In7.Cu")
		(net "PSU_I2C_SCL")
	)
	(segment
		(start 14.478 40.255469)
		(end 14.478 46.736)
		(width 0.12065)
		(layer "In7.Cu")
		(net "PSU_I2C_SCL")
	)
	(segment
		(start 17.907 36.322)
		(end 16.383 37.846)
		(width 0.12065)
		(layer "In7.Cu")
		(net "PSU_I2C_SCL")
	)
	(segment
		(start 30.520259 25.694259)
		(end 30.693004 25.694259)
		(width 0.12065)
		(layer "In7.Cu")
		(net "PSU_I2C_SCL")
	)
	(segment
		(start 16.383 38.350469)
		(end 14.478 40.255469)
		(width 0.12065)
		(layer "In7.Cu")
		(net "PSU_I2C_SCL")
	)
	(segment
		(start 29.464 22.733)
		(end 29.464 23.876)
		(width 0.12065)
		(layer "In7.Cu")
		(net "PSU_I2C_SCL")
	)
	(segment
		(start 20.193 36.83)
		(end 19.685 36.322)
		(width 0.12065)
		(layer "In7.Cu")
		(net "PSU_I2C_SCL")
	)
	(segment
		(start 30.028312 24.038941)
		(end 30.287341 24.297996)
		(width 0.12065)
		(layer "In7.Cu")
		(net "PSU_I2C_SCL")
	)
	(segment
		(start 28.321 17.399)
		(end 30.734 19.812)
		(width 0.12065)
		(layer "In7.Cu")
		(net "PSU_I2C_SCL")
	)
	(segment
		(start 27.457857 11.709832)
		(end 28.321 12.572975)
		(width 0.12065)
		(layer "In7.Cu")
		(net "PSU_I2C_SCL")
	)
	(segment
		(start 14.478 46.736)
		(end 13.97 47.244)
		(width 0.12065)
		(layer "In7.Cu")
		(net "PSU_I2C_SCL")
	)
	(segment
		(start 30.952059 25.953314)
		(end 30.952059 26.507059)
		(width 0.12065)
		(layer "In7.Cu")
		(net "PSU_I2C_SCL")
	)
	(segment
		(start 30.287341 24.297996)
		(end 30.287341 25.461341)
		(width 0.12065)
		(layer "In7.Cu")
		(net "PSU_I2C_SCL")
	)
	(segment
		(start 13.97 47.244)
		(end 13.97 48.7045)
		(width 0.12065)
		(layer "In7.Cu")
		(net "PSU_I2C_SCL")
	)
	(segment
		(start 30.734 21.463)
		(end 29.464 22.733)
		(width 0.12065)
		(layer "In7.Cu")
		(net "PSU_I2C_SCL")
	)
	(segment
		(start 30.693004 25.694259)
		(end 30.952059 25.953314)
		(width 0.12065)
		(layer "In7.Cu")
		(net "PSU_I2C_SCL")
	)
	(segment
		(start 29.464 23.876)
		(end 29.626941 24.038941)
		(width 0.12065)
		(layer "In7.Cu")
		(net "PSU_I2C_SCL")
	)
	(segment
		(start 28.321 12.572975)
		(end 28.321 17.399)
		(width 0.12065)
		(layer "In7.Cu")
		(net "PSU_I2C_SCL")
	)
	(segment
		(start 30.734 19.812)
		(end 30.734 21.463)
		(width 0.12065)
		(layer "In7.Cu")
		(net "PSU_I2C_SCL")
	)
	(segment
		(start 26.7716 11.5443)
		(end 27.457857 11.709832)
		(width 0.12065)
		(layer "In7.Cu")
		(net "PSU_I2C_SCL")
	)
	(segment
		(start 30.287341 25.461341)
		(end 30.520259 25.694259)
		(width 0.12065)
		(layer "In7.Cu")
		(net "PSU_I2C_SCL")
	)
	(segment
		(start 19.685 36.322)
		(end 17.907 36.322)
		(width 0.12065)
		(layer "In7.Cu")
		(net "PSU_I2C_SCL")
	)
	(segment
		(start 40.237004 13.042011)
		(end 39.737005 12.542012)
		(width 0.13208)
		(layer "F.Cu")
		(net "PGRM_JTAG_TRST_L")
	)
	(via
		(at 39.737005 12.542012)
		(size 0.4826)
		(drill 0.20574)
		(layers "F.Cu" "B.Cu")
		(net "PGRM_JTAG_TRST_L")
	)
	(via
		(at 37.592 2.394585)
		(size 0.508)
		(drill 0.2667)
		(layers "F.Cu" "B.Cu")
		(net "PGRM_JTAG_TRST_L")
	)
	(via
		(at 3.937 5.08)
		(size 0.508)
		(drill 0.254)
		(layers "F.Cu" "B.Cu")
		(net "PGRM_JTAG_TRST_L")
	)
	(segment
		(start 40.237029 12.04214)
		(end 40.236877 12.04214)
		(width 0.14732)
		(layer "B.Cu")
		(net "PGRM_JTAG_TRST_L")
	)
	(segment
		(start 5.05968 5.969)
		(end 4.826 5.969)
		(width 0.14732)
		(layer "B.Cu")
		(net "PGRM_JTAG_TRST_L")
	)
	(segment
		(start 40.236877 12.04214)
		(end 39.737005 12.542012)
		(width 0.14732)
		(layer "B.Cu")
		(net "PGRM_JTAG_TRST_L")
	)
	(segment
		(start 39.737005 12.542012)
		(end 40.237029 13.042036)
		(width 0.14732)
		(layer "B.Cu")
		(net "PGRM_JTAG_TRST_L")
	)
	(segment
		(start 4.826 5.969)
		(end 3.937 5.08)
		(width 0.14732)
		(layer "B.Cu")
		(net "PGRM_JTAG_TRST_L")
	)
	(segment
		(start 5.207 6.35)
		(end 5.207 6.11632)
		(width 0.14732)
		(layer "B.Cu")
		(net "PGRM_JTAG_TRST_L")
	)
	(segment
		(start 5.207 6.11632)
		(end 5.05968 5.969)
		(width 0.14732)
		(layer "B.Cu")
		(net "PGRM_JTAG_TRST_L")
	)
	(segment
		(start 40.237029 13.042036)
		(end 40.237029 14.041882)
		(width 0.14732)
		(layer "B.Cu")
		(net "PGRM_JTAG_TRST_L")
	)
	(segment
		(start 32.053479 1.590675)
		(end 31.170829 2.473325)
		(width 0.12065)
		(layer "In6.Cu")
		(net "PGRM_JTAG_TRST_L")
	)
	(segment
		(start 28.692475 1.133475)
		(end 26.787475 1.133475)
		(width 0.12065)
		(layer "In6.Cu")
		(net "PGRM_JTAG_TRST_L")
	)
	(segment
		(start 37.592 2.394585)
		(end 33.763585 2.394585)
		(width 0.12065)
		(layer "In6.Cu")
		(net "PGRM_JTAG_TRST_L")
	)
	(segment
		(start 30.032325 2.473325)
		(end 28.692475 1.133475)
		(width 0.12065)
		(layer "In6.Cu")
		(net "PGRM_JTAG_TRST_L")
	)
	(segment
		(start 32.959675 1.590675)
		(end 32.053479 1.590675)
		(width 0.12065)
		(layer "In6.Cu")
		(net "PGRM_JTAG_TRST_L")
	)
	(segment
		(start 23.622 -2.032)
		(end 6.985 -2.032)
		(width 0.12065)
		(layer "In6.Cu")
		(net "PGRM_JTAG_TRST_L")
	)
	(segment
		(start 6.985 -2.032)
		(end 3.556 1.397)
		(width 0.12065)
		(layer "In6.Cu")
		(net "PGRM_JTAG_TRST_L")
	)
	(segment
		(start 33.763585 2.394585)
		(end 32.959675 1.590675)
		(width 0.12065)
		(layer "In6.Cu")
		(net "PGRM_JTAG_TRST_L")
	)
	(segment
		(start 3.556 4.699)
		(end 3.937 5.08)
		(width 0.12065)
		(layer "In6.Cu")
		(net "PGRM_JTAG_TRST_L")
	)
	(segment
		(start 26.787475 1.133475)
		(end 23.622 -2.032)
		(width 0.12065)
		(layer "In6.Cu")
		(net "PGRM_JTAG_TRST_L")
	)
	(segment
		(start 3.556 1.397)
		(end 3.556 4.699)
		(width 0.12065)
		(layer "In6.Cu")
		(net "PGRM_JTAG_TRST_L")
	)
	(segment
		(start 31.170829 2.473325)
		(end 30.032325 2.473325)
		(width 0.12065)
		(layer "In6.Cu")
		(net "PGRM_JTAG_TRST_L")
	)
	(segment
		(start 37.592 2.394585)
		(end 38.159868 2.394585)
		(width 0.12065)
		(layer "In7.Cu")
		(net "PGRM_JTAG_TRST_L")
	)
	(segment
		(start 40.71051 5.945226)
		(end 41.275 6.509715)
		(width 0.12065)
		(layer "In7.Cu")
		(net "PGRM_JTAG_TRST_L")
	)
	(segment
		(start 40.259 9.779)
		(end 40.259 12.065)
		(width 0.12065)
		(layer "In7.Cu")
		(net "PGRM_JTAG_TRST_L")
	)
	(segment
		(start 39.781988 12.542012)
		(end 39.737005 12.542012)
		(width 0.12065)
		(layer "In7.Cu")
		(net "PGRM_JTAG_TRST_L")
	)
	(segment
		(start 40.14023 5.515508)
		(end 40.569947 5.945226)
		(width 0.12065)
		(layer "In7.Cu")
		(net "PGRM_JTAG_TRST_L")
	)
	(segment
		(start 39.140232 3.70906)
		(end 39.624 4.192829)
		(width 0.12065)
		(layer "In7.Cu")
		(net "PGRM_JTAG_TRST_L")
	)
	(segment
		(start 40.14023 5.08823)
		(end 40.14023 5.515508)
		(width 0.12065)
		(layer "In7.Cu")
		(net "PGRM_JTAG_TRST_L")
	)
	(segment
		(start 41.275 8.763)
		(end 40.259 9.779)
		(width 0.12065)
		(layer "In7.Cu")
		(net "PGRM_JTAG_TRST_L")
	)
	(segment
		(start 40.259 12.065)
		(end 39.781988 12.542012)
		(width 0.12065)
		(layer "In7.Cu")
		(net "PGRM_JTAG_TRST_L")
	)
	(segment
		(start 39.624 4.572)
		(end 40.14023 5.08823)
		(width 0.12065)
		(layer "In7.Cu")
		(net "PGRM_JTAG_TRST_L")
	)
	(segment
		(start 38.159868 2.394585)
		(end 39.140232 3.374949)
		(width 0.12065)
		(layer "In7.Cu")
		(net "PGRM_JTAG_TRST_L")
	)
	(segment
		(start 39.140232 3.374949)
		(end 39.140232 3.70906)
		(width 0.12065)
		(layer "In7.Cu")
		(net "PGRM_JTAG_TRST_L")
	)
	(segment
		(start 39.624 4.192829)
		(end 39.624 4.572)
		(width 0.12065)
		(layer "In7.Cu")
		(net "PGRM_JTAG_TRST_L")
	)
	(segment
		(start 41.275 6.509715)
		(end 41.275 8.763)
		(width 0.12065)
		(layer "In7.Cu")
		(net "PGRM_JTAG_TRST_L")
	)
	(segment
		(start 40.569947 5.945226)
		(end 40.71051 5.945226)
		(width 0.12065)
		(layer "In7.Cu")
		(net "PGRM_JTAG_TRST_L")
	)
	(segment
		(start 40.237004 12.041988)
		(end 39.737005 11.541989)
		(width 0.13208)
		(layer "F.Cu")
		(net "PGRM_JTAG_TMS")
	)
	(via
		(at 39.737005 11.541989)
		(size 0.4826)
		(drill 0.20574)
		(layers "F.Cu" "B.Cu")
		(net "PGRM_JTAG_TMS")
	)
	(via
		(at 0.6604 8.3439)
		(size 0.508)
		(drill 0.25654)
		(layers "F.Cu" "B.Cu")
		(net "PGRM_JTAG_TMS")
	)
	(segment
		(start 0.8763 8.128)
		(end 0.6604 8.3439)
		(width 0.14732)
		(layer "B.Cu")
		(net "PGRM_JTAG_TMS")
	)
	(segment
		(start 39.237031 12.041962)
		(end 39.237031 12.04214)
		(width 0.14732)
		(layer "B.Cu")
		(net "PGRM_JTAG_TMS")
	)
	(segment
		(start 39.737005 11.541989)
		(end 39.237031 12.041962)
		(width 0.14732)
		(layer "B.Cu")
		(net "PGRM_JTAG_TMS")
	)
	(segment
		(start 2.032 8.128)
		(end 0.8763 8.128)
		(width 0.14732)
		(layer "B.Cu")
		(net "PGRM_JTAG_TMS")
	)
	(segment
		(start 17.526 21.717)
		(end 19.557975 21.717)
		(width 0.12065)
		(layer "In2.Cu")
		(net "PGRM_JTAG_TMS")
	)
	(segment
		(start 11.198225 15.008225)
		(end 12.647879 15.008225)
		(width 0.12065)
		(layer "In2.Cu")
		(net "PGRM_JTAG_TMS")
	)
	(segment
		(start 16.00835 19.638797)
		(end 16.845128 20.475575)
		(width 0.12065)
		(layer "In2.Cu")
		(net "PGRM_JTAG_TMS")
	)
	(segment
		(start 13.293725 16.341827)
		(end 13.681075 16.729177)
		(width 0.12065)
		(layer "In2.Cu")
		(net "PGRM_JTAG_TMS")
	)
	(segment
		(start 10.753725 14.384071)
		(end 10.753725 14.563725)
		(width 0.12065)
		(layer "In2.Cu")
		(net "PGRM_JTAG_TMS")
	)
	(segment
		(start 34.731325 11.363325)
		(end 35.433 12.065)
		(width 0.12065)
		(layer "In2.Cu")
		(net "PGRM_JTAG_TMS")
	)
	(segment
		(start 16.845229 20.475575)
		(end 17.103725 20.734071)
		(width 0.12065)
		(layer "In2.Cu")
		(net "PGRM_JTAG_TMS")
	)
	(segment
		(start 13.681075 16.729177)
		(end 13.681075 17.289729)
		(width 0.12065)
		(layer "In2.Cu")
		(net "PGRM_JTAG_TMS")
	)
	(segment
		(start 17.103725 20.734071)
		(end 17.103725 21.294725)
		(width 0.12065)
		(layer "In2.Cu")
		(net "PGRM_JTAG_TMS")
	)
	(segment
		(start 22.351975 18.923)
		(end 24.13 18.923)
		(width 0.12065)
		(layer "In2.Cu")
		(net "PGRM_JTAG_TMS")
	)
	(segment
		(start 13.939571 17.548225)
		(end 13.992225 17.548225)
		(width 0.12065)
		(layer "In2.Cu")
		(net "PGRM_JTAG_TMS")
	)
	(segment
		(start 16.845128 20.475575)
		(end 16.845229 20.475575)
		(width 0.12065)
		(layer "In2.Cu")
		(net "PGRM_JTAG_TMS")
	)
	(segment
		(start 12.647879 15.008225)
		(end 13.293725 15.654071)
		(width 0.12065)
		(layer "In2.Cu")
		(net "PGRM_JTAG_TMS")
	)
	(segment
		(start 10.753725 14.563725)
		(end 11.198225 15.008225)
		(width 0.12065)
		(layer "In2.Cu")
		(net "PGRM_JTAG_TMS")
	)
	(segment
		(start 16.00835 19.56435)
		(end 16.00835 19.638797)
		(width 0.12065)
		(layer "In2.Cu")
		(net "PGRM_JTAG_TMS")
	)
	(segment
		(start 19.557975 21.717)
		(end 22.351975 18.923)
		(width 0.12065)
		(layer "In2.Cu")
		(net "PGRM_JTAG_TMS")
	)
	(segment
		(start 35.433 12.065)
		(end 38.862025 12.065)
		(width 0.12065)
		(layer "In2.Cu")
		(net "PGRM_JTAG_TMS")
	)
	(segment
		(start 39.385037 11.541989)
		(end 39.737005 11.541989)
		(width 0.12065)
		(layer "In2.Cu")
		(net "PGRM_JTAG_TMS")
	)
	(segment
		(start 2.352675 10.036175)
		(end 2.352675 11.43)
		(width 0.12065)
		(layer "In2.Cu")
		(net "PGRM_JTAG_TMS")
	)
	(segment
		(start 13.293725 15.654071)
		(end 13.293725 16.341827)
		(width 0.12065)
		(layer "In2.Cu")
		(net "PGRM_JTAG_TMS")
	)
	(segment
		(start 13.992225 17.548225)
		(end 16.00835 19.56435)
		(width 0.12065)
		(layer "In2.Cu")
		(net "PGRM_JTAG_TMS")
	)
	(segment
		(start 31.43565 11.363325)
		(end 34.731325 11.363325)
		(width 0.12065)
		(layer "In2.Cu")
		(net "PGRM_JTAG_TMS")
	)
	(segment
		(start 17.103725 21.294725)
		(end 17.526 21.717)
		(width 0.12065)
		(layer "In2.Cu")
		(net "PGRM_JTAG_TMS")
	)
	(segment
		(start 5.273675 14.351)
		(end 7.239 14.351)
		(width 0.12065)
		(layer "In2.Cu")
		(net "PGRM_JTAG_TMS")
	)
	(segment
		(start 7.464425 14.125575)
		(end 10.495229 14.125575)
		(width 0.12065)
		(layer "In2.Cu")
		(net "PGRM_JTAG_TMS")
	)
	(segment
		(start 2.352675 11.43)
		(end 5.273675 14.351)
		(width 0.12065)
		(layer "In2.Cu")
		(net "PGRM_JTAG_TMS")
	)
	(segment
		(start 24.828525 17.970449)
		(end 31.43565 11.363325)
		(width 0.12065)
		(layer "In2.Cu")
		(net "PGRM_JTAG_TMS")
	)
	(segment
		(start 13.681075 17.289729)
		(end 13.939571 17.548225)
		(width 0.12065)
		(layer "In2.Cu")
		(net "PGRM_JTAG_TMS")
	)
	(segment
		(start 10.495229 14.125575)
		(end 10.753725 14.384071)
		(width 0.12065)
		(layer "In2.Cu")
		(net "PGRM_JTAG_TMS")
	)
	(segment
		(start 38.862025 12.065)
		(end 39.385037 11.541989)
		(width 0.12065)
		(layer "In2.Cu")
		(net "PGRM_JTAG_TMS")
	)
	(segment
		(start 24.13 18.923)
		(end 24.828525 18.224475)
		(width 0.12065)
		(layer "In2.Cu")
		(net "PGRM_JTAG_TMS")
	)
	(segment
		(start 24.828525 18.224475)
		(end 24.828525 17.970449)
		(width 0.12065)
		(layer "In2.Cu")
		(net "PGRM_JTAG_TMS")
	)
	(segment
		(start 0.6604 8.3439)
		(end 2.352675 10.036175)
		(width 0.12065)
		(layer "In2.Cu")
		(net "PGRM_JTAG_TMS")
	)
	(segment
		(start 7.239 14.351)
		(end 7.464425 14.125575)
		(width 0.12065)
		(layer "In2.Cu")
		(net "PGRM_JTAG_TMS")
	)
	(via
		(at 26.7081 10.414)
		(size 0.508)
		(drill 0.25654)
		(layers "F.Cu" "B.Cu")
		(net "PGRM_JTAG_TDO")
	)
	(via
		(at 24.892 5.207)
		(size 0.508)
		(drill 0.2667)
		(layers "F.Cu" "B.Cu")
		(net "PGRM_JTAG_TDO")
	)
	(via
		(at 0.6604 7.0739)
		(size 0.508)
		(drill 0.25654)
		(layers "F.Cu" "B.Cu")
		(net "PGRM_JTAG_TDO")
	)
	(segment
		(start 1.1303 6.604)
		(end 0.6604 7.0739)
		(width 0.14732)
		(layer "B.Cu")
		(net "PGRM_JTAG_TDO")
	)
	(segment
		(start 26.7081 9.525)
		(end 26.7081 10.414)
		(width 0.14732)
		(layer "B.Cu")
		(net "PGRM_JTAG_TDO")
	)
	(segment
		(start 2.794 6.604)
		(end 1.1303 6.604)
		(width 0.14732)
		(layer "B.Cu")
		(net "PGRM_JTAG_TDO")
	)
	(segment
		(start 25.654 0.762)
		(end 23.14575 -1.74625)
		(width 0.12065)
		(layer "In6.Cu")
		(net "PGRM_JTAG_TDO")
	)
	(segment
		(start 25.654 4.445)
		(end 25.654 0.762)
		(width 0.12065)
		(layer "In6.Cu")
		(net "PGRM_JTAG_TDO")
	)
	(segment
		(start 3.937 1.651)
		(end 3.937 4.191)
		(width 0.12065)
		(layer "In6.Cu")
		(net "PGRM_JTAG_TDO")
	)
	(segment
		(start 0.6731 7.0739)
		(end 0.6604 7.0739)
		(width 0.12065)
		(layer "In6.Cu")
		(net "PGRM_JTAG_TDO")
	)
	(segment
		(start 4.445 4.699)
		(end 4.445 5.207)
		(width 0.12065)
		(layer "In6.Cu")
		(net "PGRM_JTAG_TDO")
	)
	(segment
		(start 4.064 5.588)
		(end 2.159 5.588)
		(width 0.12065)
		(layer "In6.Cu")
		(net "PGRM_JTAG_TDO")
	)
	(segment
		(start 23.14575 -1.74625)
		(end 7.33425 -1.74625)
		(width 0.12065)
		(layer "In6.Cu")
		(net "PGRM_JTAG_TDO")
	)
	(segment
		(start 4.445 5.207)
		(end 4.064 5.588)
		(width 0.12065)
		(layer "In6.Cu")
		(net "PGRM_JTAG_TDO")
	)
	(segment
		(start 2.159 5.588)
		(end 0.6731 7.0739)
		(width 0.12065)
		(layer "In6.Cu")
		(net "PGRM_JTAG_TDO")
	)
	(segment
		(start 3.937 4.191)
		(end 4.445 4.699)
		(width 0.12065)
		(layer "In6.Cu")
		(net "PGRM_JTAG_TDO")
	)
	(segment
		(start 7.33425 -1.74625)
		(end 3.937 1.651)
		(width 0.12065)
		(layer "In6.Cu")
		(net "PGRM_JTAG_TDO")
	)
	(segment
		(start 24.892 5.207)
		(end 25.654 4.445)
		(width 0.12065)
		(layer "In6.Cu")
		(net "PGRM_JTAG_TDO")
	)
	(segment
		(start 24.892 5.207)
		(end 25.527 5.842)
		(width 0.12065)
		(layer "In7.Cu")
		(net "PGRM_JTAG_TDO")
	)
	(segment
		(start 25.527 5.842)
		(end 25.527 9.2329)
		(width 0.12065)
		(layer "In7.Cu")
		(net "PGRM_JTAG_TDO")
	)
	(segment
		(start 25.527 9.2329)
		(end 26.7081 10.414)
		(width 0.12065)
		(layer "In7.Cu")
		(net "PGRM_JTAG_TDO")
	)
	(segment
		(start 39.237006 11.04199)
		(end 38.737007 10.541991)
		(width 0.13208)
		(layer "F.Cu")
		(net "PGRM_JTAG_TDI")
	)
	(via
		(at 3.381629 9.076207)
		(size 0.762)
		(drill 0.381)
		(layers "F.Cu" "B.Cu")
		(net "PGRM_JTAG_TDI")
	)
	(via
		(at 38.737007 10.541991)
		(size 0.4826)
		(drill 0.20574)
		(layers "F.Cu" "B.Cu")
		(net "PGRM_JTAG_TDI")
	)
	(via
		(at 6.6294 9.4869)
		(size 0.508)
		(drill 0.254)
		(layers "F.Cu" "B.Cu")
		(net "PGRM_JTAG_TDI")
	)
	(via
		(at 25.019 10.16)
		(size 0.508)
		(drill 0.254)
		(layers "F.Cu" "B.Cu")
		(net "PGRM_JTAG_TDI")
	)
	(segment
		(start 3.488207 9.076207)
		(end 3.381629 9.076207)
		(width 0.14732)
		(layer "B.Cu")
		(net "PGRM_JTAG_TDI")
	)
	(segment
		(start 3.683 9.271)
		(end 3.488207 9.076207)
		(width 0.14732)
		(layer "B.Cu")
		(net "PGRM_JTAG_TDI")
	)
	(segment
		(start 4.699 9.271)
		(end 3.683 9.271)
		(width 0.14732)
		(layer "B.Cu")
		(net "PGRM_JTAG_TDI")
	)
	(segment
		(start 5.1308 9.7028)
		(end 4.699 9.271)
		(width 0.14732)
		(layer "B.Cu")
		(net "PGRM_JTAG_TDI")
	)
	(segment
		(start 24.765 10.414)
		(end 25.019 10.16)
		(width 0.14732)
		(layer "B.Cu")
		(net "PGRM_JTAG_TDI")
	)
	(segment
		(start 25.8699 10.414)
		(end 25.273 10.414)
		(width 0.14732)
		(layer "B.Cu")
		(net "PGRM_JTAG_TDI")
	)
	(segment
		(start 5.2578 9.7028)
		(end 5.1308 9.7028)
		(width 0.14732)
		(layer "B.Cu")
		(net "PGRM_JTAG_TDI")
	)
	(segment
		(start 24.1681 10.414)
		(end 24.765 10.414)
		(width 0.14732)
		(layer "B.Cu")
		(net "PGRM_JTAG_TDI")
	)
	(segment
		(start 6.6294 9.4869)
		(end 6.4135 9.7028)
		(width 0.14732)
		(layer "B.Cu")
		(net "PGRM_JTAG_TDI")
	)
	(segment
		(start 6.4135 9.7028)
		(end 5.2578 9.7028)
		(width 0.14732)
		(layer "B.Cu")
		(net "PGRM_JTAG_TDI")
	)
	(segment
		(start 25.273 10.414)
		(end 25.019 10.16)
		(width 0.14732)
		(layer "B.Cu")
		(net "PGRM_JTAG_TDI")
	)
	(segment
		(start 19.082029 14.953971)
		(end 19.082029 14.625676)
		(width 0.12065)
		(layer "In2.Cu")
		(net "PGRM_JTAG_TDI")
	)
	(segment
		(start 15.268575 14.125575)
		(end 15.575229 14.125575)
		(width 0.12065)
		(layer "In2.Cu")
		(net "PGRM_JTAG_TDI")
	)
	(segment
		(start 15.833725 16.256)
		(end 16.214725 16.637)
		(width 0.12065)
		(layer "In2.Cu")
		(net "PGRM_JTAG_TDI")
	)
	(segment
		(start 15.833725 14.384071)
		(end 15.833725 16.256)
		(width 0.12065)
		(layer "In2.Cu")
		(net "PGRM_JTAG_TDI")
	)
	(segment
		(start 13.230225 9.928225)
		(end 13.462 10.16)
		(width 0.12065)
		(layer "In2.Cu")
		(net "PGRM_JTAG_TDI")
	)
	(segment
		(start 18.796 15.24)
		(end 19.082029 14.953971)
		(width 0.12065)
		(layer "In2.Cu")
		(net "PGRM_JTAG_TDI")
	)
	(segment
		(start 21.723198 11.984482)
		(end 21.72335 11.729999)
		(width 0.12065)
		(layer "In2.Cu")
		(net "PGRM_JTAG_TDI")
	)
	(segment
		(start 14.563725 13.420725)
		(end 15.268575 14.125575)
		(width 0.12065)
		(layer "In2.Cu")
		(net "PGRM_JTAG_TDI")
	)
	(segment
		(start 19.082029 14.625676)
		(end 21.723198 11.984482)
		(width 0.12065)
		(layer "In2.Cu")
		(net "PGRM_JTAG_TDI")
	)
	(segment
		(start 22.017609 11.436121)
		(end 22.345879 11.436121)
		(width 0.12065)
		(layer "In2.Cu")
		(net "PGRM_JTAG_TDI")
	)
	(segment
		(start 10.129571 9.928225)
		(end 13.230225 9.928225)
		(width 0.12065)
		(layer "In2.Cu")
		(net "PGRM_JTAG_TDI")
	)
	(segment
		(start 9.871075 9.669729)
		(end 10.129571 9.928225)
		(width 0.12065)
		(layer "In2.Cu")
		(net "PGRM_JTAG_TDI")
	)
	(segment
		(start 7.458075 8.658225)
		(end 9.420225 8.658225)
		(width 0.12065)
		(layer "In2.Cu")
		(net "PGRM_JTAG_TDI")
	)
	(segment
		(start 21.72335 11.729999)
		(end 22.017609 11.436121)
		(width 0.12065)
		(layer "In2.Cu")
		(net "PGRM_JTAG_TDI")
	)
	(segment
		(start 6.6294 9.4869)
		(end 7.458075 8.658225)
		(width 0.12065)
		(layer "In2.Cu")
		(net "PGRM_JTAG_TDI")
	)
	(segment
		(start 18.415 16.637)
		(end 18.796 16.256)
		(width 0.12065)
		(layer "In2.Cu")
		(net "PGRM_JTAG_TDI")
	)
	(segment
		(start 14.563725 11.844071)
		(end 14.563725 13.420725)
		(width 0.12065)
		(layer "In2.Cu")
		(net "PGRM_JTAG_TDI")
	)
	(segment
		(start 16.214725 16.637)
		(end 18.415 16.637)
		(width 0.12065)
		(layer "In2.Cu")
		(net "PGRM_JTAG_TDI")
	)
	(segment
		(start 15.575229 14.125575)
		(end 15.833725 14.384071)
		(width 0.12065)
		(layer "In2.Cu")
		(net "PGRM_JTAG_TDI")
	)
	(segment
		(start 22.345879 11.436121)
		(end 23.622 10.16)
		(width 0.12065)
		(layer "In2.Cu")
		(net "PGRM_JTAG_TDI")
	)
	(segment
		(start 13.462 10.742346)
		(end 14.563725 11.844071)
		(width 0.12065)
		(layer "In2.Cu")
		(net "PGRM_JTAG_TDI")
	)
	(segment
		(start 23.622 10.16)
		(end 25.019 10.16)
		(width 0.12065)
		(layer "In2.Cu")
		(net "PGRM_JTAG_TDI")
	)
	(segment
		(start 9.420225 8.658225)
		(end 9.871075 9.109075)
		(width 0.12065)
		(layer "In2.Cu")
		(net "PGRM_JTAG_TDI")
	)
	(segment
		(start 13.462 10.16)
		(end 13.462 10.742346)
		(width 0.12065)
		(layer "In2.Cu")
		(net "PGRM_JTAG_TDI")
	)
	(segment
		(start 9.871075 9.109075)
		(end 9.871075 9.669729)
		(width 0.12065)
		(layer "In2.Cu")
		(net "PGRM_JTAG_TDI")
	)
	(segment
		(start 18.796 16.256)
		(end 18.796 15.24)
		(width 0.12065)
		(layer "In2.Cu")
		(net "PGRM_JTAG_TDI")
	)
	(segment
		(start 37.973 8.382)
		(end 37.785675 8.194675)
		(width 0.12065)
		(layer "In3.Cu")
		(net "PGRM_JTAG_TDI")
	)
	(segment
		(start 34.864675 6.791325)
		(end 33.528 8.128)
		(width 0.12065)
		(layer "In3.Cu")
		(net "PGRM_JTAG_TDI")
	)
	(segment
		(start 36.576 8.006258)
		(end 36.576 7.426325)
		(width 0.12065)
		(layer "In3.Cu")
		(net "PGRM_JTAG_TDI")
	)
	(segment
		(start 36.764417 8.194675)
		(end 36.576 8.006258)
		(width 0.12065)
		(layer "In3.Cu")
		(net "PGRM_JTAG_TDI")
	)
	(segment
		(start 35.941 6.791325)
		(end 34.864675 6.791325)
		(width 0.12065)
		(layer "In3.Cu")
		(net "PGRM_JTAG_TDI")
	)
	(segment
		(start 38.737007 10.541991)
		(end 37.973 9.777984)
		(width 0.12065)
		(layer "In3.Cu")
		(net "PGRM_JTAG_TDI")
	)
	(segment
		(start 31.062295 8.128)
		(end 30.935727 8.254568)
		(width 0.12065)
		(layer "In3.Cu")
		(net "PGRM_JTAG_TDI")
	)
	(segment
		(start 37.785675 8.194675)
		(end 36.764417 8.194675)
		(width 0.12065)
		(layer "In3.Cu")
		(net "PGRM_JTAG_TDI")
	)
	(segment
		(start 26.924432 8.254568)
		(end 25.019 10.16)
		(width 0.12065)
		(layer "In3.Cu")
		(net "PGRM_JTAG_TDI")
	)
	(segment
		(start 33.528 8.128)
		(end 31.062295 8.128)
		(width 0.12065)
		(layer "In3.Cu")
		(net "PGRM_JTAG_TDI")
	)
	(segment
		(start 37.973 9.777984)
		(end 37.973 8.382)
		(width 0.12065)
		(layer "In3.Cu")
		(net "PGRM_JTAG_TDI")
	)
	(segment
		(start 36.576 7.426325)
		(end 35.941 6.791325)
		(width 0.12065)
		(layer "In3.Cu")
		(net "PGRM_JTAG_TDI")
	)
	(segment
		(start 30.935727 8.254568)
		(end 26.924432 8.254568)
		(width 0.12065)
		(layer "In3.Cu")
		(net "PGRM_JTAG_TDI")
	)
	(segment
		(start 39.237006 13.042011)
		(end 38.737007 12.542012)
		(width 0.13208)
		(layer "F.Cu")
		(net "PGRM_JTAG_TCK")
	)
	(via
		(at 3.937 8.382)
		(size 0.508)
		(drill 0.254)
		(layers "F.Cu" "B.Cu")
		(net "PGRM_JTAG_TCK")
	)
	(via
		(at 38.737007 12.542012)
		(size 0.4826)
		(drill 0.20574)
		(layers "F.Cu" "B.Cu")
		(net "PGRM_JTAG_TCK")
	)
	(via
		(at 22.225 11.938)
		(size 0.508)
		(drill 0.2667)
		(layers "F.Cu" "B.Cu")
		(net "PGRM_JTAG_TCK")
	)
	(segment
		(start 38.737007 12.542012)
		(end 39.237031 13.042036)
		(width 0.14732)
		(layer "B.Cu")
		(net "PGRM_JTAG_TCK")
	)
	(segment
		(start 5.207 8.001)
		(end 4.318 8.001)
		(width 0.14732)
		(layer "B.Cu")
		(net "PGRM_JTAG_TCK")
	)
	(segment
		(start 39.237031 13.042036)
		(end 39.237031 14.041882)
		(width 0.14732)
		(layer "B.Cu")
		(net "PGRM_JTAG_TCK")
	)
	(segment
		(start 4.318 8.001)
		(end 3.937 8.382)
		(width 0.14732)
		(layer "B.Cu")
		(net "PGRM_JTAG_TCK")
	)
	(segment
		(start 22.224746 12.192406)
		(end 19.583679 14.833473)
		(width 0.12065)
		(layer "In2.Cu")
		(net "PGRM_JTAG_TCK")
	)
	(segment
		(start 13.144475 11.366475)
		(end 12.001475 11.366475)
		(width 0.12065)
		(layer "In2.Cu")
		(net "PGRM_JTAG_TCK")
	)
	(segment
		(start 16.129 17.907)
		(end 15.24 17.018)
		(width 0.12065)
		(layer "In2.Cu")
		(net "PGRM_JTAG_TCK")
	)
	(segment
		(start 19.304 17.907)
		(end 18.392775 18.818225)
		(width 0.12065)
		(layer "In2.Cu")
		(net "PGRM_JTAG_TCK")
	)
	(segment
		(start 9.9346 10.315575)
		(end 9.483725 9.8647)
		(width 0.12065)
		(layer "In2.Cu")
		(net "PGRM_JTAG_TCK")
	)
	(segment
		(start 16.479545 18.818225)
		(end 16.129 18.46768)
		(width 0.12065)
		(layer "In2.Cu")
		(net "PGRM_JTAG_TCK")
	)
	(segment
		(start 5.588 10.033)
		(end 3.937 8.382)
		(width 0.12065)
		(layer "In2.Cu")
		(net "PGRM_JTAG_TCK")
	)
	(segment
		(start 14.951075 16.094075)
		(end 14.951075 14.771421)
		(width 0.12065)
		(layer "In2.Cu")
		(net "PGRM_JTAG_TCK")
	)
	(segment
		(start 16.129 18.46768)
		(end 16.129 17.907)
		(width 0.12065)
		(layer "In2.Cu")
		(net "PGRM_JTAG_TCK")
	)
	(segment
		(start 15.24 17.018)
		(end 15.24 16.383)
		(width 0.12065)
		(layer "In2.Cu")
		(net "PGRM_JTAG_TCK")
	)
	(segment
		(start 9.225229 9.045575)
		(end 8.859571 9.045575)
		(width 0.12065)
		(layer "In2.Cu")
		(net "PGRM_JTAG_TCK")
	)
	(segment
		(start 11.811 10.668)
		(end 11.458575 10.315575)
		(width 0.12065)
		(layer "In2.Cu")
		(net "PGRM_JTAG_TCK")
	)
	(segment
		(start 18.392775 18.818225)
		(end 16.479545 18.818225)
		(width 0.12065)
		(layer "In2.Cu")
		(net "PGRM_JTAG_TCK")
	)
	(segment
		(start 5.588 10.03935)
		(end 5.588 10.033)
		(width 0.12065)
		(layer "In2.Cu")
		(net "PGRM_JTAG_TCK")
	)
	(segment
		(start 11.811 11.176)
		(end 11.811 10.668)
		(width 0.12065)
		(layer "In2.Cu")
		(net "PGRM_JTAG_TCK")
	)
	(segment
		(start 7.718425 10.315575)
		(end 5.864225 10.315575)
		(width 0.12065)
		(layer "In2.Cu")
		(net "PGRM_JTAG_TCK")
	)
	(segment
		(start 8.601075 9.304071)
		(end 8.601075 9.432925)
		(width 0.12065)
		(layer "In2.Cu")
		(net "PGRM_JTAG_TCK")
	)
	(segment
		(start 11.458575 10.315575)
		(end 9.9346 10.315575)
		(width 0.12065)
		(layer "In2.Cu")
		(net "PGRM_JTAG_TCK")
	)
	(segment
		(start 13.589 11.811)
		(end 13.144475 11.366475)
		(width 0.12065)
		(layer "In2.Cu")
		(net "PGRM_JTAG_TCK")
	)
	(segment
		(start 14.951075 14.771421)
		(end 14.305229 14.125575)
		(width 0.12065)
		(layer "In2.Cu")
		(net "PGRM_JTAG_TCK")
	)
	(segment
		(start 5.864225 10.315575)
		(end 5.588 10.03935)
		(width 0.12065)
		(layer "In2.Cu")
		(net "PGRM_JTAG_TCK")
	)
	(segment
		(start 19.583679 15.161768)
		(end 19.304 15.441447)
		(width 0.12065)
		(layer "In2.Cu")
		(net "PGRM_JTAG_TCK")
	)
	(segment
		(start 9.483725 9.304071)
		(end 9.225229 9.045575)
		(width 0.12065)
		(layer "In2.Cu")
		(net "PGRM_JTAG_TCK")
	)
	(segment
		(start 22.225 12.065)
		(end 22.224822 12.065178)
		(width 0.12065)
		(layer "In2.Cu")
		(net "PGRM_JTAG_TCK")
	)
	(segment
		(start 13.871575 14.125575)
		(end 13.589 13.843)
		(width 0.12065)
		(layer "In2.Cu")
		(net "PGRM_JTAG_TCK")
	)
	(segment
		(start 8.859571 9.045575)
		(end 8.601075 9.304071)
		(width 0.12065)
		(layer "In2.Cu")
		(net "PGRM_JTAG_TCK")
	)
	(segment
		(start 19.583679 14.833473)
		(end 19.583679 15.161768)
		(width 0.12065)
		(layer "In2.Cu")
		(net "PGRM_JTAG_TCK")
	)
	(segment
		(start 13.589 13.843)
		(end 13.589 11.811)
		(width 0.12065)
		(layer "In2.Cu")
		(net "PGRM_JTAG_TCK")
	)
	(segment
		(start 22.225 11.938)
		(end 22.225 12.065)
		(width 0.12065)
		(layer "In2.Cu")
		(net "PGRM_JTAG_TCK")
	)
	(segment
		(start 19.304 15.441447)
		(end 19.304 17.907)
		(width 0.12065)
		(layer "In2.Cu")
		(net "PGRM_JTAG_TCK")
	)
	(segment
		(start 12.001475 11.366475)
		(end 11.811 11.176)
		(width 0.12065)
		(layer "In2.Cu")
		(net "PGRM_JTAG_TCK")
	)
	(segment
		(start 15.24 16.383)
		(end 14.951075 16.094075)
		(width 0.12065)
		(layer "In2.Cu")
		(net "PGRM_JTAG_TCK")
	)
	(segment
		(start 22.224822 12.065178)
		(end 22.224746 12.192406)
		(width 0.12065)
		(layer "In2.Cu")
		(net "PGRM_JTAG_TCK")
	)
	(segment
		(start 8.601075 9.432925)
		(end 7.718425 10.315575)
		(width 0.12065)
		(layer "In2.Cu")
		(net "PGRM_JTAG_TCK")
	)
	(segment
		(start 14.305229 14.125575)
		(end 13.871575 14.125575)
		(width 0.12065)
		(layer "In2.Cu")
		(net "PGRM_JTAG_TCK")
	)
	(segment
		(start 9.483725 9.8647)
		(end 9.483725 9.304071)
		(width 0.12065)
		(layer "In2.Cu")
		(net "PGRM_JTAG_TCK")
	)
	(segment
		(start 36.642675 9.961829)
		(end 36.901171 10.220325)
		(width 0.12065)
		(layer "In3.Cu")
		(net "PGRM_JTAG_TCK")
	)
	(segment
		(start 32.286804 9.0297)
		(end 32.340779 8.975725)
		(width 0.12065)
		(layer "In3.Cu")
		(net "PGRM_JTAG_TCK")
	)
	(segment
		(start 22.225 11.938)
		(end 22.479152 11.938)
		(width 0.12065)
		(layer "In3.Cu")
		(net "PGRM_JTAG_TCK")
	)
	(segment
		(start 23.561827 10.855325)
		(end 28.503829 10.855325)
		(width 0.12065)
		(layer "In3.Cu")
		(net "PGRM_JTAG_TCK")
	)
	(segment
		(start 28.82265 10.240823)
		(end 29.798823 9.26465)
		(width 0.12065)
		(layer "In3.Cu")
		(net "PGRM_JTAG_TCK")
	)
	(segment
		(start 30.699431 9.0297)
		(end 32.286804 9.0297)
		(width 0.12065)
		(layer "In3.Cu")
		(net "PGRM_JTAG_TCK")
	)
	(segment
		(start 33.739963 8.975725)
		(end 34.565844 8.149844)
		(width 0.12065)
		(layer "In3.Cu")
		(net "PGRM_JTAG_TCK")
	)
	(segment
		(start 28.503829 10.855325)
		(end 28.762325 10.596829)
		(width 0.12065)
		(layer "In3.Cu")
		(net "PGRM_JTAG_TCK")
	)
	(segment
		(start 37.72535 10.939196)
		(end 37.72535 11.530355)
		(width 0.12065)
		(layer "In3.Cu")
		(net "PGRM_JTAG_TCK")
	)
	(segment
		(start 32.340779 8.975725)
		(end 33.739963 8.975725)
		(width 0.12065)
		(layer "In3.Cu")
		(net "PGRM_JTAG_TCK")
	)
	(segment
		(start 22.479152 11.938)
		(end 23.561827 10.855325)
		(width 0.12065)
		(layer "In3.Cu")
		(net "PGRM_JTAG_TCK")
	)
	(segment
		(start 28.82265 10.480675)
		(end 28.82265 10.240823)
		(width 0.12065)
		(layer "In3.Cu")
		(net "PGRM_JTAG_TCK")
	)
	(segment
		(start 37.72535 11.530355)
		(end 38.737007 12.542012)
		(width 0.12065)
		(layer "In3.Cu")
		(net "PGRM_JTAG_TCK")
	)
	(segment
		(start 35.963225 8.453171)
		(end 35.963225 9.209938)
		(width 0.12065)
		(layer "In3.Cu")
		(net "PGRM_JTAG_TCK")
	)
	(segment
		(start 34.565844 8.149844)
		(end 35.659898 8.149844)
		(width 0.12065)
		(layer "In3.Cu")
		(net "PGRM_JTAG_TCK")
	)
	(segment
		(start 28.762325 10.541)
		(end 28.82265 10.480675)
		(width 0.12065)
		(layer "In3.Cu")
		(net "PGRM_JTAG_TCK")
	)
	(segment
		(start 30.464481 9.26465)
		(end 30.699431 9.0297)
		(width 0.12065)
		(layer "In3.Cu")
		(net "PGRM_JTAG_TCK")
	)
	(segment
		(start 35.659898 8.149844)
		(end 35.963225 8.453171)
		(width 0.12065)
		(layer "In3.Cu")
		(net "PGRM_JTAG_TCK")
	)
	(segment
		(start 29.798823 9.26465)
		(end 30.464481 9.26465)
		(width 0.12065)
		(layer "In3.Cu")
		(net "PGRM_JTAG_TCK")
	)
	(segment
		(start 37.006479 10.220325)
		(end 37.72535 10.939196)
		(width 0.12065)
		(layer "In3.Cu")
		(net "PGRM_JTAG_TCK")
	)
	(segment
		(start 36.642675 9.889388)
		(end 36.642675 9.961829)
		(width 0.12065)
		(layer "In3.Cu")
		(net "PGRM_JTAG_TCK")
	)
	(segment
		(start 36.901171 10.220325)
		(end 37.006479 10.220325)
		(width 0.12065)
		(layer "In3.Cu")
		(net "PGRM_JTAG_TCK")
	)
	(segment
		(start 35.963225 9.209938)
		(end 36.642675 9.889388)
		(width 0.12065)
		(layer "In3.Cu")
		(net "PGRM_JTAG_TCK")
	)
	(segment
		(start 28.762325 10.596829)
		(end 28.762325 10.541)
		(width 0.12065)
		(layer "In3.Cu")
		(net "PGRM_JTAG_TCK")
	)
	(via
		(at 26.924 28.4226)
		(size 0.4572)
		(drill 0.20574)
		(layers "F.Cu" "B.Cu")
		(net "NWK1_MOD_PRES_L")
	)
	(via
		(at 10.3124 4.4069)
		(size 0.508)
		(drill 0.254)
		(layers "F.Cu" "B.Cu")
		(net "NWK1_MOD_PRES_L")
	)
	(segment
		(start 10.9474 5.0419)
		(end 10.3124 4.4069)
		(width 0.147574)
		(layer "B.Cu")
		(net "NWK1_MOD_PRES_L")
	)
	(segment
		(start 27.871801 28.4226)
		(end 28.745993 27.548408)
		(width 0.127)
		(layer "In1.Cu")
		(net "NWK1_MOD_PRES_L")
	)
	(segment
		(start 26.924 28.4226)
		(end 27.871801 28.4226)
		(width 0.127)
		(layer "In1.Cu")
		(net "NWK1_MOD_PRES_L")
	)
	(segment
		(start 9.817735 21.755735)
		(end 9.652 21.59)
		(width 0.12065)
		(layer "In7.Cu")
		(net "NWK1_MOD_PRES_L")
	)
	(segment
		(start 10.108565 23.951565)
		(end 10.107346 23.951565)
		(width 0.12065)
		(layer "In7.Cu")
		(net "NWK1_MOD_PRES_L")
	)
	(segment
		(start 10.3124 4.4196)
		(end 10.3124 4.4069)
		(width 0.12065)
		(layer "In7.Cu")
		(net "NWK1_MOD_PRES_L")
	)
	(segment
		(start 26.924 28.4226)
		(end 27.686 27.6606)
		(width 0.12065)
		(layer "In7.Cu")
		(net "NWK1_MOD_PRES_L")
	)
	(segment
		(start 16.891 21.717)
		(end 15.238146 21.717)
		(width 0.12065)
		(layer "In7.Cu")
		(net "NWK1_MOD_PRES_L")
	)
	(segment
		(start 23.241 22.225)
		(end 21.336 24.13)
		(width 0.12065)
		(layer "In7.Cu")
		(net "NWK1_MOD_PRES_L")
	)
	(segment
		(start 12.954 24.13)
		(end 10.287 24.13)
		(width 0.12065)
		(layer "In7.Cu")
		(net "NWK1_MOD_PRES_L")
	)
	(segment
		(start 9.817735 23.661954)
		(end 9.817735 21.755735)
		(width 0.12065)
		(layer "In7.Cu")
		(net "NWK1_MOD_PRES_L")
	)
	(segment
		(start 13.681075 23.402925)
		(end 12.954 24.13)
		(width 0.12065)
		(layer "In7.Cu")
		(net "NWK1_MOD_PRES_L")
	)
	(segment
		(start 27.686 27.6606)
		(end 27.686 22.86)
		(width 0.12065)
		(layer "In7.Cu")
		(net "NWK1_MOD_PRES_L")
	)
	(segment
		(start 19.84342 23.949025)
		(end 19.27258 23.949025)
		(width 0.12065)
		(layer "In7.Cu")
		(net "NWK1_MOD_PRES_L")
	)
	(segment
		(start 17.653 23.622)
		(end 17.653 22.479)
		(width 0.12065)
		(layer "In7.Cu")
		(net "NWK1_MOD_PRES_L")
	)
	(segment
		(start 15.238146 21.717)
		(end 13.681075 23.274071)
		(width 0.12065)
		(layer "In7.Cu")
		(net "NWK1_MOD_PRES_L")
	)
	(segment
		(start 9.525 5.207)
		(end 10.3124 4.4196)
		(width 0.12065)
		(layer "In7.Cu")
		(net "NWK1_MOD_PRES_L")
	)
	(segment
		(start 17.653 22.479)
		(end 16.891 21.717)
		(width 0.12065)
		(layer "In7.Cu")
		(net "NWK1_MOD_PRES_L")
	)
	(segment
		(start 7.172325 19.692671)
		(end 7.172325 5.400675)
		(width 0.12065)
		(layer "In7.Cu")
		(net "NWK1_MOD_PRES_L")
	)
	(segment
		(start 19.27258 23.949025)
		(end 19.091605 24.13)
		(width 0.12065)
		(layer "In7.Cu")
		(net "NWK1_MOD_PRES_L")
	)
	(segment
		(start 13.681075 23.274071)
		(end 13.681075 23.402925)
		(width 0.12065)
		(layer "In7.Cu")
		(net "NWK1_MOD_PRES_L")
	)
	(segment
		(start 10.287 24.13)
		(end 10.108565 23.951565)
		(width 0.12065)
		(layer "In7.Cu")
		(net "NWK1_MOD_PRES_L")
	)
	(segment
		(start 10.107346 23.951565)
		(end 9.817735 23.661954)
		(width 0.12065)
		(layer "In7.Cu")
		(net "NWK1_MOD_PRES_L")
	)
	(segment
		(start 9.652 21.59)
		(end 8.763 21.59)
		(width 0.12065)
		(layer "In7.Cu")
		(net "NWK1_MOD_PRES_L")
	)
	(segment
		(start 8.509 21.029346)
		(end 7.172325 19.692671)
		(width 0.12065)
		(layer "In7.Cu")
		(net "NWK1_MOD_PRES_L")
	)
	(segment
		(start 27.051 22.225)
		(end 23.241 22.225)
		(width 0.12065)
		(layer "In7.Cu")
		(net "NWK1_MOD_PRES_L")
	)
	(segment
		(start 8.763 21.59)
		(end 8.509 21.336)
		(width 0.12065)
		(layer "In7.Cu")
		(net "NWK1_MOD_PRES_L")
	)
	(segment
		(start 27.686 22.86)
		(end 27.051 22.225)
		(width 0.12065)
		(layer "In7.Cu")
		(net "NWK1_MOD_PRES_L")
	)
	(segment
		(start 7.366 5.207)
		(end 9.525 5.207)
		(width 0.12065)
		(layer "In7.Cu")
		(net "NWK1_MOD_PRES_L")
	)
	(segment
		(start 20.024395 24.13)
		(end 19.84342 23.949025)
		(width 0.12065)
		(layer "In7.Cu")
		(net "NWK1_MOD_PRES_L")
	)
	(segment
		(start 7.172325 5.400675)
		(end 7.366 5.207)
		(width 0.12065)
		(layer "In7.Cu")
		(net "NWK1_MOD_PRES_L")
	)
	(segment
		(start 21.336 24.13)
		(end 20.024395 24.13)
		(width 0.12065)
		(layer "In7.Cu")
		(net "NWK1_MOD_PRES_L")
	)
	(segment
		(start 19.091605 24.13)
		(end 18.161 24.13)
		(width 0.12065)
		(layer "In7.Cu")
		(net "NWK1_MOD_PRES_L")
	)
	(segment
		(start 18.161 24.13)
		(end 17.653 23.622)
		(width 0.12065)
		(layer "In7.Cu")
		(net "NWK1_MOD_PRES_L")
	)
	(segment
		(start 8.509 21.336)
		(end 8.509 21.029346)
		(width 0.12065)
		(layer "In7.Cu")
		(net "NWK1_MOD_PRES_L")
	)
	(segment
		(start 34.925 20.193)
		(end 34.925 20.701)
		(width 0.14732)
		(layer "F.Cu")
		(net "NWK1_LED_LINK_G_L")
	)
	(segment
		(start 36.322 19.939)
		(end 35.179 19.939)
		(width 0.14732)
		(layer "F.Cu")
		(net "NWK1_LED_LINK_G_L")
	)
	(segment
		(start 34.5186 21.1074)
		(end 34.4932 21.1074)
		(width 0.14732)
		(layer "F.Cu")
		(net "NWK1_LED_LINK_G_L")
	)
	(segment
		(start 35.179 19.939)
		(end 34.925 20.193)
		(width 0.14732)
		(layer "F.Cu")
		(net "NWK1_LED_LINK_G_L")
	)
	(segment
		(start 34.925 20.701)
		(end 34.5186 21.1074)
		(width 0.14732)
		(layer "F.Cu")
		(net "NWK1_LED_LINK_G_L")
	)
	(via
		(at 36.322 19.939)
		(size 0.762)
		(drill 0.381)
		(layers "F.Cu" "B.Cu")
		(net "NWK1_LED_LINK_G_L")
	)
	(via
		(at 11.5824 20.9169)
		(size 0.508)
		(drill 0.254)
		(layers "F.Cu" "B.Cu")
		(net "NWK1_LED_LINK_G_L")
	)
	(via
		(at 34.4932 21.1074)
		(size 0.4572)
		(drill 0.20574)
		(layers "F.Cu" "B.Cu")
		(net "NWK1_LED_LINK_G_L")
	)
	(segment
		(start 12.2174 21.5519)
		(end 11.5824 20.9169)
		(width 0.254)
		(layer "B.Cu")
		(net "NWK1_LED_LINK_G_L")
	)
	(segment
		(start 34.4932 21.801201)
		(end 33.746008 22.548393)
		(width 0.127)
		(layer "In1.Cu")
		(net "NWK1_LED_LINK_G_L")
	)
	(segment
		(start 34.4932 21.1074)
		(end 34.4932 21.801201)
		(width 0.127)
		(layer "In1.Cu")
		(net "NWK1_LED_LINK_G_L")
	)
	(segment
		(start 23.431398 22.606)
		(end 22.920325 22.606)
		(width 0.12065)
		(layer "In2.Cu")
		(net "NWK1_LED_LINK_G_L")
	)
	(segment
		(start 34.4932 21.1074)
		(end 34.208745 21.1074)
		(width 0.12065)
		(layer "In2.Cu")
		(net "NWK1_LED_LINK_G_L")
	)
	(segment
		(start 12.411075 21.745575)
		(end 11.5824 20.9169)
		(width 0.12065)
		(layer "In2.Cu")
		(net "NWK1_LED_LINK_G_L")
	)
	(segment
		(start 15.973425 22.577425)
		(end 15.973425 22.069425)
		(width 0.12065)
		(layer "In2.Cu")
		(net "NWK1_LED_LINK_G_L")
	)
	(segment
		(start 33.817204 21.498941)
		(end 26.895704 21.498941)
		(width 0.12065)
		(layer "In2.Cu")
		(net "NWK1_LED_LINK_G_L")
	)
	(segment
		(start 24.912472 22.552025)
		(end 23.485373 22.552025)
		(width 0.12065)
		(layer "In2.Cu")
		(net "NWK1_LED_LINK_G_L")
	)
	(segment
		(start 15.973425 22.069425)
		(end 15.649575 21.745575)
		(width 0.12065)
		(layer "In2.Cu")
		(net "NWK1_LED_LINK_G_L")
	)
	(segment
		(start 21.844 23.682325)
		(end 17.586325 23.682325)
		(width 0.12065)
		(layer "In2.Cu")
		(net "NWK1_LED_LINK_G_L")
	)
	(segment
		(start 17.586325 23.682325)
		(end 16.891 22.987)
		(width 0.12065)
		(layer "In2.Cu")
		(net "NWK1_LED_LINK_G_L")
	)
	(segment
		(start 15.649575 21.745575)
		(end 12.411075 21.745575)
		(width 0.12065)
		(layer "In2.Cu")
		(net "NWK1_LED_LINK_G_L")
	)
	(segment
		(start 22.920325 22.606)
		(end 21.844 23.682325)
		(width 0.12065)
		(layer "In2.Cu")
		(net "NWK1_LED_LINK_G_L")
	)
	(segment
		(start 24.966447 22.606)
		(end 24.912472 22.552025)
		(width 0.12065)
		(layer "In2.Cu")
		(net "NWK1_LED_LINK_G_L")
	)
	(segment
		(start 25.788645 22.606)
		(end 24.966447 22.606)
		(width 0.12065)
		(layer "In2.Cu")
		(net "NWK1_LED_LINK_G_L")
	)
	(segment
		(start 23.485373 22.552025)
		(end 23.431398 22.606)
		(width 0.12065)
		(layer "In2.Cu")
		(net "NWK1_LED_LINK_G_L")
	)
	(segment
		(start 26.895704 21.498941)
		(end 25.788645 22.606)
		(width 0.12065)
		(layer "In2.Cu")
		(net "NWK1_LED_LINK_G_L")
	)
	(segment
		(start 16.891 22.987)
		(end 16.383 22.987)
		(width 0.12065)
		(layer "In2.Cu")
		(net "NWK1_LED_LINK_G_L")
	)
	(segment
		(start 34.208745 21.1074)
		(end 33.817204 21.498941)
		(width 0.12065)
		(layer "In2.Cu")
		(net "NWK1_LED_LINK_G_L")
	)
	(segment
		(start 16.383 22.987)
		(end 15.973425 22.577425)
		(width 0.12065)
		(layer "In2.Cu")
		(net "NWK1_LED_LINK_G_L")
	)
	(segment
		(start 28.745993 28.810407)
		(end 27.7876 29.7434)
		(width 0.127)
		(layer "F.Cu")
		(net "NWK1_LED_ACT_G_L")
	)
	(segment
		(start 28.745993 28.548406)
		(end 28.745993 28.810407)
		(width 0.127)
		(layer "F.Cu")
		(net "NWK1_LED_ACT_G_L")
	)
	(via
		(at 27.7876 29.7434)
		(size 0.4572)
		(drill 0.20574)
		(layers "F.Cu" "B.Cu")
		(net "NWK1_LED_ACT_G_L")
	)
	(via
		(at 28.067 28.956)
		(size 0.762)
		(drill 0.381)
		(layers "F.Cu" "B.Cu")
		(net "NWK1_LED_ACT_G_L")
	)
	(via
		(at 11.5824 19.6469)
		(size 0.508)
		(drill 0.254)
		(layers "F.Cu" "B.Cu")
		(net "NWK1_LED_ACT_G_L")
	)
	(segment
		(start 27.7876 29.7434)
		(end 27.7876 29.2354)
		(width 0.14732)
		(layer "B.Cu")
		(net "NWK1_LED_ACT_G_L")
	)
	(segment
		(start 27.7876 29.2354)
		(end 28.067 28.956)
		(width 0.14732)
		(layer "B.Cu")
		(net "NWK1_LED_ACT_G_L")
	)
	(segment
		(start 12.2174 20.2819)
		(end 11.5824 19.6469)
		(width 0.254)
		(layer "B.Cu")
		(net "NWK1_LED_ACT_G_L")
	)
	(segment
		(start 23.050475 21.780525)
		(end 21.082 23.749)
		(width 0.12065)
		(layer "In7.Cu")
		(net "NWK1_LED_ACT_G_L")
	)
	(segment
		(start 19.993635 23.749)
		(end 19.94601 23.701375)
		(width 0.12065)
		(layer "In7.Cu")
		(net "NWK1_LED_ACT_G_L")
	)
	(segment
		(start 19.94601 23.701375)
		(end 19.16999 23.701375)
		(width 0.12065)
		(layer "In7.Cu")
		(net "NWK1_LED_ACT_G_L")
	)
	(segment
		(start 19.122365 23.749)
		(end 18.288 23.749)
		(width 0.12065)
		(layer "In7.Cu")
		(net "NWK1_LED_ACT_G_L")
	)
	(segment
		(start 26.860525 21.780525)
		(end 26.416 21.336)
		(width 0.12065)
		(layer "In7.Cu")
		(net "NWK1_LED_ACT_G_L")
	)
	(segment
		(start 25.019 21.780525)
		(end 23.050475 21.780525)
		(width 0.12065)
		(layer "In7.Cu")
		(net "NWK1_LED_ACT_G_L")
	)
	(segment
		(start 12.192 20.2565)
		(end 11.642725 19.707225)
		(width 0.12065)
		(layer "In7.Cu")
		(net "NWK1_LED_ACT_G_L")
	)
	(segment
		(start 27.7876 29.7434)
		(end 27.813 29.083)
		(width 0.12065)
		(layer "In7.Cu")
		(net "NWK1_LED_ACT_G_L")
	)
	(segment
		(start 11.642725 19.707225)
		(end 11.642725 19.6469)
		(width 0.12065)
		(layer "In7.Cu")
		(net "NWK1_LED_ACT_G_L")
	)
	(segment
		(start 12.192 21.082)
		(end 12.192 20.2565)
		(width 0.12065)
		(layer "In7.Cu")
		(net "NWK1_LED_ACT_G_L")
	)
	(segment
		(start 25.463525 21.336)
		(end 25.019 21.780525)
		(width 0.12065)
		(layer "In7.Cu")
		(net "NWK1_LED_ACT_G_L")
	)
	(segment
		(start 17.040225 21.358225)
		(end 12.468225 21.358225)
		(width 0.12065)
		(layer "In7.Cu")
		(net "NWK1_LED_ACT_G_L")
	)
	(segment
		(start 17.973675 22.291675)
		(end 17.040225 21.358225)
		(width 0.12065)
		(layer "In7.Cu")
		(net "NWK1_LED_ACT_G_L")
	)
	(segment
		(start 18.288 23.749)
		(end 17.973675 23.434675)
		(width 0.12065)
		(layer "In7.Cu")
		(net "NWK1_LED_ACT_G_L")
	)
	(segment
		(start 19.16999 23.701375)
		(end 19.122365 23.749)
		(width 0.12065)
		(layer "In7.Cu")
		(net "NWK1_LED_ACT_G_L")
	)
	(segment
		(start 27.114525 21.780525)
		(end 26.860525 21.780525)
		(width 0.12065)
		(layer "In7.Cu")
		(net "NWK1_LED_ACT_G_L")
	)
	(segment
		(start 12.468225 21.358225)
		(end 12.192 21.082)
		(width 0.12065)
		(layer "In7.Cu")
		(net "NWK1_LED_ACT_G_L")
	)
	(segment
		(start 11.642725 19.6469)
		(end 11.5824 19.6469)
		(width 0.12065)
		(layer "In7.Cu")
		(net "NWK1_LED_ACT_G_L")
	)
	(segment
		(start 27.813 29.083)
		(end 27.94 28.956)
		(width 0.12065)
		(layer "In7.Cu")
		(net "NWK1_LED_ACT_G_L")
	)
	(segment
		(start 27.94 22.606)
		(end 27.114525 21.780525)
		(width 0.12065)
		(layer "In7.Cu")
		(net "NWK1_LED_ACT_G_L")
	)
	(segment
		(start 17.973675 23.434675)
		(end 17.973675 22.291675)
		(width 0.12065)
		(layer "In7.Cu")
		(net "NWK1_LED_ACT_G_L")
	)
	(segment
		(start 26.416 21.336)
		(end 25.463525 21.336)
		(width 0.12065)
		(layer "In7.Cu")
		(net "NWK1_LED_ACT_G_L")
	)
	(segment
		(start 27.94 28.956)
		(end 27.94 22.606)
		(width 0.12065)
		(layer "In7.Cu")
		(net "NWK1_LED_ACT_G_L")
	)
	(segment
		(start 21.082 23.749)
		(end 19.993635 23.749)
		(width 0.12065)
		(layer "In7.Cu")
		(net "NWK1_LED_ACT_G_L")
	)
	(via
		(at 10.3124 27.2669)
		(size 0.508)
		(drill 0.254)
		(layers "F.Cu" "B.Cu")
		(net "NWK0_MOD_PRES_L")
	)
	(via
		(at 30.5308 26.0858)
		(size 0.4572)
		(drill 0.20574)
		(layers "F.Cu" "B.Cu")
		(net "NWK0_MOD_PRES_L")
	)
	(segment
		(start 10.9474 27.9019)
		(end 10.3124 27.2669)
		(width 0.254)
		(layer "B.Cu")
		(net "NWK0_MOD_PRES_L")
	)
	(segment
		(start 31.242 27.559)
		(end 31.256605 27.559)
		(width 0.12065)
		(layer "In1.Cu")
		(net "NWK0_MOD_PRES_L")
	)
	(segment
		(start 31.256605 27.559)
		(end 31.746012 28.048407)
		(width 0.12065)
		(layer "In1.Cu")
		(net "NWK0_MOD_PRES_L")
	)
	(segment
		(start 30.952059 27.269059)
		(end 31.242 27.559)
		(width 0.12065)
		(layer "In1.Cu")
		(net "NWK0_MOD_PRES_L")
	)
	(segment
		(start 30.5308 26.0858)
		(end 30.952059 26.507059)
		(width 0.12065)
		(layer "In1.Cu")
		(net "NWK0_MOD_PRES_L")
	)
	(segment
		(start 30.952059 26.507059)
		(end 30.952059 27.269059)
		(width 0.12065)
		(layer "In1.Cu")
		(net "NWK0_MOD_PRES_L")
	)
	(segment
		(start 22.981971 27.282775)
		(end 22.099321 28.165425)
		(width 0.12065)
		(layer "In3.Cu")
		(net "NWK0_MOD_PRES_L")
	)
	(segment
		(start 20.292746 27.94)
		(end 18.669 27.94)
		(width 0.12065)
		(layer "In3.Cu")
		(net "NWK0_MOD_PRES_L")
	)
	(segment
		(start 27.432 26.797)
		(end 25.781 26.797)
		(width 0.12065)
		(layer "In3.Cu")
		(net "NWK0_MOD_PRES_L")
	)
	(segment
		(start 18.669 27.94)
		(end 18.288 28.321)
		(width 0.12065)
		(layer "In3.Cu")
		(net "NWK0_MOD_PRES_L")
	)
	(segment
		(start 28.1432 26.0858)
		(end 27.432 26.797)
		(width 0.12065)
		(layer "In3.Cu")
		(net "NWK0_MOD_PRES_L")
	)
	(segment
		(start 25.295225 27.282775)
		(end 22.981971 27.282775)
		(width 0.12065)
		(layer "In3.Cu")
		(net "NWK0_MOD_PRES_L")
	)
	(segment
		(start 22.099321 28.165425)
		(end 20.518171 28.165425)
		(width 0.12065)
		(layer "In3.Cu")
		(net "NWK0_MOD_PRES_L")
	)
	(segment
		(start 30.5308 26.0858)
		(end 28.1432 26.0858)
		(width 0.12065)
		(layer "In3.Cu")
		(net "NWK0_MOD_PRES_L")
	)
	(segment
		(start 18.288 28.321)
		(end 11.3665 28.321)
		(width 0.12065)
		(layer "In3.Cu")
		(net "NWK0_MOD_PRES_L")
	)
	(segment
		(start 25.781 26.797)
		(end 25.295225 27.282775)
		(width 0.12065)
		(layer "In3.Cu")
		(net "NWK0_MOD_PRES_L")
	)
	(segment
		(start 20.518171 28.165425)
		(end 20.292746 27.94)
		(width 0.12065)
		(layer "In3.Cu")
		(net "NWK0_MOD_PRES_L")
	)
	(segment
		(start 11.3665 28.321)
		(end 10.3124 27.2669)
		(width 0.12065)
		(layer "In3.Cu")
		(net "NWK0_MOD_PRES_L")
	)
	(segment
		(start 26.3271 38.608)
		(end 26.3271 39.497)
		(width 0.14732)
		(layer "F.Cu")
		(net "NFP_VDD_CORE_IMON")
	)
	(segment
		(start 26.81699 39.35001)
		(end 28.1686 39.35001)
		(width 0.14732)
		(layer "F.Cu")
		(net "NFP_VDD_CORE_IMON")
	)
	(segment
		(start 26.67 39.497)
		(end 26.81699 39.35001)
		(width 0.14732)
		(layer "F.Cu")
		(net "NFP_VDD_CORE_IMON")
	)
	(segment
		(start 26.3271 39.497)
		(end 26.67 39.497)
		(width 0.14732)
		(layer "F.Cu")
		(net "NFP_VDD_CORE_IMON")
	)
	(via
		(at 26.3271 39.497)
		(size 0.508)
		(drill 0.25654)
		(layers "F.Cu" "B.Cu")
		(net "NFP_VDD_CORE_IMON")
	)
	(segment
		(start 25.781 39.497)
		(end 25.146 38.862)
		(width 0.14732)
		(layer "B.Cu")
		(net "NFP_VDD_CORE_IMON")
	)
	(segment
		(start 26.3271 39.497)
		(end 25.781 39.497)
		(width 0.14732)
		(layer "B.Cu")
		(net "NFP_VDD_CORE_IMON")
	)
	(segment
		(start 32.615708 23.365892)
		(end 32.877557 23.365892)
		(width 0.127)
		(layer "F.Cu")
		(net "NFP_SPI2_SCK")
	)
	(segment
		(start 33.195057 23.048392)
		(end 33.246009 23.048392)
		(width 0.127)
		(layer "F.Cu")
		(net "NFP_SPI2_SCK")
	)
	(segment
		(start 32.877557 23.365892)
		(end 33.195057 23.048392)
		(width 0.127)
		(layer "F.Cu")
		(net "NFP_SPI2_SCK")
	)
	(segment
		(start 32.3342 23.6474)
		(end 32.615708 23.365892)
		(width 0.127)
		(layer "F.Cu")
		(net "NFP_SPI2_SCK")
	)
	(via
		(at 32.3342 23.6474)
		(size 0.4572)
		(drill 0.20574)
		(layers "F.Cu" "B.Cu")
		(net "NFP_SPI2_SCK")
	)
	(via
		(at 42.737024 25.541986)
		(size 0.4826)
		(drill 0.20574)
		(layers "F.Cu" "B.Cu")
		(net "NFP_SPI2_SCK")
	)
	(segment
		(start 42.237025 26.042112)
		(end 42.237025 26.041985)
		(width 0.14732)
		(layer "B.Cu")
		(net "NFP_SPI2_SCK")
	)
	(segment
		(start 42.237025 26.041985)
		(end 42.737024 25.541986)
		(width 0.14732)
		(layer "B.Cu")
		(net "NFP_SPI2_SCK")
	)
	(segment
		(start 42.214038 25.019)
		(end 42.737024 25.541986)
		(width 0.12065)
		(layer "In6.Cu")
		(net "NFP_SPI2_SCK")
	)
	(segment
		(start 32.6644 23.6474)
		(end 33.030541 24.013541)
		(width 0.12065)
		(layer "In6.Cu")
		(net "NFP_SPI2_SCK")
	)
	(segment
		(start 32.3342 23.6474)
		(end 32.6644 23.6474)
		(width 0.12065)
		(layer "In6.Cu")
		(net "NFP_SPI2_SCK")
	)
	(segment
		(start 36.459541 24.140541)
		(end 37.338 25.019)
		(width 0.12065)
		(layer "In6.Cu")
		(net "NFP_SPI2_SCK")
	)
	(segment
		(start 37.338 25.019)
		(end 42.214038 25.019)
		(width 0.12065)
		(layer "In6.Cu")
		(net "NFP_SPI2_SCK")
	)
	(segment
		(start 33.030541 24.013541)
		(end 35.143796 24.013541)
		(width 0.12065)
		(layer "In6.Cu")
		(net "NFP_SPI2_SCK")
	)
	(segment
		(start 35.143796 24.013541)
		(end 35.270796 24.140541)
		(width 0.12065)
		(layer "In6.Cu")
		(net "NFP_SPI2_SCK")
	)
	(segment
		(start 35.270796 24.140541)
		(end 36.459541 24.140541)
		(width 0.12065)
		(layer "In6.Cu")
		(net "NFP_SPI2_SCK")
	)
	(segment
		(start 28.2067 20.7645)
		(end 28.2067 21.509101)
		(width 0.127)
		(layer "F.Cu")
		(net "NFP_SPI2_MOSI")
	)
	(segment
		(start 28.2067 21.509101)
		(end 28.745993 22.048394)
		(width 0.127)
		(layer "F.Cu")
		(net "NFP_SPI2_MOSI")
	)
	(segment
		(start 28.6512 20.2692)
		(end 28.2067 20.7645)
		(width 0.127)
		(layer "F.Cu")
		(net "NFP_SPI2_MOSI")
	)
	(via
		(at 40.737003 19.541998)
		(size 0.4826)
		(drill 0.20574)
		(layers "F.Cu" "B.Cu")
		(net "NFP_SPI2_MOSI")
	)
	(via
		(at 28.6512 20.2692)
		(size 0.4572)
		(drill 0.20574)
		(layers "F.Cu" "B.Cu")
		(net "NFP_SPI2_MOSI")
	)
	(segment
		(start 40.8559 18.558002)
		(end 40.817927 19.461074)
		(width 0.14732)
		(layer "B.Cu")
		(net "NFP_SPI2_MOSI")
	)
	(segment
		(start 40.817927 19.461074)
		(end 40.737003 19.541998)
		(width 0.14732)
		(layer "B.Cu")
		(net "NFP_SPI2_MOSI")
	)
	(segment
		(start 36.449 19.431)
		(end 37.049075 18.830925)
		(width 0.12065)
		(layer "In6.Cu")
		(net "NFP_SPI2_MOSI")
	)
	(segment
		(start 37.049075 18.830925)
		(end 40.293925 18.830925)
		(width 0.12065)
		(layer "In6.Cu")
		(net "NFP_SPI2_MOSI")
	)
	(segment
		(start 28.6512 20.2692)
		(end 29.4894 19.431)
		(width 0.12065)
		(layer "In6.Cu")
		(net "NFP_SPI2_MOSI")
	)
	(segment
		(start 29.4894 19.431)
		(end 36.449 19.431)
		(width 0.12065)
		(layer "In6.Cu")
		(net "NFP_SPI2_MOSI")
	)
	(segment
		(start 40.737003 19.274003)
		(end 40.737003 19.541998)
		(width 0.12065)
		(layer "In6.Cu")
		(net "NFP_SPI2_MOSI")
	)
	(segment
		(start 40.293925 18.830925)
		(end 40.737003 19.274003)
		(width 0.12065)
		(layer "In6.Cu")
		(net "NFP_SPI2_MOSI")
	)
	(segment
		(start 40.237004 17.042003)
		(end 39.737005 16.542004)
		(width 0.13208)
		(layer "F.Cu")
		(net "NFP_SPI2_MISO")
	)
	(via
		(at 39.737005 16.542004)
		(size 0.4826)
		(drill 0.25654)
		(layers "F.Cu" "B.Cu")
		(net "NFP_SPI2_MISO")
	)
	(via
		(at 32.8168 21.1074)
		(size 0.4572)
		(drill 0.20574)
		(layers "F.Cu" "B.Cu")
		(net "NFP_SPI2_MISO")
	)
	(segment
		(start 32.8168 21.1074)
		(end 32.8168 22.119184)
		(width 0.127)
		(layer "In1.Cu")
		(net "NFP_SPI2_MISO")
	)
	(segment
		(start 32.8168 22.119184)
		(end 33.246009 22.548393)
		(width 0.127)
		(layer "In1.Cu")
		(net "NFP_SPI2_MISO")
	)
	(segment
		(start 39.243 17.399025)
		(end 39.243 18.034)
		(width 0.12065)
		(layer "In2.Cu")
		(net "NFP_SPI2_MISO")
	)
	(segment
		(start 39.737005 16.542004)
		(end 39.737005 16.905021)
		(width 0.12065)
		(layer "In2.Cu")
		(net "NFP_SPI2_MISO")
	)
	(segment
		(start 32.8168 21.1201)
		(end 32.8168 21.1074)
		(width 0.12065)
		(layer "In2.Cu")
		(net "NFP_SPI2_MISO")
	)
	(segment
		(start 32.8295 21.1328)
		(end 32.8168 21.1201)
		(width 0.12065)
		(layer "In2.Cu")
		(net "NFP_SPI2_MISO")
	)
	(segment
		(start 35.066859 20.432141)
		(end 34.798 20.701)
		(width 0.12065)
		(layer "In2.Cu")
		(net "NFP_SPI2_MISO")
	)
	(segment
		(start 33.401 20.701)
		(end 32.9692 21.1328)
		(width 0.12065)
		(layer "In2.Cu")
		(net "NFP_SPI2_MISO")
	)
	(segment
		(start 39.737005 16.905021)
		(end 39.243 17.399025)
		(width 0.12065)
		(layer "In2.Cu")
		(net "NFP_SPI2_MISO")
	)
	(segment
		(start 34.798 20.701)
		(end 33.401 20.701)
		(width 0.12065)
		(layer "In2.Cu")
		(net "NFP_SPI2_MISO")
	)
	(segment
		(start 36.576 20.066)
		(end 35.311055 20.066)
		(width 0.12065)
		(layer "In2.Cu")
		(net "NFP_SPI2_MISO")
	)
	(segment
		(start 35.311055 20.066)
		(end 35.066859 20.310196)
		(width 0.12065)
		(layer "In2.Cu")
		(net "NFP_SPI2_MISO")
	)
	(segment
		(start 35.066859 20.310196)
		(end 35.066859 20.432141)
		(width 0.12065)
		(layer "In2.Cu")
		(net "NFP_SPI2_MISO")
	)
	(segment
		(start 36.946459 19.695541)
		(end 36.576 20.066)
		(width 0.12065)
		(layer "In2.Cu")
		(net "NFP_SPI2_MISO")
	)
	(segment
		(start 39.243 18.034)
		(end 37.581459 19.695541)
		(width 0.12065)
		(layer "In2.Cu")
		(net "NFP_SPI2_MISO")
	)
	(segment
		(start 37.581459 19.695541)
		(end 36.946459 19.695541)
		(width 0.12065)
		(layer "In2.Cu")
		(net "NFP_SPI2_MISO")
	)
	(segment
		(start 32.9692 21.1328)
		(end 32.8295 21.1328)
		(width 0.12065)
		(layer "In2.Cu")
		(net "NFP_SPI2_MISO")
	)
	(segment
		(start 29.155441 21.391575)
		(end 29.155441 21.408441)
		(width 0.127)
		(layer "F.Cu")
		(net "NFP_SPI2_CS")
	)
	(segment
		(start 29.0449 20.7391)
		(end 29.0449 21.281034)
		(width 0.127)
		(layer "F.Cu")
		(net "NFP_SPI2_CS")
	)
	(segment
		(start 29.0449 21.281034)
		(end 29.155441 21.391575)
		(width 0.127)
		(layer "F.Cu")
		(net "NFP_SPI2_CS")
	)
	(segment
		(start 29.464 20.2692)
		(end 29.0449 20.7391)
		(width 0.127)
		(layer "F.Cu")
		(net "NFP_SPI2_CS")
	)
	(segment
		(start 29.464 20.2692)
		(end 29.464 19.431)
		(width 0.14732)
		(layer "F.Cu")
		(net "NFP_SPI2_CS")
	)
	(segment
		(start 29.745991 21.998991)
		(end 29.745991 22.048394)
		(width 0.127)
		(layer "F.Cu")
		(net "NFP_SPI2_CS")
	)
	(segment
		(start 40.237004 16.042005)
		(end 39.737005 15.542006)
		(width 0.13208)
		(layer "F.Cu")
		(net "NFP_SPI2_CS")
	)
	(segment
		(start 29.155441 21.408441)
		(end 29.745991 21.998991)
		(width 0.127)
		(layer "F.Cu")
		(net "NFP_SPI2_CS")
	)
	(via
		(at 39.737005 15.542006)
		(size 0.4826)
		(drill 0.20574)
		(layers "F.Cu" "B.Cu")
		(net "NFP_SPI2_CS")
	)
	(via
		(at 29.464 19.431)
		(size 0.762)
		(drill 0.381)
		(layers "F.Cu" "B.Cu")
		(net "NFP_SPI2_CS")
	)
	(via
		(at 29.464 20.2692)
		(size 0.4572)
		(drill 0.20574)
		(layers "F.Cu" "B.Cu")
		(net "NFP_SPI2_CS")
	)
	(segment
		(start 29.464 20.193)
		(end 29.845 19.812)
		(width 0.12065)
		(layer "In2.Cu")
		(net "NFP_SPI2_CS")
	)
	(segment
		(start 34.798 19.812)
		(end 37.465 17.145)
		(width 0.12065)
		(layer "In2.Cu")
		(net "NFP_SPI2_CS")
	)
	(segment
		(start 38.862 17.145)
		(end 39.150011 16.856989)
		(width 0.12065)
		(layer "In2.Cu")
		(net "NFP_SPI2_CS")
	)
	(segment
		(start 29.464 20.2692)
		(end 29.464 20.193)
		(width 0.12065)
		(layer "In2.Cu")
		(net "NFP_SPI2_CS")
	)
	(segment
		(start 37.465 17.145)
		(end 38.862 17.145)
		(width 0.12065)
		(layer "In2.Cu")
		(net "NFP_SPI2_CS")
	)
	(segment
		(start 29.845 19.812)
		(end 34.798 19.812)
		(width 0.12065)
		(layer "In2.Cu")
		(net "NFP_SPI2_CS")
	)
	(segment
		(start 39.737005 15.88897)
		(end 39.737005 15.542006)
		(width 0.12065)
		(layer "In2.Cu")
		(net "NFP_SPI2_CS")
	)
	(segment
		(start 39.150011 16.475964)
		(end 39.737005 15.88897)
		(width 0.12065)
		(layer "In2.Cu")
		(net "NFP_SPI2_CS")
	)
	(segment
		(start 39.150011 16.856989)
		(end 39.150011 16.475964)
		(width 0.12065)
		(layer "In2.Cu")
		(net "NFP_SPI2_CS")
	)
	(segment
		(start 36.3601 6.35)
		(end 37.084 6.35)
		(width 0.099314)
		(layer "F.Cu")
		(net "NFP_SERDES012_SYSCLK_IN_P")
	)
	(segment
		(start 46.236992 10.041992)
		(end 45.736993 9.541993)
		(width 0.099314)
		(layer "F.Cu")
		(net "NFP_SERDES012_SYSCLK_IN_P")
	)
	(via
		(at 45.736993 9.541993)
		(size 0.4826)
		(drill 0.20574)
		(layers "F.Cu" "B.Cu")
		(net "NFP_SERDES012_SYSCLK_IN_P")
	)
	(via
		(at 37.084 6.35)
		(size 0.508)
		(drill 0.2667)
		(layers "F.Cu" "B.Cu")
		(net "NFP_SERDES012_SYSCLK_IN_P")
	)
	(segment
		(start 46.237017 10.042017)
		(end 46.237017 10.042144)
		(width 0.099314)
		(layer "B.Cu")
		(net "NFP_SERDES012_SYSCLK_IN_P")
	)
	(segment
		(start 45.736993 9.541993)
		(end 46.237017 10.042017)
		(width 0.099314)
		(layer "B.Cu")
		(net "NFP_SERDES012_SYSCLK_IN_P")
	)
	(segment
		(start 38.278816 6.638265)
		(end 37.372265 6.638265)
		(width 0.095758)
		(layer "In3.Cu")
		(net "NFP_SERDES012_SYSCLK_IN_P")
	)
	(segment
		(start 42.341902 8.770976)
		(end 42.341902 7.291375)
		(width 0.095758)
		(layer "In3.Cu")
		(net "NFP_SERDES012_SYSCLK_IN_P")
	)
	(segment
		(start 42.504995 8.934069)
		(end 42.341902 8.770976)
		(width 0.095758)
		(layer "In3.Cu")
		(net "NFP_SERDES012_SYSCLK_IN_P")
	)
	(segment
		(start 45.129069 8.934069)
		(end 42.504995 8.934069)
		(width 0.095758)
		(layer "In3.Cu")
		(net "NFP_SERDES012_SYSCLK_IN_P")
	)
	(segment
		(start 41.9846 6.934073)
		(end 38.574624 6.934073)
		(width 0.095758)
		(layer "In3.Cu")
		(net "NFP_SERDES012_SYSCLK_IN_P")
	)
	(segment
		(start 37.372265 6.638265)
		(end 37.271325 6.537325)
		(width 0.095758)
		(layer "In3.Cu")
		(net "NFP_SERDES012_SYSCLK_IN_P")
	)
	(segment
		(start 37.271325 6.537325)
		(end 37.084 6.35)
		(width 0.096012)
		(layer "In3.Cu")
		(net "NFP_SERDES012_SYSCLK_IN_P")
	)
	(segment
		(start 45.736993 9.541993)
		(end 45.129069 8.934069)
		(width 0.095758)
		(layer "In3.Cu")
		(net "NFP_SERDES012_SYSCLK_IN_P")
	)
	(segment
		(start 38.574624 6.934073)
		(end 38.278816 6.638265)
		(width 0.095758)
		(layer "In3.Cu")
		(net "NFP_SERDES012_SYSCLK_IN_P")
	)
	(segment
		(start 42.341902 7.291375)
		(end 41.9846 6.934073)
		(width 0.095758)
		(layer "In3.Cu")
		(net "NFP_SERDES012_SYSCLK_IN_P")
	)
	(segment
		(start 36.3601 7.493)
		(end 37.084 7.493)
		(width 0.099314)
		(layer "F.Cu")
		(net "NFP_SERDES012_SYSCLK_IN_N")
	)
	(segment
		(start 45.236994 10.041992)
		(end 44.736995 9.541993)
		(width 0.099314)
		(layer "F.Cu")
		(net "NFP_SERDES012_SYSCLK_IN_N")
	)
	(via
		(at 44.736995 9.541993)
		(size 0.4826)
		(drill 0.20574)
		(layers "F.Cu" "B.Cu")
		(net "NFP_SERDES012_SYSCLK_IN_N")
	)
	(via
		(at 37.084 7.493)
		(size 0.508)
		(drill 0.2667)
		(layers "F.Cu" "B.Cu")
		(net "NFP_SERDES012_SYSCLK_IN_N")
	)
	(segment
		(start 45.237019 10.042017)
		(end 45.237019 10.042144)
		(width 0.099314)
		(layer "B.Cu")
		(net "NFP_SERDES012_SYSCLK_IN_N")
	)
	(segment
		(start 44.736995 9.541993)
		(end 45.237019 10.042017)
		(width 0.099314)
		(layer "B.Cu")
		(net "NFP_SERDES012_SYSCLK_IN_N")
	)
	(segment
		(start 37.326214 6.849466)
		(end 37.084 7.09168)
		(width 0.096012)
		(layer "In3.Cu")
		(net "NFP_SERDES012_SYSCLK_IN_N")
	)
	(segment
		(start 37.327484 6.848196)
		(end 37.326214 6.849466)
		(width 0.095758)
		(layer "In3.Cu")
		(net "NFP_SERDES012_SYSCLK_IN_N")
	)
	(segment
		(start 44.986626 9.525)
		(end 45.085 9.426626)
		(width 0.095758)
		(layer "In3.Cu")
		(net "NFP_SERDES012_SYSCLK_IN_N")
	)
	(segment
		(start 44.985051 9.148191)
		(end 42.416247 9.148191)
		(width 0.095758)
		(layer "In3.Cu")
		(net "NFP_SERDES012_SYSCLK_IN_N")
	)
	(segment
		(start 41.895852 7.148195)
		(end 38.485877 7.148195)
		(width 0.095758)
		(layer "In3.Cu")
		(net "NFP_SERDES012_SYSCLK_IN_N")
	)
	(segment
		(start 42.12778 7.380122)
		(end 41.895852 7.148195)
		(width 0.095758)
		(layer "In3.Cu")
		(net "NFP_SERDES012_SYSCLK_IN_N")
	)
	(segment
		(start 37.084 7.09168)
		(end 37.084 7.493)
		(width 0.096012)
		(layer "In3.Cu")
		(net "NFP_SERDES012_SYSCLK_IN_N")
	)
	(segment
		(start 42.416247 9.148191)
		(end 42.12778 8.859723)
		(width 0.095758)
		(layer "In3.Cu")
		(net "NFP_SERDES012_SYSCLK_IN_N")
	)
	(segment
		(start 45.085 9.426626)
		(end 45.085 9.24814)
		(width 0.095758)
		(layer "In3.Cu")
		(net "NFP_SERDES012_SYSCLK_IN_N")
	)
	(segment
		(start 42.12778 8.859723)
		(end 42.12778 7.380122)
		(width 0.095758)
		(layer "In3.Cu")
		(net "NFP_SERDES012_SYSCLK_IN_N")
	)
	(segment
		(start 44.753987 9.525)
		(end 44.986626 9.525)
		(width 0.095758)
		(layer "In3.Cu")
		(net "NFP_SERDES012_SYSCLK_IN_N")
	)
	(segment
		(start 44.736995 9.541993)
		(end 44.753987 9.525)
		(width 0.095758)
		(layer "In3.Cu")
		(net "NFP_SERDES012_SYSCLK_IN_N")
	)
	(segment
		(start 38.485877 7.148195)
		(end 38.185877 6.848196)
		(width 0.095758)
		(layer "In3.Cu")
		(net "NFP_SERDES012_SYSCLK_IN_N")
	)
	(segment
		(start 45.085 9.24814)
		(end 44.985051 9.148191)
		(width 0.095758)
		(layer "In3.Cu")
		(net "NFP_SERDES012_SYSCLK_IN_N")
	)
	(segment
		(start 38.185877 6.848196)
		(end 37.327484 6.848196)
		(width 0.095758)
		(layer "In3.Cu")
		(net "NFP_SERDES012_SYSCLK_IN_N")
	)
	(segment
		(start 51.237007 4.042004)
		(end 50.737008 3.542005)
		(width 0.099314)
		(layer "F.Cu")
		(net "NFP_SERDES0_TX0_P")
	)
	(via
		(at 10.3124 22.1869)
		(size 0.508)
		(drill 0.254)
		(layers "F.Cu" "B.Cu")
		(net "NFP_SERDES0_TX0_P")
	)
	(via
		(at 50.737008 3.542005)
		(size 0.4826)
		(drill 0.20574)
		(layers "F.Cu" "B.Cu")
		(net "NFP_SERDES0_TX0_P")
	)
	(segment
		(start 10.9474 22.8219)
		(end 10.3124 22.1869)
		(width 0.099314)
		(layer "B.Cu")
		(net "NFP_SERDES0_TX0_P")
	)
	(segment
		(start 42.367048 1.797685)
		(end 42.367048 1.82372)
		(width 0.095758)
		(layer "In7.Cu")
		(net "NFP_SERDES0_TX0_P")
	)
	(segment
		(start 50.34407 3.934943)
		(end 50.737008 3.542005)
		(width 0.095758)
		(layer "In7.Cu")
		(net "NFP_SERDES0_TX0_P")
	)
	(segment
		(start 10.3124 22.1869)
		(end 10.3124 22.585045)
		(width 0.096012)
		(layer "In7.Cu")
		(net "NFP_SERDES0_TX0_P")
	)
	(segment
		(start 27.158848 5.58165)
		(end 28.600502 5.58165)
		(width 0.096012)
		(layer "In7.Cu")
		(net "NFP_SERDES0_TX0_P")
	)
	(segment
		(start 10.709275 22.691725)
		(end 10.88771 22.51329)
		(width 0.096012)
		(layer "In7.Cu")
		(net "NFP_SERDES0_TX0_P")
	)
	(segment
		(start 10.88771 22.51329)
		(end 10.88771 16.819118)
		(width 0.096012)
		(layer "In7.Cu")
		(net "NFP_SERDES0_TX0_P")
	)
	(segment
		(start 32.152692 1.00711)
		(end 41.785819 1.00711)
		(width 0.096012)
		(layer "In7.Cu")
		(net "NFP_SERDES0_TX0_P")
	)
	(segment
		(start 42.367048 1.82372)
		(end 42.343934 1.846834)
		(width 0.095758)
		(layer "In7.Cu")
		(net "NFP_SERDES0_TX0_P")
	)
	(segment
		(start 31.496 1.663802)
		(end 32.152692 1.00711)
		(width 0.096012)
		(layer "In7.Cu")
		(net "NFP_SERDES0_TX0_P")
	)
	(segment
		(start 42.913757 4.934814)
		(end 46.899703 4.934814)
		(width 0.095758)
		(layer "In7.Cu")
		(net "NFP_SERDES0_TX0_P")
	)
	(segment
		(start 21.40331 6.041492)
		(end 22.377502 5.0673)
		(width 0.096012)
		(layer "In7.Cu")
		(net "NFP_SERDES0_TX0_P")
	)
	(segment
		(start 19.304 9.525)
		(end 21.40331 7.42569)
		(width 0.096012)
		(layer "In7.Cu")
		(net "NFP_SERDES0_TX0_P")
	)
	(segment
		(start 25.888848 4.31165)
		(end 27.158848 5.58165)
		(width 0.096012)
		(layer "In7.Cu")
		(net "NFP_SERDES0_TX0_P")
	)
	(segment
		(start 24.149152 4.31165)
		(end 25.888848 4.31165)
		(width 0.096012)
		(layer "In7.Cu")
		(net "NFP_SERDES0_TX0_P")
	)
	(segment
		(start 42.343934 1.846834)
		(end 42.343934 4.36499)
		(width 0.095758)
		(layer "In7.Cu")
		(net "NFP_SERDES0_TX0_P")
	)
	(segment
		(start 28.600578 5.581726)
		(end 28.708274 5.581726)
		(width 0.096012)
		(layer "In7.Cu")
		(net "NFP_SERDES0_TX0_P")
	)
	(segment
		(start 19.304 10.668)
		(end 19.304 9.525)
		(width 0.096012)
		(layer "In7.Cu")
		(net "NFP_SERDES0_TX0_P")
	)
	(segment
		(start 22.377502 5.0673)
		(end 23.393502 5.0673)
		(width 0.096012)
		(layer "In7.Cu")
		(net "NFP_SERDES0_TX0_P")
	)
	(segment
		(start 11.294618 16.41221)
		(end 16.747592 16.41221)
		(width 0.096012)
		(layer "In7.Cu")
		(net "NFP_SERDES0_TX0_P")
	)
	(segment
		(start 16.747592 16.41221)
		(end 17.09674 16.063062)
		(width 0.096012)
		(layer "In7.Cu")
		(net "NFP_SERDES0_TX0_P")
	)
	(segment
		(start 10.88771 16.819118)
		(end 11.294618 16.41221)
		(width 0.096012)
		(layer "In7.Cu")
		(net "NFP_SERDES0_TX0_P")
	)
	(segment
		(start 42.343934 4.36499)
		(end 42.913757 4.934814)
		(width 0.095758)
		(layer "In7.Cu")
		(net "NFP_SERDES0_TX0_P")
	)
	(segment
		(start 21.40331 7.42569)
		(end 21.40331 6.041492)
		(width 0.096012)
		(layer "In7.Cu")
		(net "NFP_SERDES0_TX0_P")
	)
	(segment
		(start 46.899703 4.934814)
		(end 47.129802 4.704715)
		(width 0.095758)
		(layer "In7.Cu")
		(net "NFP_SERDES0_TX0_P")
	)
	(segment
		(start 47.129802 4.704715)
		(end 47.129802 4.290797)
		(width 0.095758)
		(layer "In7.Cu")
		(net "NFP_SERDES0_TX0_P")
	)
	(segment
		(start 28.708274 5.581726)
		(end 31.496 2.794)
		(width 0.096012)
		(layer "In7.Cu")
		(net "NFP_SERDES0_TX0_P")
	)
	(segment
		(start 28.600502 5.58165)
		(end 28.600578 5.581726)
		(width 0.096012)
		(layer "In7.Cu")
		(net "NFP_SERDES0_TX0_P")
	)
	(segment
		(start 10.41908 22.691725)
		(end 10.709275 22.691725)
		(width 0.096012)
		(layer "In7.Cu")
		(net "NFP_SERDES0_TX0_P")
	)
	(segment
		(start 31.496 2.794)
		(end 31.496 1.663802)
		(width 0.096012)
		(layer "In7.Cu")
		(net "NFP_SERDES0_TX0_P")
	)
	(segment
		(start 41.785819 1.00711)
		(end 42.367048 1.588338)
		(width 0.096012)
		(layer "In7.Cu")
		(net "NFP_SERDES0_TX0_P")
	)
	(segment
		(start 47.129802 4.290797)
		(end 47.485656 3.934943)
		(width 0.095758)
		(layer "In7.Cu")
		(net "NFP_SERDES0_TX0_P")
	)
	(segment
		(start 10.3124 22.585045)
		(end 10.41908 22.691725)
		(width 0.096012)
		(layer "In7.Cu")
		(net "NFP_SERDES0_TX0_P")
	)
	(segment
		(start 47.485656 3.934943)
		(end 50.34407 3.934943)
		(width 0.095758)
		(layer "In7.Cu")
		(net "NFP_SERDES0_TX0_P")
	)
	(segment
		(start 17.09674 12.87526)
		(end 19.304 10.668)
		(width 0.096012)
		(layer "In7.Cu")
		(net "NFP_SERDES0_TX0_P")
	)
	(segment
		(start 17.09674 16.063062)
		(end 17.09674 12.87526)
		(width 0.096012)
		(layer "In7.Cu")
		(net "NFP_SERDES0_TX0_P")
	)
	(segment
		(start 23.393502 5.0673)
		(end 24.149152 4.31165)
		(width 0.096012)
		(layer "In7.Cu")
		(net "NFP_SERDES0_TX0_P")
	)
	(segment
		(start 42.367048 1.588338)
		(end 42.367048 1.797685)
		(width 0.096012)
		(layer "In7.Cu")
		(net "NFP_SERDES0_TX0_P")
	)
	(segment
		(start 51.237007 5.042002)
		(end 50.737008 4.542003)
		(width 0.099314)
		(layer "F.Cu")
		(net "NFP_SERDES0_TX0_N")
	)
	(via
		(at 50.737008 4.542003)
		(size 0.4826)
		(drill 0.25654)
		(layers "F.Cu" "B.Cu")
		(net "NFP_SERDES0_TX0_N")
	)
	(via
		(at 10.3124 23.4569)
		(size 0.508)
		(drill 0.254)
		(layers "F.Cu" "B.Cu")
		(net "NFP_SERDES0_TX0_N")
	)
	(segment
		(start 10.9474 24.0919)
		(end 10.3124 23.4569)
		(width 0.099314)
		(layer "B.Cu")
		(net "NFP_SERDES0_TX0_N")
	)
	(segment
		(start 50.34407 4.149065)
		(end 47.574403 4.149065)
		(width 0.095758)
		(layer "In7.Cu")
		(net "NFP_SERDES0_TX0_N")
	)
	(segment
		(start 41.677971 1.26746)
		(end 32.26054 1.26746)
		(width 0.096012)
		(layer "In7.Cu")
		(net "NFP_SERDES0_TX0_N")
	)
	(segment
		(start 23.50135 5.32765)
		(end 22.48535 5.32765)
		(width 0.096012)
		(layer "In7.Cu")
		(net "NFP_SERDES0_TX0_N")
	)
	(segment
		(start 19.56435 10.775848)
		(end 17.35709 12.983108)
		(width 0.096012)
		(layer "In7.Cu")
		(net "NFP_SERDES0_TX0_N")
	)
	(segment
		(start 11.14806 22.621138)
		(end 10.817123 22.952075)
		(width 0.096012)
		(layer "In7.Cu")
		(net "NFP_SERDES0_TX0_N")
	)
	(segment
		(start 31.75635 2.901848)
		(end 28.816122 5.842076)
		(width 0.096012)
		(layer "In7.Cu")
		(net "NFP_SERDES0_TX0_N")
	)
	(segment
		(start 17.35709 12.983108)
		(end 17.35709 16.17091)
		(width 0.096012)
		(layer "In7.Cu")
		(net "NFP_SERDES0_TX0_N")
	)
	(segment
		(start 22.48535 5.32765)
		(end 21.66366 6.14934)
		(width 0.096012)
		(layer "In7.Cu")
		(net "NFP_SERDES0_TX0_N")
	)
	(segment
		(start 17.35709 16.17091)
		(end 16.85544 16.67256)
		(width 0.096012)
		(layer "In7.Cu")
		(net "NFP_SERDES0_TX0_N")
	)
	(segment
		(start 10.3124 23.058755)
		(end 10.3124 23.4569)
		(width 0.096012)
		(layer "In7.Cu")
		(net "NFP_SERDES0_TX0_N")
	)
	(segment
		(start 47.574403 4.149065)
		(end 47.343924 4.379544)
		(width 0.095758)
		(layer "In7.Cu")
		(net "NFP_SERDES0_TX0_N")
	)
	(segment
		(start 42.106698 1.82372)
		(end 42.106698 1.797685)
		(width 0.095758)
		(layer "In7.Cu")
		(net "NFP_SERDES0_TX0_N")
	)
	(segment
		(start 21.66366 6.14934)
		(end 21.66366 7.533538)
		(width 0.096012)
		(layer "In7.Cu")
		(net "NFP_SERDES0_TX0_N")
	)
	(segment
		(start 42.82501 5.148936)
		(end 42.129812 4.453738)
		(width 0.095758)
		(layer "In7.Cu")
		(net "NFP_SERDES0_TX0_N")
	)
	(segment
		(start 24.257 4.572)
		(end 23.50135 5.32765)
		(width 0.096012)
		(layer "In7.Cu")
		(net "NFP_SERDES0_TX0_N")
	)
	(segment
		(start 28.492653 5.842)
		(end 27.051 5.842)
		(width 0.096012)
		(layer "In7.Cu")
		(net "NFP_SERDES0_TX0_N")
	)
	(segment
		(start 11.14806 16.926966)
		(end 11.14806 22.621138)
		(width 0.096012)
		(layer "In7.Cu")
		(net "NFP_SERDES0_TX0_N")
	)
	(segment
		(start 27.051 5.842)
		(end 25.781 4.572)
		(width 0.096012)
		(layer "In7.Cu")
		(net "NFP_SERDES0_TX0_N")
	)
	(segment
		(start 19.56435 9.632848)
		(end 19.56435 10.775848)
		(width 0.096012)
		(layer "In7.Cu")
		(net "NFP_SERDES0_TX0_N")
	)
	(segment
		(start 50.737008 4.542003)
		(end 50.34407 4.149065)
		(width 0.095758)
		(layer "In7.Cu")
		(net "NFP_SERDES0_TX0_N")
	)
	(segment
		(start 31.75635 1.77165)
		(end 31.75635 2.901848)
		(width 0.096012)
		(layer "In7.Cu")
		(net "NFP_SERDES0_TX0_N")
	)
	(segment
		(start 10.41908 22.952075)
		(end 10.3124 23.058755)
		(width 0.096012)
		(layer "In7.Cu")
		(net "NFP_SERDES0_TX0_N")
	)
	(segment
		(start 32.26054 1.26746)
		(end 31.75635 1.77165)
		(width 0.096012)
		(layer "In7.Cu")
		(net "NFP_SERDES0_TX0_N")
	)
	(segment
		(start 28.492729 5.842076)
		(end 28.492653 5.842)
		(width 0.096012)
		(layer "In7.Cu")
		(net "NFP_SERDES0_TX0_N")
	)
	(segment
		(start 46.988451 5.148936)
		(end 42.82501 5.148936)
		(width 0.095758)
		(layer "In7.Cu")
		(net "NFP_SERDES0_TX0_N")
	)
	(segment
		(start 25.781 4.572)
		(end 24.257 4.572)
		(width 0.096012)
		(layer "In7.Cu")
		(net "NFP_SERDES0_TX0_N")
	)
	(segment
		(start 42.106698 1.696187)
		(end 41.677971 1.26746)
		(width 0.096012)
		(layer "In7.Cu")
		(net "NFP_SERDES0_TX0_N")
	)
	(segment
		(start 47.343924 4.379544)
		(end 47.343924 4.793463)
		(width 0.095758)
		(layer "In7.Cu")
		(net "NFP_SERDES0_TX0_N")
	)
	(segment
		(start 21.66366 7.533538)
		(end 19.56435 9.632848)
		(width 0.096012)
		(layer "In7.Cu")
		(net "NFP_SERDES0_TX0_N")
	)
	(segment
		(start 16.85544 16.67256)
		(end 11.402466 16.67256)
		(width 0.096012)
		(layer "In7.Cu")
		(net "NFP_SERDES0_TX0_N")
	)
	(segment
		(start 42.129812 1.846834)
		(end 42.106698 1.82372)
		(width 0.095758)
		(layer "In7.Cu")
		(net "NFP_SERDES0_TX0_N")
	)
	(segment
		(start 42.106698 1.797685)
		(end 42.106698 1.696187)
		(width 0.096012)
		(layer "In7.Cu")
		(net "NFP_SERDES0_TX0_N")
	)
	(segment
		(start 42.129812 4.453738)
		(end 42.129812 1.846834)
		(width 0.095758)
		(layer "In7.Cu")
		(net "NFP_SERDES0_TX0_N")
	)
	(segment
		(start 28.816122 5.842076)
		(end 28.492729 5.842076)
		(width 0.096012)
		(layer "In7.Cu")
		(net "NFP_SERDES0_TX0_N")
	)
	(segment
		(start 11.402466 16.67256)
		(end 11.14806 16.926966)
		(width 0.096012)
		(layer "In7.Cu")
		(net "NFP_SERDES0_TX0_N")
	)
	(segment
		(start 47.343924 4.793463)
		(end 46.988451 5.148936)
		(width 0.095758)
		(layer "In7.Cu")
		(net "NFP_SERDES0_TX0_N")
	)
	(segment
		(start 10.817123 22.952075)
		(end 10.41908 22.952075)
		(width 0.096012)
		(layer "In7.Cu")
		(net "NFP_SERDES0_TX0_N")
	)
	(segment
		(start 51.237007 7.041998)
		(end 50.737008 6.541999)
		(width 0.099314)
		(layer "F.Cu")
		(net "NFP_SERDES0_RX0_P")
	)
	(via
		(at 11.5824 24.7269)
		(size 0.508)
		(drill 0.254)
		(layers "F.Cu" "B.Cu")
		(net "NFP_SERDES0_RX0_P")
	)
	(via
		(at 50.737008 6.541999)
		(size 0.4826)
		(drill 0.20574)
		(layers "F.Cu" "B.Cu")
		(net "NFP_SERDES0_RX0_P")
	)
	(segment
		(start 12.2174 25.3619)
		(end 11.5824 24.7269)
		(width 0.099314)
		(layer "B.Cu")
		(net "NFP_SERDES0_RX0_P")
	)
	(segment
		(start 38.403149 7.934808)
		(end 38.380035 7.911694)
		(width 0.095758)
		(layer "In6.Cu")
		(net "NFP_SERDES0_RX0_P")
	)
	(segment
		(start 16.445103 25.231725)
		(end 15.96771 25.709118)
		(width 0.096012)
		(layer "In6.Cu")
		(net "NFP_SERDES0_RX0_P")
	)
	(segment
		(start 23.763275 14.611883)
		(end 23.563351 14.611883)
		(width 0.096012)
		(layer "In6.Cu")
		(net "NFP_SERDES0_RX0_P")
	)
	(segment
		(start 22.08911 18.199964)
		(end 21.499424 18.78965)
		(width 0.096012)
		(layer "In6.Cu")
		(net "NFP_SERDES0_RX0_P")
	)
	(segment
		(start 38.354 7.911694)
		(end 38.329997 7.911694)
		(width 0.096012)
		(layer "In6.Cu")
		(net "NFP_SERDES0_RX0_P")
	)
	(segment
		(start 27.305 11.663274)
		(end 25.706934 13.26134)
		(width 0.096012)
		(layer "In6.Cu")
		(net "NFP_SERDES0_RX0_P")
	)
	(segment
		(start 18.84934 23.581436)
		(end 17.199051 25.231725)
		(width 0.096012)
		(layer "In6.Cu")
		(net "NFP_SERDES0_RX0_P")
	)
	(segment
		(start 23.04034 15.134895)
		(end 23.04034 16.07566)
		(width 0.096012)
		(layer "In6.Cu")
		(net "NFP_SERDES0_RX0_P")
	)
	(segment
		(start 25.113818 13.26134)
		(end 23.763275 14.611883)
		(width 0.096012)
		(layer "In6.Cu")
		(net "NFP_SERDES0_RX0_P")
	)
	(segment
		(start 19.11477 22.046108)
		(end 18.84934 22.311538)
		(width 0.096012)
		(layer "In6.Cu")
		(net "NFP_SERDES0_RX0_P")
	)
	(segment
		(start 50.737008 6.541999)
		(end 50.34407 6.934937)
		(width 0.095758)
		(layer "In6.Cu")
		(net "NFP_SERDES0_RX0_P")
	)
	(segment
		(start 12.087225 25.231725)
		(end 11.5824 24.7269)
		(width 0.096012)
		(layer "In6.Cu")
		(net "NFP_SERDES0_RX0_P")
	)
	(segment
		(start 50.34407 6.934937)
		(end 48.30412 6.934937)
		(width 0.095758)
		(layer "In6.Cu")
		(net "NFP_SERDES0_RX0_P")
	)
	(segment
		(start 25.706934 13.26134)
		(end 25.113818 13.26134)
		(width 0.096012)
		(layer "In6.Cu")
		(net "NFP_SERDES0_RX0_P")
	)
	(segment
		(start 33.401 8.636)
		(end 29.718 8.636)
		(width 0.096012)
		(layer "In6.Cu")
		(net "NFP_SERDES0_RX0_P")
	)
	(segment
		(start 12.32535 26.904848)
		(end 12.538608 26.69159)
		(width 0.096012)
		(layer "In6.Cu")
		(net "NFP_SERDES0_RX0_P")
	)
	(segment
		(start 14.410182 26.69159)
		(end 14.81709 26.284682)
		(width 0.096012)
		(layer "In6.Cu")
		(net "NFP_SERDES0_RX0_P")
	)
	(segment
		(start 27.305 8.89)
		(end 27.305 11.663274)
		(width 0.096012)
		(layer "In6.Cu")
		(net "NFP_SERDES0_RX0_P")
	)
	(segment
		(start 19.60118 19.76882)
		(end 19.60118 20.338186)
		(width 0.096012)
		(layer "In6.Cu")
		(net "NFP_SERDES0_RX0_P")
	)
	(segment
		(start 38.314351 7.92734)
		(end 34.10966 7.92734)
		(width 0.096012)
		(layer "In6.Cu")
		(net "NFP_SERDES0_RX0_P")
	)
	(segment
		(start 15.767152 28.06065)
		(end 12.680848 28.06065)
		(width 0.096012)
		(layer "In6.Cu")
		(net "NFP_SERDES0_RX0_P")
	)
	(segment
		(start 15.96771 25.709118)
		(end 15.96771 27.860092)
		(width 0.096012)
		(layer "In6.Cu")
		(net "NFP_SERDES0_RX0_P")
	)
	(segment
		(start 18.84934 22.311538)
		(end 18.84934 23.581436)
		(width 0.096012)
		(layer "In6.Cu")
		(net "NFP_SERDES0_RX0_P")
	)
	(segment
		(start 15.96771 27.860092)
		(end 15.767152 28.06065)
		(width 0.096012)
		(layer "In6.Cu")
		(net "NFP_SERDES0_RX0_P")
	)
	(segment
		(start 17.199051 25.231725)
		(end 16.445103 25.231725)
		(width 0.096012)
		(layer "In6.Cu")
		(net "NFP_SERDES0_RX0_P")
	)
	(segment
		(start 20.58035 18.78965)
		(end 19.60118 19.76882)
		(width 0.096012)
		(layer "In6.Cu")
		(net "NFP_SERDES0_RX0_P")
	)
	(segment
		(start 38.329997 7.911694)
		(end 38.314351 7.92734)
		(width 0.096012)
		(layer "In6.Cu")
		(net "NFP_SERDES0_RX0_P")
	)
	(segment
		(start 12.32535 27.705152)
		(end 12.32535 26.904848)
		(width 0.096012)
		(layer "In6.Cu")
		(net "NFP_SERDES0_RX0_P")
	)
	(segment
		(start 14.81709 25.709118)
		(end 14.339697 25.231725)
		(width 0.096012)
		(layer "In6.Cu")
		(net "NFP_SERDES0_RX0_P")
	)
	(segment
		(start 29.718 8.636)
		(end 29.464 8.382)
		(width 0.096012)
		(layer "In6.Cu")
		(net "NFP_SERDES0_RX0_P")
	)
	(segment
		(start 38.380035 7.911694)
		(end 38.354 7.911694)
		(width 0.095758)
		(layer "In6.Cu")
		(net "NFP_SERDES0_RX0_P")
	)
	(segment
		(start 22.08911 17.02689)
		(end 22.08911 18.199964)
		(width 0.096012)
		(layer "In6.Cu")
		(net "NFP_SERDES0_RX0_P")
	)
	(segment
		(start 19.11477 20.824596)
		(end 19.11477 22.046108)
		(width 0.096012)
		(layer "In6.Cu")
		(net "NFP_SERDES0_RX0_P")
	)
	(segment
		(start 48.30412 6.934937)
		(end 47.304249 7.934808)
		(width 0.095758)
		(layer "In6.Cu")
		(net "NFP_SERDES0_RX0_P")
	)
	(segment
		(start 21.499424 18.78965)
		(end 20.58035 18.78965)
		(width 0.096012)
		(layer "In6.Cu")
		(net "NFP_SERDES0_RX0_P")
	)
	(segment
		(start 23.04034 16.07566)
		(end 22.08911 17.02689)
		(width 0.096012)
		(layer "In6.Cu")
		(net "NFP_SERDES0_RX0_P")
	)
	(segment
		(start 14.81709 26.284682)
		(end 14.81709 25.709118)
		(width 0.096012)
		(layer "In6.Cu")
		(net "NFP_SERDES0_RX0_P")
	)
	(segment
		(start 29.464 8.382)
		(end 27.813 8.382)
		(width 0.096012)
		(layer "In6.Cu")
		(net "NFP_SERDES0_RX0_P")
	)
	(segment
		(start 19.60118 20.338186)
		(end 19.11477 20.824596)
		(width 0.096012)
		(layer "In6.Cu")
		(net "NFP_SERDES0_RX0_P")
	)
	(segment
		(start 12.538608 26.69159)
		(end 14.410182 26.69159)
		(width 0.096012)
		(layer "In6.Cu")
		(net "NFP_SERDES0_RX0_P")
	)
	(segment
		(start 34.10966 7.92734)
		(end 33.401 8.636)
		(width 0.096012)
		(layer "In6.Cu")
		(net "NFP_SERDES0_RX0_P")
	)
	(segment
		(start 12.680848 28.06065)
		(end 12.32535 27.705152)
		(width 0.096012)
		(layer "In6.Cu")
		(net "NFP_SERDES0_RX0_P")
	)
	(segment
		(start 14.339697 25.231725)
		(end 12.087225 25.231725)
		(width 0.096012)
		(layer "In6.Cu")
		(net "NFP_SERDES0_RX0_P")
	)
	(segment
		(start 23.563351 14.611883)
		(end 23.04034 15.134895)
		(width 0.096012)
		(layer "In6.Cu")
		(net "NFP_SERDES0_RX0_P")
	)
	(segment
		(start 47.304249 7.934808)
		(end 38.403149 7.934808)
		(width 0.095758)
		(layer "In6.Cu")
		(net "NFP_SERDES0_RX0_P")
	)
	(segment
		(start 27.813 8.382)
		(end 27.305 8.89)
		(width 0.096012)
		(layer "In6.Cu")
		(net "NFP_SERDES0_RX0_P")
	)
	(segment
		(start 51.237007 8.041996)
		(end 50.737008 7.541997)
		(width 0.099314)
		(layer "F.Cu")
		(net "NFP_SERDES0_RX0_N")
	)
	(via
		(at 50.737008 7.541997)
		(size 0.4826)
		(drill 0.25654)
		(layers "F.Cu" "B.Cu")
		(net "NFP_SERDES0_RX0_N")
	)
	(via
		(at 11.5824 25.9969)
		(size 0.508)
		(drill 0.254)
		(layers "F.Cu" "B.Cu")
		(net "NFP_SERDES0_RX0_N")
	)
	(segment
		(start 12.2174 26.6319)
		(end 11.5824 25.9969)
		(width 0.099314)
		(layer "B.Cu")
		(net "NFP_SERDES0_RX0_N")
	)
	(segment
		(start 38.329997 8.172044)
		(end 38.314351 8.18769)
		(width 0.096012)
		(layer "In6.Cu")
		(net "NFP_SERDES0_RX0_N")
	)
	(segment
		(start 27.56535 11.771122)
		(end 25.814782 13.52169)
		(width 0.096012)
		(layer "In6.Cu")
		(net "NFP_SERDES0_RX0_N")
	)
	(segment
		(start 17.3069 25.492075)
		(end 16.552951 25.492075)
		(width 0.096012)
		(layer "In6.Cu")
		(net "NFP_SERDES0_RX0_N")
	)
	(segment
		(start 12.573 28.321)
		(end 12.065 27.813)
		(width 0.096012)
		(layer "In6.Cu")
		(net "NFP_SERDES0_RX0_N")
	)
	(segment
		(start 27.920848 8.64235)
		(end 27.56535 8.997848)
		(width 0.096012)
		(layer "In6.Cu")
		(net "NFP_SERDES0_RX0_N")
	)
	(segment
		(start 12.065 26.797)
		(end 12.43076 26.43124)
		(width 0.096012)
		(layer "In6.Cu")
		(net "NFP_SERDES0_RX0_N")
	)
	(segment
		(start 19.86153 20.446035)
		(end 19.37512 20.932445)
		(width 0.096012)
		(layer "In6.Cu")
		(net "NFP_SERDES0_RX0_N")
	)
	(segment
		(start 14.55674 26.176834)
		(end 14.55674 25.816966)
		(width 0.096012)
		(layer "In6.Cu")
		(net "NFP_SERDES0_RX0_N")
	)
	(segment
		(start 15.875 28.321)
		(end 12.573 28.321)
		(width 0.096012)
		(layer "In6.Cu")
		(net "NFP_SERDES0_RX0_N")
	)
	(segment
		(start 20.688198 19.05)
		(end 19.86153 19.876668)
		(width 0.096012)
		(layer "In6.Cu")
		(net "NFP_SERDES0_RX0_N")
	)
	(segment
		(start 25.814782 13.52169)
		(end 25.221667 13.52169)
		(width 0.096012)
		(layer "In6.Cu")
		(net "NFP_SERDES0_RX0_N")
	)
	(segment
		(start 27.56535 8.997848)
		(end 27.56535 11.771122)
		(width 0.096012)
		(layer "In6.Cu")
		(net "NFP_SERDES0_RX0_N")
	)
	(segment
		(start 34.217508 8.18769)
		(end 33.508848 8.89635)
		(width 0.096012)
		(layer "In6.Cu")
		(net "NFP_SERDES0_RX0_N")
	)
	(segment
		(start 16.22806 27.96794)
		(end 15.875 28.321)
		(width 0.096012)
		(layer "In6.Cu")
		(net "NFP_SERDES0_RX0_N")
	)
	(segment
		(start 47.392996 8.14893)
		(end 38.403149 8.14893)
		(width 0.095758)
		(layer "In6.Cu")
		(net "NFP_SERDES0_RX0_N")
	)
	(segment
		(start 19.10969 22.419386)
		(end 19.10969 23.689285)
		(width 0.096012)
		(layer "In6.Cu")
		(net "NFP_SERDES0_RX0_N")
	)
	(segment
		(start 16.552951 25.492075)
		(end 16.22806 25.816966)
		(width 0.096012)
		(layer "In6.Cu")
		(net "NFP_SERDES0_RX0_N")
	)
	(segment
		(start 23.30069 16.183508)
		(end 22.34946 17.134738)
		(width 0.096012)
		(layer "In6.Cu")
		(net "NFP_SERDES0_RX0_N")
	)
	(segment
		(start 14.55674 25.816966)
		(end 14.231849 25.492075)
		(width 0.096012)
		(layer "In6.Cu")
		(net "NFP_SERDES0_RX0_N")
	)
	(segment
		(start 33.508848 8.89635)
		(end 29.610152 8.89635)
		(width 0.096012)
		(layer "In6.Cu")
		(net "NFP_SERDES0_RX0_N")
	)
	(segment
		(start 14.231849 25.492075)
		(end 12.087225 25.492075)
		(width 0.096012)
		(layer "In6.Cu")
		(net "NFP_SERDES0_RX0_N")
	)
	(segment
		(start 19.37512 20.932445)
		(end 19.37512 22.153956)
		(width 0.096012)
		(layer "In6.Cu")
		(net "NFP_SERDES0_RX0_N")
	)
	(segment
		(start 29.356152 8.64235)
		(end 27.920848 8.64235)
		(width 0.096012)
		(layer "In6.Cu")
		(net "NFP_SERDES0_RX0_N")
	)
	(segment
		(start 38.403149 8.14893)
		(end 38.380035 8.172044)
		(width 0.095758)
		(layer "In6.Cu")
		(net "NFP_SERDES0_RX0_N")
	)
	(segment
		(start 50.737008 7.541997)
		(end 50.34407 7.149059)
		(width 0.095758)
		(layer "In6.Cu")
		(net "NFP_SERDES0_RX0_N")
	)
	(segment
		(start 25.221667 13.52169)
		(end 23.871123 14.872233)
		(width 0.096012)
		(layer "In6.Cu")
		(net "NFP_SERDES0_RX0_N")
	)
	(segment
		(start 12.43076 26.43124)
		(end 14.302334 26.43124)
		(width 0.096012)
		(layer "In6.Cu")
		(net "NFP_SERDES0_RX0_N")
	)
	(segment
		(start 50.34407 7.149059)
		(end 48.392867 7.149059)
		(width 0.095758)
		(layer "In6.Cu")
		(net "NFP_SERDES0_RX0_N")
	)
	(segment
		(start 19.37512 22.153956)
		(end 19.10969 22.419386)
		(width 0.096012)
		(layer "In6.Cu")
		(net "NFP_SERDES0_RX0_N")
	)
	(segment
		(start 38.354 8.172044)
		(end 38.329997 8.172044)
		(width 0.096012)
		(layer "In6.Cu")
		(net "NFP_SERDES0_RX0_N")
	)
	(segment
		(start 19.10969 23.689285)
		(end 17.3069 25.492075)
		(width 0.096012)
		(layer "In6.Cu")
		(net "NFP_SERDES0_RX0_N")
	)
	(segment
		(start 38.380035 8.172044)
		(end 38.354 8.172044)
		(width 0.095758)
		(layer "In6.Cu")
		(net "NFP_SERDES0_RX0_N")
	)
	(segment
		(start 14.302334 26.43124)
		(end 14.55674 26.176834)
		(width 0.096012)
		(layer "In6.Cu")
		(net "NFP_SERDES0_RX0_N")
	)
	(segment
		(start 23.871123 14.872233)
		(end 23.6712 14.872233)
		(width 0.096012)
		(layer "In6.Cu")
		(net "NFP_SERDES0_RX0_N")
	)
	(segment
		(start 29.610152 8.89635)
		(end 29.356152 8.64235)
		(width 0.096012)
		(layer "In6.Cu")
		(net "NFP_SERDES0_RX0_N")
	)
	(segment
		(start 12.065 27.813)
		(end 12.065 26.797)
		(width 0.096012)
		(layer "In6.Cu")
		(net "NFP_SERDES0_RX0_N")
	)
	(segment
		(start 19.86153 19.876668)
		(end 19.86153 20.446035)
		(width 0.096012)
		(layer "In6.Cu")
		(net "NFP_SERDES0_RX0_N")
	)
	(segment
		(start 12.087225 25.492075)
		(end 11.5824 25.9969)
		(width 0.096012)
		(layer "In6.Cu")
		(net "NFP_SERDES0_RX0_N")
	)
	(segment
		(start 21.607272 19.05)
		(end 20.688198 19.05)
		(width 0.096012)
		(layer "In6.Cu")
		(net "NFP_SERDES0_RX0_N")
	)
	(segment
		(start 23.30069 15.242743)
		(end 23.30069 16.183508)
		(width 0.096012)
		(layer "In6.Cu")
		(net "NFP_SERDES0_RX0_N")
	)
	(segment
		(start 48.392867 7.149059)
		(end 47.392996 8.14893)
		(width 0.095758)
		(layer "In6.Cu")
		(net "NFP_SERDES0_RX0_N")
	)
	(segment
		(start 22.34946 18.307812)
		(end 21.607272 19.05)
		(width 0.096012)
		(layer "In6.Cu")
		(net "NFP_SERDES0_RX0_N")
	)
	(segment
		(start 16.22806 25.816966)
		(end 16.22806 27.96794)
		(width 0.096012)
		(layer "In6.Cu")
		(net "NFP_SERDES0_RX0_N")
	)
	(segment
		(start 22.34946 17.134738)
		(end 22.34946 18.307812)
		(width 0.096012)
		(layer "In6.Cu")
		(net "NFP_SERDES0_RX0_N")
	)
	(segment
		(start 38.314351 8.18769)
		(end 34.217508 8.18769)
		(width 0.096012)
		(layer "In6.Cu")
		(net "NFP_SERDES0_RX0_N")
	)
	(segment
		(start 23.6712 14.872233)
		(end 23.30069 15.242743)
		(width 0.096012)
		(layer "In6.Cu")
		(net "NFP_SERDES0_RX0_N")
	)
	(segment
		(start 35.206889 22.587509)
		(end 34.746006 23.048392)
		(width 0.127)
		(layer "F.Cu")
		(net "NFP_REF_CLK_156M_EN")
	)
	(segment
		(start 36.2712 22.1234)
		(end 35.807091 22.587509)
		(width 0.127)
		(layer "F.Cu")
		(net "NFP_REF_CLK_156M_EN")
	)
	(segment
		(start 32.6771 1.8669)
		(end 33.274 1.8669)
		(width 0.14732)
		(layer "F.Cu")
		(net "NFP_REF_CLK_156M_EN")
	)
	(segment
		(start 35.807091 22.587509)
		(end 35.206889 22.587509)
		(width 0.127)
		(layer "F.Cu")
		(net "NFP_REF_CLK_156M_EN")
	)
	(segment
		(start 32.512 2.032)
		(end 32.6771 1.8669)
		(width 0.14732)
		(layer "F.Cu")
		(net "NFP_REF_CLK_156M_EN")
	)
	(segment
		(start 32.385 2.032)
		(end 32.512 2.032)
		(width 0.14732)
		(layer "F.Cu")
		(net "NFP_REF_CLK_156M_EN")
	)
	(via
		(at 36.2712 22.1234)
		(size 0.4572)
		(drill 0.20574)
		(layers "F.Cu" "B.Cu")
		(net "NFP_REF_CLK_156M_EN")
	)
	(via
		(at 29.718 10.16)
		(size 0.508)
		(drill 0.2667)
		(layers "F.Cu" "B.Cu")
		(net "NFP_REF_CLK_156M_EN")
	)
	(via
		(at 32.385 2.032)
		(size 0.508)
		(drill 0.254)
		(layers "F.Cu" "B.Cu")
		(net "NFP_REF_CLK_156M_EN")
	)
	(via
		(at 37.084 10.922)
		(size 0.508)
		(drill 0.254)
		(layers "F.Cu" "B.Cu")
		(net "NFP_REF_CLK_156M_EN")
	)
	(segment
		(start 30.099 9.779)
		(end 34.671 9.779)
		(width 0.12065)
		(layer "In6.Cu")
		(net "NFP_REF_CLK_156M_EN")
	)
	(segment
		(start 35.814 10.922)
		(end 37.084 10.922)
		(width 0.12065)
		(layer "In6.Cu")
		(net "NFP_REF_CLK_156M_EN")
	)
	(segment
		(start 29.718 10.16)
		(end 30.099 9.779)
		(width 0.12065)
		(layer "In6.Cu")
		(net "NFP_REF_CLK_156M_EN")
	)
	(segment
		(start 34.671 9.779)
		(end 35.814 10.922)
		(width 0.12065)
		(layer "In6.Cu")
		(net "NFP_REF_CLK_156M_EN")
	)
	(segment
		(start 32.512 2.159)
		(end 32.385 2.032)
		(width 0.12065)
		(layer "In7.Cu")
		(net "NFP_REF_CLK_156M_EN")
	)
	(segment
		(start 31.242 4.826)
		(end 32.512 3.556)
		(width 0.12065)
		(layer "In7.Cu")
		(net "NFP_REF_CLK_156M_EN")
	)
	(segment
		(start 31.242 8.636)
		(end 31.242 4.826)
		(width 0.12065)
		(layer "In7.Cu")
		(net "NFP_REF_CLK_156M_EN")
	)
	(segment
		(start 29.718 10.16)
		(end 31.242 8.636)
		(width 0.12065)
		(layer "In7.Cu")
		(net "NFP_REF_CLK_156M_EN")
	)
	(segment
		(start 37.592 16.51)
		(end 36.2712 17.8308)
		(width 0.12065)
		(layer "In7.Cu")
		(net "NFP_REF_CLK_156M_EN")
	)
	(segment
		(start 37.084 10.922)
		(end 37.592 11.557)
		(width 0.12065)
		(layer "In7.Cu")
		(net "NFP_REF_CLK_156M_EN")
	)
	(segment
		(start 32.512 3.556)
		(end 32.512 2.159)
		(width 0.12065)
		(layer "In7.Cu")
		(net "NFP_REF_CLK_156M_EN")
	)
	(segment
		(start 37.592 11.557)
		(end 37.592 16.51)
		(width 0.12065)
		(layer "In7.Cu")
		(net "NFP_REF_CLK_156M_EN")
	)
	(segment
		(start 36.2712 17.8308)
		(end 36.2712 22.1234)
		(width 0.12065)
		(layer "In7.Cu")
		(net "NFP_REF_CLK_156M_EN")
	)
	(segment
		(start 33.746008 24.04839)
		(end 33.738718 24.0411)
		(width 0.127)
		(layer "F.Cu")
		(net "NFP_REF_CLK_100M_EN")
	)
	(segment
		(start 28.321 9.144)
		(end 28.1559 8.9789)
		(width 0.14732)
		(layer "F.Cu")
		(net "NFP_REF_CLK_100M_EN")
	)
	(segment
		(start 33.738718 24.0411)
		(end 32.7533 24.0411)
		(width 0.127)
		(layer "F.Cu")
		(net "NFP_REF_CLK_100M_EN")
	)
	(segment
		(start 28.1559 8.9789)
		(end 28.1559 8.255)
		(width 0.14732)
		(layer "F.Cu")
		(net "NFP_REF_CLK_100M_EN")
	)
	(segment
		(start 32.7533 24.0411)
		(end 32.3342 24.4602)
		(width 0.127)
		(layer "F.Cu")
		(net "NFP_REF_CLK_100M_EN")
	)
	(via
		(at 28.321 9.144)
		(size 0.508)
		(drill 0.2667)
		(layers "F.Cu" "B.Cu")
		(net "NFP_REF_CLK_100M_EN")
	)
	(via
		(at 32.3342 24.4602)
		(size 0.4572)
		(drill 0.20574)
		(layers "F.Cu" "B.Cu")
		(net "NFP_REF_CLK_100M_EN")
	)
	(segment
		(start 28.829 13.843)
		(end 27.432 15.24)
		(width 0.12065)
		(layer "In6.Cu")
		(net "NFP_REF_CLK_100M_EN")
	)
	(segment
		(start 22.987076 20.446924)
		(end 21.717076 20.446924)
		(width 0.12065)
		(layer "In6.Cu")
		(net "NFP_REF_CLK_100M_EN")
	)
	(segment
		(start 21.142325 21.021675)
		(end 21.142325 21.904325)
		(width 0.12065)
		(layer "In6.Cu")
		(net "NFP_REF_CLK_100M_EN")
	)
	(segment
		(start 28.321 9.144)
		(end 28.829 9.652)
		(width 0.12065)
		(layer "In6.Cu")
		(net "NFP_REF_CLK_100M_EN")
	)
	(segment
		(start 27.432 16.002)
		(end 22.987076 20.446924)
		(width 0.12065)
		(layer "In6.Cu")
		(net "NFP_REF_CLK_100M_EN")
	)
	(segment
		(start 27.213204 24.068659)
		(end 31.307659 24.068659)
		(width 0.12065)
		(layer "In6.Cu")
		(net "NFP_REF_CLK_100M_EN")
	)
	(segment
		(start 31.6992 24.4602)
		(end 32.3342 24.4602)
		(width 0.12065)
		(layer "In6.Cu")
		(net "NFP_REF_CLK_100M_EN")
	)
	(segment
		(start 31.307659 24.068659)
		(end 31.6992 24.4602)
		(width 0.12065)
		(layer "In6.Cu")
		(net "NFP_REF_CLK_100M_EN")
	)
	(segment
		(start 21.717076 20.446924)
		(end 21.142325 21.021675)
		(width 0.12065)
		(layer "In6.Cu")
		(net "NFP_REF_CLK_100M_EN")
	)
	(segment
		(start 27.086204 23.941659)
		(end 27.213204 24.068659)
		(width 0.12065)
		(layer "In6.Cu")
		(net "NFP_REF_CLK_100M_EN")
	)
	(segment
		(start 27.432 15.24)
		(end 27.432 16.002)
		(width 0.12065)
		(layer "In6.Cu")
		(net "NFP_REF_CLK_100M_EN")
	)
	(segment
		(start 23.179659 23.941659)
		(end 27.086204 23.941659)
		(width 0.12065)
		(layer "In6.Cu")
		(net "NFP_REF_CLK_100M_EN")
	)
	(segment
		(start 28.829 9.652)
		(end 28.829 13.843)
		(width 0.12065)
		(layer "In6.Cu")
		(net "NFP_REF_CLK_100M_EN")
	)
	(segment
		(start 21.142325 21.904325)
		(end 23.179659 23.941659)
		(width 0.12065)
		(layer "In6.Cu")
		(net "NFP_REF_CLK_100M_EN")
	)
	(segment
		(start 32.766 20.2946)
		(end 32.3977 20.6375)
		(width 0.127)
		(layer "F.Cu")
		(net "NFP_PCIE0_RESET_OUT_L")
	)
	(segment
		(start 32.3977 21.896705)
		(end 32.246011 22.048394)
		(width 0.127)
		(layer "F.Cu")
		(net "NFP_PCIE0_RESET_OUT_L")
	)
	(segment
		(start 32.3977 20.6375)
		(end 32.3977 21.896705)
		(width 0.127)
		(layer "F.Cu")
		(net "NFP_PCIE0_RESET_OUT_L")
	)
	(via
		(at 32.766 20.2946)
		(size 0.4572)
		(drill 0.20574)
		(layers "F.Cu" "B.Cu")
		(net "NFP_PCIE0_RESET_OUT_L")
	)
	(via
		(at 40.737003 20.541996)
		(size 0.4826)
		(drill 0.25654)
		(layers "F.Cu" "B.Cu")
		(net "NFP_PCIE0_RESET_OUT_L")
	)
	(segment
		(start 40.737003 20.541996)
		(end 41.212999 20.066)
		(width 0.14732)
		(layer "B.Cu")
		(net "NFP_PCIE0_RESET_OUT_L")
	)
	(segment
		(start 41.212999 20.066)
		(end 41.91 20.066)
		(width 0.14732)
		(layer "B.Cu")
		(net "NFP_PCIE0_RESET_OUT_L")
	)
	(segment
		(start 42.237152 20.393152)
		(end 42.237152 21.041995)
		(width 0.14732)
		(layer "B.Cu")
		(net "NFP_PCIE0_RESET_OUT_L")
	)
	(segment
		(start 41.91 20.066)
		(end 42.237152 20.393152)
		(width 0.14732)
		(layer "B.Cu")
		(net "NFP_PCIE0_RESET_OUT_L")
	)
	(segment
		(start 39.910004 20.066)
		(end 38.1 20.066)
		(width 0.12065)
		(layer "In6.Cu")
		(net "NFP_PCIE0_RESET_OUT_L")
	)
	(segment
		(start 35.620604 20.863941)
		(end 34.960941 20.863941)
		(width 0.12065)
		(layer "In6.Cu")
		(net "NFP_PCIE0_RESET_OUT_L")
	)
	(segment
		(start 34.960941 20.863941)
		(end 34.798 20.701)
		(width 0.12065)
		(layer "In6.Cu")
		(net "NFP_PCIE0_RESET_OUT_L")
	)
	(segment
		(start 35.794086 20.690459)
		(end 35.620604 20.863941)
		(width 0.12065)
		(layer "In6.Cu")
		(net "NFP_PCIE0_RESET_OUT_L")
	)
	(segment
		(start 33.1724 20.701)
		(end 32.766 20.2946)
		(width 0.12065)
		(layer "In6.Cu")
		(net "NFP_PCIE0_RESET_OUT_L")
	)
	(segment
		(start 40.386 20.541996)
		(end 39.910004 20.066)
		(width 0.12065)
		(layer "In6.Cu")
		(net "NFP_PCIE0_RESET_OUT_L")
	)
	(segment
		(start 34.798 20.701)
		(end 33.1724 20.701)
		(width 0.12065)
		(layer "In6.Cu")
		(net "NFP_PCIE0_RESET_OUT_L")
	)
	(segment
		(start 37.475541 20.690459)
		(end 35.794086 20.690459)
		(width 0.12065)
		(layer "In6.Cu")
		(net "NFP_PCIE0_RESET_OUT_L")
	)
	(segment
		(start 40.737003 20.541996)
		(end 40.386 20.541996)
		(width 0.12065)
		(layer "In6.Cu")
		(net "NFP_PCIE0_RESET_OUT_L")
	)
	(segment
		(start 38.1 20.066)
		(end 37.475541 20.690459)
		(width 0.12065)
		(layer "In6.Cu")
		(net "NFP_PCIE0_RESET_OUT_L")
	)
	(segment
		(start 40.237004 15.042007)
		(end 39.737005 14.542008)
		(width 0.13208)
		(layer "F.Cu")
		(net "NFP_JTAG_ARM_TRST_L")
	)
	(via
		(at 40.894 46.736)
		(size 0.508)
		(drill 0.25654)
		(layers "F.Cu" "B.Cu")
		(net "NFP_JTAG_ARM_TRST_L")
	)
	(via
		(at 39.737005 27.542007)
		(size 0.4826)
		(drill 0.20574)
		(layers "F.Cu" "B.Cu")
		(net "NFP_JTAG_ARM_TRST_L")
	)
	(via
		(at 39.737005 14.542008)
		(size 0.4826)
		(drill 0.20574)
		(layers "F.Cu" "B.Cu")
		(net "NFP_JTAG_ARM_TRST_L")
	)
	(via
		(at 19.05 45.9105)
		(size 0.508)
		(drill 0.25654)
		(layers "F.Cu" "B.Cu")
		(net "NFP_JTAG_ARM_TRST_L")
	)
	(segment
		(start 40.237029 27.042364)
		(end 40.236648 27.042364)
		(width 0.14732)
		(layer "B.Cu")
		(net "NFP_JTAG_ARM_TRST_L")
	)
	(segment
		(start 40.236648 27.042364)
		(end 39.737005 27.542007)
		(width 0.14732)
		(layer "B.Cu")
		(net "NFP_JTAG_ARM_TRST_L")
	)
	(segment
		(start 17.78 44.958)
		(end 18.7325 45.9105)
		(width 0.14732)
		(layer "B.Cu")
		(net "NFP_JTAG_ARM_TRST_L")
	)
	(segment
		(start 39.237031 27.042364)
		(end 39.237361 27.042364)
		(width 0.14732)
		(layer "B.Cu")
		(net "NFP_JTAG_ARM_TRST_L")
	)
	(segment
		(start 17.78 43.8785)
		(end 17.78 44.958)
		(width 0.14732)
		(layer "B.Cu")
		(net "NFP_JTAG_ARM_TRST_L")
	)
	(segment
		(start 39.237361 27.042364)
		(end 39.737005 27.542007)
		(width 0.14732)
		(layer "B.Cu")
		(net "NFP_JTAG_ARM_TRST_L")
	)
	(segment
		(start 18.7325 45.9105)
		(end 19.05 45.9105)
		(width 0.14732)
		(layer "B.Cu")
		(net "NFP_JTAG_ARM_TRST_L")
	)
	(segment
		(start 32.075196 43.081575)
		(end 30.881396 44.275375)
		(width 0.12065)
		(layer "In6.Cu")
		(net "NFP_JTAG_ARM_TRST_L")
	)
	(segment
		(start 30.650053 44.395898)
		(end 28.801797 44.395898)
		(width 0.12065)
		(layer "In6.Cu")
		(net "NFP_JTAG_ARM_TRST_L")
	)
	(segment
		(start 23.363276 43.87022)
		(end 23.363276 44.888353)
		(width 0.12065)
		(layer "In6.Cu")
		(net "NFP_JTAG_ARM_TRST_L")
	)
	(segment
		(start 35.288957 44.69765)
		(end 34.844228 44.69765)
		(width 0.12065)
		(layer "In6.Cu")
		(net "NFP_JTAG_ARM_TRST_L")
	)
	(segment
		(start 32.440829 43.081575)
		(end 32.075196 43.081575)
		(width 0.12065)
		(layer "In6.Cu")
		(net "NFP_JTAG_ARM_TRST_L")
	)
	(segment
		(start 22.785629 45.466)
		(end 19.4945 45.466)
		(width 0.12065)
		(layer "In6.Cu")
		(net "NFP_JTAG_ARM_TRST_L")
	)
	(segment
		(start 34.844228 44.69765)
		(end 33.713928 43.56735)
		(width 0.12065)
		(layer "In6.Cu")
		(net "NFP_JTAG_ARM_TRST_L")
	)
	(segment
		(start 28.801797 44.395898)
		(end 27.042974 42.637075)
		(width 0.12065)
		(layer "In6.Cu")
		(net "NFP_JTAG_ARM_TRST_L")
	)
	(segment
		(start 24.59642 42.637075)
		(end 23.363276 43.87022)
		(width 0.12065)
		(layer "In6.Cu")
		(net "NFP_JTAG_ARM_TRST_L")
	)
	(segment
		(start 36.425607 45.8343)
		(end 35.288957 44.69765)
		(width 0.12065)
		(layer "In6.Cu")
		(net "NFP_JTAG_ARM_TRST_L")
	)
	(segment
		(start 32.926604 43.56735)
		(end 32.440829 43.081575)
		(width 0.12065)
		(layer "In6.Cu")
		(net "NFP_JTAG_ARM_TRST_L")
	)
	(segment
		(start 19.4945 45.466)
		(end 19.05 45.9105)
		(width 0.12065)
		(layer "In6.Cu")
		(net "NFP_JTAG_ARM_TRST_L")
	)
	(segment
		(start 30.881396 44.275375)
		(end 30.770576 44.275375)
		(width 0.12065)
		(layer "In6.Cu")
		(net "NFP_JTAG_ARM_TRST_L")
	)
	(segment
		(start 27.042974 42.637075)
		(end 24.59642 42.637075)
		(width 0.12065)
		(layer "In6.Cu")
		(net "NFP_JTAG_ARM_TRST_L")
	)
	(segment
		(start 40.894 46.736)
		(end 39.9923 45.8343)
		(width 0.12065)
		(layer "In6.Cu")
		(net "NFP_JTAG_ARM_TRST_L")
	)
	(segment
		(start 23.363276 44.888353)
		(end 22.785629 45.466)
		(width 0.12065)
		(layer "In6.Cu")
		(net "NFP_JTAG_ARM_TRST_L")
	)
	(segment
		(start 33.713928 43.56735)
		(end 32.926604 43.56735)
		(width 0.12065)
		(layer "In6.Cu")
		(net "NFP_JTAG_ARM_TRST_L")
	)
	(segment
		(start 39.9923 45.8343)
		(end 36.425607 45.8343)
		(width 0.12065)
		(layer "In6.Cu")
		(net "NFP_JTAG_ARM_TRST_L")
	)
	(segment
		(start 30.770576 44.275375)
		(end 30.650053 44.395898)
		(width 0.12065)
		(layer "In6.Cu")
		(net "NFP_JTAG_ARM_TRST_L")
	)
	(segment
		(start 39.33378 19.21322)
		(end 39.33378 25.709067)
		(width 0.12065)
		(layer "In7.Cu")
		(net "NFP_JTAG_ARM_TRST_L")
	)
	(segment
		(start 39.497 29.87228)
		(end 39.33378 29.709059)
		(width 0.12065)
		(layer "In7.Cu")
		(net "NFP_JTAG_ARM_TRST_L")
	)
	(segment
		(start 39.243 33.401)
		(end 39.878 32.766)
		(width 0.12065)
		(layer "In7.Cu")
		(net "NFP_JTAG_ARM_TRST_L")
	)
	(segment
		(start 39.497 27.302003)
		(end 39.737005 27.542007)
		(width 0.12065)
		(layer "In7.Cu")
		(net "NFP_JTAG_ARM_TRST_L")
	)
	(segment
		(start 39.33378 29.374948)
		(end 39.497 29.211727)
		(width 0.12065)
		(layer "In7.Cu")
		(net "NFP_JTAG_ARM_TRST_L")
	)
	(segment
		(start 40.386 14.986)
		(end 40.894 14.986)
		(width 0.12065)
		(layer "In7.Cu")
		(net "NFP_JTAG_ARM_TRST_L")
	)
	(segment
		(start 39.737005 14.542008)
		(end 39.942008 14.542008)
		(width 0.12065)
		(layer "In7.Cu")
		(net "NFP_JTAG_ARM_TRST_L")
	)
	(segment
		(start 39.497 29.972)
		(end 39.497 29.87228)
		(width 0.12065)
		(layer "In7.Cu")
		(net "NFP_JTAG_ARM_TRST_L")
	)
	(segment
		(start 41.275 15.367)
		(end 41.275 17.574285)
		(width 0.12065)
		(layer "In7.Cu")
		(net "NFP_JTAG_ARM_TRST_L")
	)
	(segment
		(start 40.894 14.986)
		(end 41.275 15.367)
		(width 0.12065)
		(layer "In7.Cu")
		(net "NFP_JTAG_ARM_TRST_L")
	)
	(segment
		(start 39.878 32.766)
		(end 39.878 30.353)
		(width 0.12065)
		(layer "In7.Cu")
		(net "NFP_JTAG_ARM_TRST_L")
	)
	(segment
		(start 39.33378 29.709059)
		(end 39.33378 29.374948)
		(width 0.12065)
		(layer "In7.Cu")
		(net "NFP_JTAG_ARM_TRST_L")
	)
	(segment
		(start 39.33378 25.709067)
		(end 39.497 25.872288)
		(width 0.12065)
		(layer "In7.Cu")
		(net "NFP_JTAG_ARM_TRST_L")
	)
	(segment
		(start 39.942008 14.542008)
		(end 40.386 14.986)
		(width 0.12065)
		(layer "In7.Cu")
		(net "NFP_JTAG_ARM_TRST_L")
	)
	(segment
		(start 41.275 17.574285)
		(end 40.904058 17.945227)
		(width 0.12065)
		(layer "In7.Cu")
		(net "NFP_JTAG_ARM_TRST_L")
	)
	(segment
		(start 40.601773 17.945227)
		(end 39.33378 19.21322)
		(width 0.12065)
		(layer "In7.Cu")
		(net "NFP_JTAG_ARM_TRST_L")
	)
	(segment
		(start 39.243 45.085)
		(end 39.243 33.401)
		(width 0.12065)
		(layer "In7.Cu")
		(net "NFP_JTAG_ARM_TRST_L")
	)
	(segment
		(start 39.878 30.353)
		(end 39.497 29.972)
		(width 0.12065)
		(layer "In7.Cu")
		(net "NFP_JTAG_ARM_TRST_L")
	)
	(segment
		(start 40.894 46.736)
		(end 39.243 45.085)
		(width 0.12065)
		(layer "In7.Cu")
		(net "NFP_JTAG_ARM_TRST_L")
	)
	(segment
		(start 39.497 29.211727)
		(end 39.497 27.782012)
		(width 0.12065)
		(layer "In7.Cu")
		(net "NFP_JTAG_ARM_TRST_L")
	)
	(segment
		(start 39.497 27.782012)
		(end 39.737005 27.542007)
		(width 0.12065)
		(layer "In7.Cu")
		(net "NFP_JTAG_ARM_TRST_L")
	)
	(segment
		(start 40.904058 17.945227)
		(end 40.601773 17.945227)
		(width 0.12065)
		(layer "In7.Cu")
		(net "NFP_JTAG_ARM_TRST_L")
	)
	(segment
		(start 39.497 25.872288)
		(end 39.497 27.302003)
		(width 0.12065)
		(layer "In7.Cu")
		(net "NFP_JTAG_ARM_TRST_L")
	)
	(segment
		(start 39.237006 14.042009)
		(end 38.737007 13.54201)
		(width 0.13208)
		(layer "F.Cu")
		(net "NFP_JTAG_ARM_TMS")
	)
	(via
		(at 38.989 47.117)
		(size 0.508)
		(drill 0.25654)
		(layers "F.Cu" "B.Cu")
		(net "NFP_JTAG_ARM_TMS")
	)
	(via
		(at 38.737007 13.54201)
		(size 0.4826)
		(drill 0.20574)
		(layers "F.Cu" "B.Cu")
		(net "NFP_JTAG_ARM_TMS")
	)
	(via
		(at 15.24 45.9105)
		(size 0.508)
		(drill 0.25654)
		(layers "F.Cu" "B.Cu")
		(net "NFP_JTAG_ARM_TMS")
	)
	(segment
		(start 39.8399 9.652)
		(end 39.53256 9.34466)
		(width 0.14732)
		(layer "B.Cu")
		(net "NFP_JTAG_ARM_TMS")
	)
	(segment
		(start 39.53256 9.34466)
		(end 39.490269 9.34466)
		(width 0.14732)
		(layer "B.Cu")
		(net "NFP_JTAG_ARM_TMS")
	)
	(segment
		(start 39.490269 9.34466)
		(end 39.245642 9.100033)
		(width 0.14732)
		(layer "B.Cu")
		(net "NFP_JTAG_ARM_TMS")
	)
	(segment
		(start 16.51 43.8785)
		(end 16.51 45.212)
		(width 0.14732)
		(layer "B.Cu")
		(net "NFP_JTAG_ARM_TMS")
	)
	(segment
		(start 15.4305 45.72)
		(end 15.24 45.9105)
		(width 0.14732)
		(layer "B.Cu")
		(net "NFP_JTAG_ARM_TMS")
	)
	(segment
		(start 16.51 45.212)
		(end 16.002 45.72)
		(width 0.14732)
		(layer "B.Cu")
		(net "NFP_JTAG_ARM_TMS")
	)
	(segment
		(start 39.245642 9.100033)
		(end 38.524967 9.100033)
		(width 0.14732)
		(layer "B.Cu")
		(net "NFP_JTAG_ARM_TMS")
	)
	(segment
		(start 16.002 45.72)
		(end 15.4305 45.72)
		(width 0.14732)
		(layer "B.Cu")
		(net "NFP_JTAG_ARM_TMS")
	)
	(segment
		(start 38.524967 9.100033)
		(end 38.227 9.398)
		(width 0.14732)
		(layer "B.Cu")
		(net "NFP_JTAG_ARM_TMS")
	)
	(segment
		(start 38.227 9.398)
		(end 38.227 13.032003)
		(width 0.14732)
		(layer "B.Cu")
		(net "NFP_JTAG_ARM_TMS")
	)
	(segment
		(start 38.227 13.032003)
		(end 38.737007 13.54201)
		(width 0.14732)
		(layer "B.Cu")
		(net "NFP_JTAG_ARM_TMS")
	)
	(segment
		(start 31.783274 44.643675)
		(end 33.986521 44.643675)
		(width 0.12065)
		(layer "In6.Cu")
		(net "NFP_JTAG_ARM_TMS")
	)
	(segment
		(start 30.85785 44.897548)
		(end 30.978373 44.777025)
		(width 0.12065)
		(layer "In6.Cu")
		(net "NFP_JTAG_ARM_TMS")
	)
	(segment
		(start 35.535184 45.653325)
		(end 36.217809 46.33595)
		(width 0.12065)
		(layer "In6.Cu")
		(net "NFP_JTAG_ARM_TMS")
	)
	(segment
		(start 33.986521 44.643675)
		(end 34.996171 45.653325)
		(width 0.12065)
		(layer "In6.Cu")
		(net "NFP_JTAG_ARM_TMS")
	)
	(segment
		(start 18.671718 46.539861)
		(end 18.699607 46.534273)
		(width 0.12065)
		(layer "In6.Cu")
		(net "NFP_JTAG_ARM_TMS")
	)
	(segment
		(start 36.217809 46.33595)
		(end 38.20795 46.33595)
		(width 0.12065)
		(layer "In6.Cu")
		(net "NFP_JTAG_ARM_TMS")
	)
	(segment
		(start 18.81538 46.494929)
		(end 18.825261 46.48835)
		(width 0.12065)
		(layer "In6.Cu")
		(net "NFP_JTAG_ARM_TMS")
	)
	(segment
		(start 34.996171 45.653325)
		(end 35.535184 45.653325)
		(width 0.12065)
		(layer "In6.Cu")
		(net "NFP_JTAG_ARM_TMS")
	)
	(segment
		(start 30.978373 44.777025)
		(end 31.649924 44.777025)
		(width 0.12065)
		(layer "In6.Cu")
		(net "NFP_JTAG_ARM_TMS")
	)
	(segment
		(start 15.24 46.354644)
		(end 15.427503 46.542147)
		(width 0.12065)
		(layer "In6.Cu")
		(net "NFP_JTAG_ARM_TMS")
	)
	(segment
		(start 21.861729 46.262925)
		(end 22.338944 46.262925)
		(width 0.12065)
		(layer "In6.Cu")
		(net "NFP_JTAG_ARM_TMS")
	)
	(segment
		(start 18.739561 46.526323)
		(end 18.81538 46.494929)
		(width 0.12065)
		(layer "In6.Cu")
		(net "NFP_JTAG_ARM_TMS")
	)
	(segment
		(start 22.338944 46.262925)
		(end 23.628223 44.973646)
		(width 0.12065)
		(layer "In6.Cu")
		(net "NFP_JTAG_ARM_TMS")
	)
	(segment
		(start 26.835151 43.138725)
		(end 28.593974 44.897548)
		(width 0.12065)
		(layer "In6.Cu")
		(net "NFP_JTAG_ARM_TMS")
	)
	(segment
		(start 18.825261 46.48835)
		(end 21.636304 46.48835)
		(width 0.12065)
		(layer "In6.Cu")
		(net "NFP_JTAG_ARM_TMS")
	)
	(segment
		(start 18.699607 46.534273)
		(end 18.739561 46.526323)
		(width 0.12065)
		(layer "In6.Cu")
		(net "NFP_JTAG_ARM_TMS")
	)
	(segment
		(start 24.804218 43.138725)
		(end 26.835151 43.138725)
		(width 0.12065)
		(layer "In6.Cu")
		(net "NFP_JTAG_ARM_TMS")
	)
	(segment
		(start 38.20795 46.33595)
		(end 38.989 47.117)
		(width 0.12065)
		(layer "In6.Cu")
		(net "NFP_JTAG_ARM_TMS")
	)
	(segment
		(start 23.628223 44.55983)
		(end 23.961725 44.226328)
		(width 0.12065)
		(layer "In6.Cu")
		(net "NFP_JTAG_ARM_TMS")
	)
	(segment
		(start 28.593974 44.897548)
		(end 30.85785 44.897548)
		(width 0.12065)
		(layer "In6.Cu")
		(net "NFP_JTAG_ARM_TMS")
	)
	(segment
		(start 15.427503 46.542147)
		(end 18.660364 46.542147)
		(width 0.12065)
		(layer "In6.Cu")
		(net "NFP_JTAG_ARM_TMS")
	)
	(segment
		(start 31.649924 44.777025)
		(end 31.783274 44.643675)
		(width 0.12065)
		(layer "In6.Cu")
		(net "NFP_JTAG_ARM_TMS")
	)
	(segment
		(start 23.961725 43.981218)
		(end 24.804218 43.138725)
		(width 0.12065)
		(layer "In6.Cu")
		(net "NFP_JTAG_ARM_TMS")
	)
	(segment
		(start 23.628223 44.973646)
		(end 23.628223 44.55983)
		(width 0.12065)
		(layer "In6.Cu")
		(net "NFP_JTAG_ARM_TMS")
	)
	(segment
		(start 18.660364 46.542147)
		(end 18.671692 46.539887)
		(width 0.12065)
		(layer "In6.Cu")
		(net "NFP_JTAG_ARM_TMS")
	)
	(segment
		(start 15.24 45.9105)
		(end 15.24 46.354644)
		(width 0.12065)
		(layer "In6.Cu")
		(net "NFP_JTAG_ARM_TMS")
	)
	(segment
		(start 23.961725 44.226328)
		(end 23.961725 43.981218)
		(width 0.12065)
		(layer "In6.Cu")
		(net "NFP_JTAG_ARM_TMS")
	)
	(segment
		(start 21.636304 46.48835)
		(end 21.861729 46.262925)
		(width 0.12065)
		(layer "In6.Cu")
		(net "NFP_JTAG_ARM_TMS")
	)
	(segment
		(start 18.671692 46.539887)
		(end 18.671718 46.539861)
		(width 0.12065)
		(layer "In6.Cu")
		(net "NFP_JTAG_ARM_TMS")
	)
	(segment
		(start 38.81501 13.54201)
		(end 39.243 13.97)
		(width 0.12065)
		(layer "In7.Cu")
		(net "NFP_JTAG_ARM_TMS")
	)
	(segment
		(start 39.649781 15.138781)
		(end 39.90406 15.138781)
		(width 0.12065)
		(layer "In7.Cu")
		(net "NFP_JTAG_ARM_TMS")
	)
	(segment
		(start 40.14023 15.37495)
		(end 40.14023 17.709058)
		(width 0.12065)
		(layer "In7.Cu")
		(net "NFP_JTAG_ARM_TMS")
	)
	(segment
		(start 38.735 42.497705)
		(end 38.735 46.863)
		(width 0.12065)
		(layer "In7.Cu")
		(net "NFP_JTAG_ARM_TMS")
	)
	(segment
		(start 38.989 33.02)
		(end 38.608 33.02)
		(width 0.12065)
		(layer "In7.Cu")
		(net "NFP_JTAG_ARM_TMS")
	)
	(segment
		(start 38.166675 41.92938)
		(end 38.735 42.497705)
		(width 0.12065)
		(layer "In7.Cu")
		(net "NFP_JTAG_ARM_TMS")
	)
	(segment
		(start 38.737007 13.54201)
		(end 38.81501 13.54201)
		(width 0.12065)
		(layer "In7.Cu")
		(net "NFP_JTAG_ARM_TMS")
	)
	(segment
		(start 38.855777 18.852947)
		(end 38.333782 19.374942)
		(width 0.12065)
		(layer "In7.Cu")
		(net "NFP_JTAG_ARM_TMS")
	)
	(segment
		(start 38.333782 19.374942)
		(end 38.333782 23.728782)
		(width 0.12065)
		(layer "In7.Cu")
		(net "NFP_JTAG_ARM_TMS")
	)
	(segment
		(start 38.333782 23.728782)
		(end 38.989 24.384)
		(width 0.12065)
		(layer "In7.Cu")
		(net "NFP_JTAG_ARM_TMS")
	)
	(segment
		(start 38.166675 33.461325)
		(end 38.166675 41.92938)
		(width 0.12065)
		(layer "In7.Cu")
		(net "NFP_JTAG_ARM_TMS")
	)
	(segment
		(start 38.989 30.099)
		(end 39.37 30.48)
		(width 0.12065)
		(layer "In7.Cu")
		(net "NFP_JTAG_ARM_TMS")
	)
	(segment
		(start 39.243 13.97)
		(end 39.243 14.732)
		(width 0.12065)
		(layer "In7.Cu")
		(net "NFP_JTAG_ARM_TMS")
	)
	(segment
		(start 38.735 46.863)
		(end 38.989 47.117)
		(width 0.12065)
		(layer "In7.Cu")
		(net "NFP_JTAG_ARM_TMS")
	)
	(segment
		(start 39.90406 15.138781)
		(end 40.14023 15.37495)
		(width 0.12065)
		(layer "In7.Cu")
		(net "NFP_JTAG_ARM_TMS")
	)
	(segment
		(start 38.996341 18.852947)
		(end 38.855777 18.852947)
		(width 0.12065)
		(layer "In7.Cu")
		(net "NFP_JTAG_ARM_TMS")
	)
	(segment
		(start 38.608 33.02)
		(end 38.166675 33.461325)
		(width 0.12065)
		(layer "In7.Cu")
		(net "NFP_JTAG_ARM_TMS")
	)
	(segment
		(start 39.37 30.48)
		(end 39.37 32.639)
		(width 0.12065)
		(layer "In7.Cu")
		(net "NFP_JTAG_ARM_TMS")
	)
	(segment
		(start 39.37 32.639)
		(end 38.989 33.02)
		(width 0.12065)
		(layer "In7.Cu")
		(net "NFP_JTAG_ARM_TMS")
	)
	(segment
		(start 40.14023 17.709058)
		(end 38.996341 18.852947)
		(width 0.12065)
		(layer "In7.Cu")
		(net "NFP_JTAG_ARM_TMS")
	)
	(segment
		(start 38.989 24.384)
		(end 38.989 30.099)
		(width 0.12065)
		(layer "In7.Cu")
		(net "NFP_JTAG_ARM_TMS")
	)
	(segment
		(start 39.243 14.732)
		(end 39.649781 15.138781)
		(width 0.12065)
		(layer "In7.Cu")
		(net "NFP_JTAG_ARM_TMS")
	)
	(segment
		(start 25.654 13.97)
		(end 25.527 14.097)
		(width 0.14732)
		(layer "F.Cu")
		(net "NFP_JTAG_ARM_TDO")
	)
	(segment
		(start 26.6319 13.97)
		(end 25.654 13.97)
		(width 0.14732)
		(layer "F.Cu")
		(net "NFP_JTAG_ARM_TDO")
	)
	(via
		(at 11.557 29.337)
		(size 0.508)
		(drill 0.254)
		(layers "F.Cu" "B.Cu")
		(net "NFP_JTAG_ARM_TDO")
	)
	(via
		(at 25.527 14.097)
		(size 0.508)
		(drill 0.254)
		(layers "F.Cu" "B.Cu")
		(net "NFP_JTAG_ARM_TDO")
	)
	(via
		(at 13.97 45.9105)
		(size 0.508)
		(drill 0.25654)
		(layers "F.Cu" "B.Cu")
		(net "NFP_JTAG_ARM_TDO")
	)
	(via
		(at 37.084 47.117)
		(size 0.508)
		(drill 0.25654)
		(layers "F.Cu" "B.Cu")
		(net "NFP_JTAG_ARM_TDO")
	)
	(segment
		(start 15.24 43.8785)
		(end 15.24 44.958)
		(width 0.14732)
		(layer "B.Cu")
		(net "NFP_JTAG_ARM_TDO")
	)
	(segment
		(start 26.035 13.589)
		(end 26.035 12.17422)
		(width 0.14732)
		(layer "B.Cu")
		(net "NFP_JTAG_ARM_TDO")
	)
	(segment
		(start 26.784706 12.17422)
		(end 27.22626 11.732666)
		(width 0.14732)
		(layer "B.Cu")
		(net "NFP_JTAG_ARM_TDO")
	)
	(segment
		(start 27.35834 10.015093)
		(end 27.432 9.941433)
		(width 0.14732)
		(layer "B.Cu")
		(net "NFP_JTAG_ARM_TDO")
	)
	(segment
		(start 27.178 8.509)
		(end 26.7081 8.509)
		(width 0.14732)
		(layer "B.Cu")
		(net "NFP_JTAG_ARM_TDO")
	)
	(segment
		(start 27.22626 10.147275)
		(end 27.35834 10.015195)
		(width 0.14732)
		(layer "B.Cu")
		(net "NFP_JTAG_ARM_TDO")
	)
	(segment
		(start 27.432 8.763)
		(end 27.178 8.509)
		(width 0.14732)
		(layer "B.Cu")
		(net "NFP_JTAG_ARM_TDO")
	)
	(segment
		(start 25.527 14.097)
		(end 26.035 13.589)
		(width 0.14732)
		(layer "B.Cu")
		(net "NFP_JTAG_ARM_TDO")
	)
	(segment
		(start 27.22626 11.732666)
		(end 27.22626 10.147275)
		(width 0.14732)
		(layer "B.Cu")
		(net "NFP_JTAG_ARM_TDO")
	)
	(segment
		(start 27.432 9.941433)
		(end 27.432 8.763)
		(width 0.14732)
		(layer "B.Cu")
		(net "NFP_JTAG_ARM_TDO")
	)
	(segment
		(start 14.478 45.72)
		(end 14.1605 45.72)
		(width 0.14732)
		(layer "B.Cu")
		(net "NFP_JTAG_ARM_TDO")
	)
	(segment
		(start 15.24 44.958)
		(end 14.478 45.72)
		(width 0.14732)
		(layer "B.Cu")
		(net "NFP_JTAG_ARM_TDO")
	)
	(segment
		(start 14.1605 45.72)
		(end 13.97 45.9105)
		(width 0.14732)
		(layer "B.Cu")
		(net "NFP_JTAG_ARM_TDO")
	)
	(segment
		(start 26.035 12.17422)
		(end 26.784706 12.17422)
		(width 0.14732)
		(layer "B.Cu")
		(net "NFP_JTAG_ARM_TDO")
	)
	(segment
		(start 27.35834 10.015195)
		(end 27.35834 10.015093)
		(width 0.14732)
		(layer "B.Cu")
		(net "NFP_JTAG_ARM_TDO")
	)
	(segment
		(start 20.356195 20.650937)
		(end 19.869785 21.137347)
		(width 0.12065)
		(layer "In6.Cu")
		(net "NFP_JTAG_ARM_TDO")
	)
	(segment
		(start 24.958675 44.93293)
		(end 24.396573 45.495032)
		(width 0.12065)
		(layer "In6.Cu")
		(net "NFP_JTAG_ARM_TDO")
	)
	(segment
		(start 22.479 19.685)
		(end 21.209 19.685)
		(width 0.12065)
		(layer "In6.Cu")
		(net "NFP_JTAG_ARM_TDO")
	)
	(segment
		(start 13.97 46.144485)
		(end 13.97 45.9105)
		(width 0.12065)
		(layer "In6.Cu")
		(net "NFP_JTAG_ARM_TDO")
	)
	(segment
		(start 17.78 26.035025)
		(end 17.78 27.432)
		(width 0.12065)
		(layer "In6.Cu")
		(net "NFP_JTAG_ARM_TDO")
	)
	(segment
		(start 23.495 17.907)
		(end 23.495 18.669)
		(width 0.12065)
		(layer "In6.Cu")
		(net "NFP_JTAG_ARM_TDO")
	)
	(segment
		(start 24.958675 44.394196)
		(end 24.958675 44.93293)
		(width 0.12065)
		(layer "In6.Cu")
		(net "NFP_JTAG_ARM_TDO")
	)
	(segment
		(start 22.053626 47.012225)
		(end 21.774302 47.291549)
		(width 0.12065)
		(layer "In6.Cu")
		(net "NFP_JTAG_ARM_TDO")
	)
	(segment
		(start 27.55199 45.958125)
		(end 27.05034 45.456475)
		(width 0.12065)
		(layer "In6.Cu")
		(net "NFP_JTAG_ARM_TDO")
	)
	(segment
		(start 15.117064 47.291549)
		(end 13.97 46.144485)
		(width 0.12065)
		(layer "In6.Cu")
		(net "NFP_JTAG_ARM_TDO")
	)
	(segment
		(start 19.869785 22.536785)
		(end 20.193 22.86)
		(width 0.12065)
		(layer "In6.Cu")
		(net "NFP_JTAG_ARM_TDO")
	)
	(segment
		(start 25.582804 44.135675)
		(end 25.217196 44.135675)
		(width 0.12065)
		(layer "In6.Cu")
		(net "NFP_JTAG_ARM_TDO")
	)
	(segment
		(start 29.081247 45.958125)
		(end 27.55199 45.958125)
		(width 0.12065)
		(layer "In6.Cu")
		(net "NFP_JTAG_ARM_TDO")
	)
	(segment
		(start 27.05034 45.456475)
		(end 26.384606 45.456475)
		(width 0.12065)
		(layer "In6.Cu")
		(net "NFP_JTAG_ARM_TDO")
	)
	(segment
		(start 25.527 14.224)
		(end 24.698325 15.052675)
		(width 0.12065)
		(layer "In6.Cu")
		(net "NFP_JTAG_ARM_TDO")
	)
	(segment
		(start 23.304144 47.012225)
		(end 22.053626 47.012225)
		(width 0.12065)
		(layer "In6.Cu")
		(net "NFP_JTAG_ARM_TDO")
	)
	(segment
		(start 23.876 15.758846)
		(end 23.876 17.526)
		(width 0.12065)
		(layer "In6.Cu")
		(net "NFP_JTAG_ARM_TDO")
	)
	(segment
		(start 24.582171 15.052675)
		(end 23.876 15.758846)
		(width 0.12065)
		(layer "In6.Cu")
		(net "NFP_JTAG_ARM_TDO")
	)
	(segment
		(start 37.084 47.117)
		(end 35.422154 47.117)
		(width 0.12065)
		(layer "In6.Cu")
		(net "NFP_JTAG_ARM_TDO")
	)
	(segment
		(start 20.193 24.384025)
		(end 19.999325 24.5777)
		(width 0.12065)
		(layer "In6.Cu")
		(net "NFP_JTAG_ARM_TDO")
	)
	(segment
		(start 15.875 29.337)
		(end 11.557 29.337)
		(width 0.12065)
		(layer "In6.Cu")
		(net "NFP_JTAG_ARM_TDO")
	)
	(segment
		(start 32.00466 46.408975)
		(end 29.532097 46.408975)
		(width 0.12065)
		(layer "In6.Cu")
		(net "NFP_JTAG_ARM_TDO")
	)
	(segment
		(start 35.361829 47.177325)
		(end 34.996171 47.177325)
		(width 0.12065)
		(layer "In6.Cu")
		(net "NFP_JTAG_ARM_TDO")
	)
	(segment
		(start 25.841325 44.394196)
		(end 25.582804 44.135675)
		(width 0.12065)
		(layer "In6.Cu")
		(net "NFP_JTAG_ARM_TDO")
	)
	(segment
		(start 20.356195 20.537805)
		(end 20.356195 20.650937)
		(width 0.12065)
		(layer "In6.Cu")
		(net "NFP_JTAG_ARM_TDO")
	)
	(segment
		(start 25.841325 44.913194)
		(end 25.841325 44.394196)
		(width 0.12065)
		(layer "In6.Cu")
		(net "NFP_JTAG_ARM_TDO")
	)
	(segment
		(start 23.495 18.669)
		(end 22.479 19.685)
		(width 0.12065)
		(layer "In6.Cu")
		(net "NFP_JTAG_ARM_TDO")
	)
	(segment
		(start 19.740829 25.079325)
		(end 18.7357 25.079325)
		(width 0.12065)
		(layer "In6.Cu")
		(net "NFP_JTAG_ARM_TDO")
	)
	(segment
		(start 24.396573 45.919796)
		(end 23.304144 47.012225)
		(width 0.12065)
		(layer "In6.Cu")
		(net "NFP_JTAG_ARM_TDO")
	)
	(segment
		(start 19.869785 21.137347)
		(end 19.869785 22.536785)
		(width 0.12065)
		(layer "In6.Cu")
		(net "NFP_JTAG_ARM_TDO")
	)
	(segment
		(start 24.396573 45.495032)
		(end 24.396573 45.919796)
		(width 0.12065)
		(layer "In6.Cu")
		(net "NFP_JTAG_ARM_TDO")
	)
	(segment
		(start 26.384606 45.456475)
		(end 25.841325 44.913194)
		(width 0.12065)
		(layer "In6.Cu")
		(net "NFP_JTAG_ARM_TDO")
	)
	(segment
		(start 29.532097 46.408975)
		(end 29.081247 45.958125)
		(width 0.12065)
		(layer "In6.Cu")
		(net "NFP_JTAG_ARM_TDO")
	)
	(segment
		(start 24.698325 15.052675)
		(end 24.582171 15.052675)
		(width 0.12065)
		(layer "In6.Cu")
		(net "NFP_JTAG_ARM_TDO")
	)
	(segment
		(start 35.422154 47.117)
		(end 35.361829 47.177325)
		(width 0.12065)
		(layer "In6.Cu")
		(net "NFP_JTAG_ARM_TDO")
	)
	(segment
		(start 20.193 22.86)
		(end 20.193 24.384025)
		(width 0.12065)
		(layer "In6.Cu")
		(net "NFP_JTAG_ARM_TDO")
	)
	(segment
		(start 19.999325 24.5777)
		(end 19.999325 24.820829)
		(width 0.12065)
		(layer "In6.Cu")
		(net "NFP_JTAG_ARM_TDO")
	)
	(segment
		(start 32.22056 46.193075)
		(end 32.00466 46.408975)
		(width 0.12065)
		(layer "In6.Cu")
		(net "NFP_JTAG_ARM_TDO")
	)
	(segment
		(start 34.011921 46.193075)
		(end 32.22056 46.193075)
		(width 0.12065)
		(layer "In6.Cu")
		(net "NFP_JTAG_ARM_TDO")
	)
	(segment
		(start 21.209 19.685)
		(end 20.356195 20.537805)
		(width 0.12065)
		(layer "In6.Cu")
		(net "NFP_JTAG_ARM_TDO")
	)
	(segment
		(start 23.876 17.526)
		(end 23.495 17.907)
		(width 0.12065)
		(layer "In6.Cu")
		(net "NFP_JTAG_ARM_TDO")
	)
	(segment
		(start 25.217196 44.135675)
		(end 24.958675 44.394196)
		(width 0.12065)
		(layer "In6.Cu")
		(net "NFP_JTAG_ARM_TDO")
	)
	(segment
		(start 21.774302 47.291549)
		(end 15.117064 47.291549)
		(width 0.12065)
		(layer "In6.Cu")
		(net "NFP_JTAG_ARM_TDO")
	)
	(segment
		(start 18.7357 25.079325)
		(end 17.78 26.035025)
		(width 0.12065)
		(layer "In6.Cu")
		(net "NFP_JTAG_ARM_TDO")
	)
	(segment
		(start 19.999325 24.820829)
		(end 19.740829 25.079325)
		(width 0.12065)
		(layer "In6.Cu")
		(net "NFP_JTAG_ARM_TDO")
	)
	(segment
		(start 25.527 14.097)
		(end 25.527 14.224)
		(width 0.12065)
		(layer "In6.Cu")
		(net "NFP_JTAG_ARM_TDO")
	)
	(segment
		(start 17.78 27.432)
		(end 15.875 29.337)
		(width 0.12065)
		(layer "In6.Cu")
		(net "NFP_JTAG_ARM_TDO")
	)
	(segment
		(start 34.996171 47.177325)
		(end 34.011921 46.193075)
		(width 0.12065)
		(layer "In6.Cu")
		(net "NFP_JTAG_ARM_TDO")
	)
	(segment
		(start 10.287 37.084)
		(end 10.287 32.639)
		(width 0.12065)
		(layer "In7.Cu")
		(net "NFP_JTAG_ARM_TDO")
	)
	(segment
		(start 10.287 32.639)
		(end 11.176 31.75)
		(width 0.12065)
		(layer "In7.Cu")
		(net "NFP_JTAG_ARM_TDO")
	)
	(segment
		(start 9.779 41.7195)
		(end 9.779 37.592)
		(width 0.12065)
		(layer "In7.Cu")
		(net "NFP_JTAG_ARM_TDO")
	)
	(segment
		(start 11.176 31.75)
		(end 11.176 29.718)
		(width 0.12065)
		(layer "In7.Cu")
		(net "NFP_JTAG_ARM_TDO")
	)
	(segment
		(start 9.779 37.592)
		(end 10.287 37.084)
		(width 0.12065)
		(layer "In7.Cu")
		(net "NFP_JTAG_ARM_TDO")
	)
	(segment
		(start 11.176 29.718)
		(end 11.557 29.337)
		(width 0.12065)
		(layer "In7.Cu")
		(net "NFP_JTAG_ARM_TDO")
	)
	(segment
		(start 13.97 45.9105)
		(end 9.779 41.7195)
		(width 0.12065)
		(layer "In7.Cu")
		(net "NFP_JTAG_ARM_TDO")
	)
	(segment
		(start 39.237006 15.042007)
		(end 38.737007 14.542008)
		(width 0.13208)
		(layer "F.Cu")
		(net "NFP_JTAG_ARM_TDI")
	)
	(via
		(at 25.019 11.43)
		(size 0.508)
		(drill 0.254)
		(layers "F.Cu" "B.Cu")
		(net "NFP_JTAG_ARM_TDI")
	)
	(via
		(at 12.7 45.9105)
		(size 0.508)
		(drill 0.25654)
		(layers "F.Cu" "B.Cu")
		(net "NFP_JTAG_ARM_TDI")
	)
	(via
		(at 35.179 46.736)
		(size 0.508)
		(drill 0.25654)
		(layers "F.Cu" "B.Cu")
		(net "NFP_JTAG_ARM_TDI")
	)
	(via
		(at 38.737007 14.542008)
		(size 0.4826)
		(drill 0.20574)
		(layers "F.Cu" "B.Cu")
		(net "NFP_JTAG_ARM_TDI")
	)
	(segment
		(start 13.081 45.847)
		(end 12.7635 45.847)
		(width 0.14732)
		(layer "B.Cu")
		(net "NFP_JTAG_ARM_TDI")
	)
	(segment
		(start 26.035 11.33602)
		(end 25.94102 11.43)
		(width 0.14732)
		(layer "B.Cu")
		(net "NFP_JTAG_ARM_TDI")
	)
	(segment
		(start 13.97 43.8785)
		(end 13.97 44.958)
		(width 0.14732)
		(layer "B.Cu")
		(net "NFP_JTAG_ARM_TDI")
	)
	(segment
		(start 24.1681 11.303)
		(end 24.2951 11.43)
		(width 0.14732)
		(layer "B.Cu")
		(net "NFP_JTAG_ARM_TDI")
	)
	(segment
		(start 24.2951 11.43)
		(end 25.019 11.43)
		(width 0.14732)
		(layer "B.Cu")
		(net "NFP_JTAG_ARM_TDI")
	)
	(segment
		(start 25.94102 11.43)
		(end 25.019 11.43)
		(width 0.14732)
		(layer "B.Cu")
		(net "NFP_JTAG_ARM_TDI")
	)
	(segment
		(start 12.7635 45.847)
		(end 12.7 45.9105)
		(width 0.14732)
		(layer "B.Cu")
		(net "NFP_JTAG_ARM_TDI")
	)
	(segment
		(start 13.97 44.958)
		(end 13.081 45.847)
		(width 0.14732)
		(layer "B.Cu")
		(net "NFP_JTAG_ARM_TDI")
	)
	(segment
		(start 33.329829 10.480675)
		(end 32.964171 10.480675)
		(width 0.12065)
		(layer "In3.Cu")
		(net "NFP_JTAG_ARM_TDI")
	)
	(segment
		(start 37.011026 13.577545)
		(end 33.968131 10.53465)
		(width 0.12065)
		(layer "In3.Cu")
		(net "NFP_JTAG_ARM_TDI")
	)
	(segment
		(start 38.290983 14.542008)
		(end 38.220752 14.471777)
		(width 0.12065)
		(layer "In3.Cu")
		(net "NFP_JTAG_ARM_TDI")
	)
	(segment
		(start 37.809018 14.471777)
		(end 37.011026 13.673785)
		(width 0.12065)
		(layer "In3.Cu")
		(net "NFP_JTAG_ARM_TDI")
	)
	(segment
		(start 29.113759 13.335)
		(end 26.924 13.335)
		(width 0.12065)
		(layer "In3.Cu")
		(net "NFP_JTAG_ARM_TDI")
	)
	(segment
		(start 38.220752 14.471777)
		(end 37.809018 14.471777)
		(width 0.12065)
		(layer "In3.Cu")
		(net "NFP_JTAG_ARM_TDI")
	)
	(segment
		(start 31.429325 11.115675)
		(end 31.333084 11.115675)
		(width 0.12065)
		(layer "In3.Cu")
		(net "NFP_JTAG_ARM_TDI")
	)
	(segment
		(start 33.968131 10.53465)
		(end 33.383804 10.53465)
		(width 0.12065)
		(layer "In3.Cu")
		(net "NFP_JTAG_ARM_TDI")
	)
	(segment
		(start 32.910196 10.53465)
		(end 32.01035 10.53465)
		(width 0.12065)
		(layer "In3.Cu")
		(net "NFP_JTAG_ARM_TDI")
	)
	(segment
		(start 32.01035 10.53465)
		(end 31.429325 11.115675)
		(width 0.12065)
		(layer "In3.Cu")
		(net "NFP_JTAG_ARM_TDI")
	)
	(segment
		(start 37.011026 13.673785)
		(end 37.011026 13.577545)
		(width 0.12065)
		(layer "In3.Cu")
		(net "NFP_JTAG_ARM_TDI")
	)
	(segment
		(start 26.924 13.335)
		(end 25.019 11.43)
		(width 0.12065)
		(layer "In3.Cu")
		(net "NFP_JTAG_ARM_TDI")
	)
	(segment
		(start 33.383804 10.53465)
		(end 33.329829 10.480675)
		(width 0.12065)
		(layer "In3.Cu")
		(net "NFP_JTAG_ARM_TDI")
	)
	(segment
		(start 31.333084 11.115675)
		(end 29.113759 13.335)
		(width 0.12065)
		(layer "In3.Cu")
		(net "NFP_JTAG_ARM_TDI")
	)
	(segment
		(start 38.737007 14.542008)
		(end 38.290983 14.542008)
		(width 0.12065)
		(layer "In3.Cu")
		(net "NFP_JTAG_ARM_TDI")
	)
	(segment
		(start 32.964171 10.480675)
		(end 32.910196 10.53465)
		(width 0.12065)
		(layer "In3.Cu")
		(net "NFP_JTAG_ARM_TDI")
	)
	(segment
		(start 13.141325 45.469175)
		(end 14.152804 45.469175)
		(width 0.12065)
		(layer "In6.Cu")
		(net "NFP_JTAG_ARM_TDI")
	)
	(segment
		(start 21.725611 46.99)
		(end 21.951036 46.764575)
		(width 0.12065)
		(layer "In6.Cu")
		(net "NFP_JTAG_ARM_TDI")
	)
	(segment
		(start 25.685394 43.888025)
		(end 26.088975 44.291606)
		(width 0.12065)
		(layer "In6.Cu")
		(net "NFP_JTAG_ARM_TDI")
	)
	(segment
		(start 14.732 46.048371)
		(end 14.732 46.556244)
		(width 0.12065)
		(layer "In6.Cu")
		(net "NFP_JTAG_ARM_TDI")
	)
	(segment
		(start 27.65458 45.710475)
		(end 29.183838 45.710475)
		(width 0.12065)
		(layer "In6.Cu")
		(net "NFP_JTAG_ARM_TDI")
	)
	(segment
		(start 12.7 45.9105)
		(end 13.141325 45.469175)
		(width 0.12065)
		(layer "In6.Cu")
		(net "NFP_JTAG_ARM_TDI")
	)
	(segment
		(start 26.487196 45.208825)
		(end 27.15293 45.208825)
		(width 0.12065)
		(layer "In6.Cu")
		(net "NFP_JTAG_ARM_TDI")
	)
	(segment
		(start 26.088975 44.810604)
		(end 26.487196 45.208825)
		(width 0.12065)
		(layer "In6.Cu")
		(net "NFP_JTAG_ARM_TDI")
	)
	(segment
		(start 24.148796 45.817333)
		(end 24.148796 45.392569)
		(width 0.12065)
		(layer "In6.Cu")
		(net "NFP_JTAG_ARM_TDI")
	)
	(segment
		(start 21.951036 46.764575)
		(end 23.201554 46.764575)
		(width 0.12065)
		(layer "In6.Cu")
		(net "NFP_JTAG_ARM_TDI")
	)
	(segment
		(start 23.201554 46.764575)
		(end 24.148796 45.817333)
		(width 0.12065)
		(layer "In6.Cu")
		(net "NFP_JTAG_ARM_TDI")
	)
	(segment
		(start 32.11797 45.945425)
		(end 34.228583 45.945425)
		(width 0.12065)
		(layer "In6.Cu")
		(net "NFP_JTAG_ARM_TDI")
	)
	(segment
		(start 31.90207 46.161325)
		(end 32.11797 45.945425)
		(width 0.12065)
		(layer "In6.Cu")
		(net "NFP_JTAG_ARM_TDI")
	)
	(segment
		(start 34.228583 45.945425)
		(end 34.614739 46.331581)
		(width 0.12065)
		(layer "In6.Cu")
		(net "NFP_JTAG_ARM_TDI")
	)
	(segment
		(start 34.774581 46.331581)
		(end 35.179 46.736)
		(width 0.12065)
		(layer "In6.Cu")
		(net "NFP_JTAG_ARM_TDI")
	)
	(segment
		(start 18.709157 47.043899)
		(end 18.885281 47.008974)
		(width 0.12065)
		(layer "In6.Cu")
		(net "NFP_JTAG_ARM_TDI")
	)
	(segment
		(start 24.711025 44.291606)
		(end 25.114606 43.888025)
		(width 0.12065)
		(layer "In6.Cu")
		(net "NFP_JTAG_ARM_TDI")
	)
	(segment
		(start 24.711025 44.83034)
		(end 24.711025 44.291606)
		(width 0.12065)
		(layer "In6.Cu")
		(net "NFP_JTAG_ARM_TDI")
	)
	(segment
		(start 15.219655 47.043899)
		(end 18.709157 47.043899)
		(width 0.12065)
		(layer "In6.Cu")
		(net "NFP_JTAG_ARM_TDI")
	)
	(segment
		(start 27.15293 45.208825)
		(end 27.65458 45.710475)
		(width 0.12065)
		(layer "In6.Cu")
		(net "NFP_JTAG_ARM_TDI")
	)
	(segment
		(start 26.088975 44.291606)
		(end 26.088975 44.810604)
		(width 0.12065)
		(layer "In6.Cu")
		(net "NFP_JTAG_ARM_TDI")
	)
	(segment
		(start 34.614739 46.331581)
		(end 34.774581 46.331581)
		(width 0.12065)
		(layer "In6.Cu")
		(net "NFP_JTAG_ARM_TDI")
	)
	(segment
		(start 18.931103 46.99)
		(end 21.725611 46.99)
		(width 0.12065)
		(layer "In6.Cu")
		(net "NFP_JTAG_ARM_TDI")
	)
	(segment
		(start 18.885281 47.008974)
		(end 18.931103 46.99)
		(width 0.12065)
		(layer "In6.Cu")
		(net "NFP_JTAG_ARM_TDI")
	)
	(segment
		(start 29.183838 45.710475)
		(end 29.634688 46.161325)
		(width 0.12065)
		(layer "In6.Cu")
		(net "NFP_JTAG_ARM_TDI")
	)
	(segment
		(start 14.152804 45.469175)
		(end 14.732 46.048371)
		(width 0.12065)
		(layer "In6.Cu")
		(net "NFP_JTAG_ARM_TDI")
	)
	(segment
		(start 14.732 46.556244)
		(end 15.219655 47.043899)
		(width 0.12065)
		(layer "In6.Cu")
		(net "NFP_JTAG_ARM_TDI")
	)
	(segment
		(start 24.148796 45.392569)
		(end 24.711025 44.83034)
		(width 0.12065)
		(layer "In6.Cu")
		(net "NFP_JTAG_ARM_TDI")
	)
	(segment
		(start 25.114606 43.888025)
		(end 25.685394 43.888025)
		(width 0.12065)
		(layer "In6.Cu")
		(net "NFP_JTAG_ARM_TDI")
	)
	(segment
		(start 29.634688 46.161325)
		(end 31.90207 46.161325)
		(width 0.12065)
		(layer "In6.Cu")
		(net "NFP_JTAG_ARM_TDI")
	)
	(segment
		(start 37.719 23.975746)
		(end 37.719 23.949355)
		(width 0.12065)
		(layer "In7.Cu")
		(net "NFP_JTAG_ARM_TDI")
	)
	(segment
		(start 35.687 44.745605)
		(end 35.687 44.704)
		(width 0.12065)
		(layer "In7.Cu")
		(net "NFP_JTAG_ARM_TDI")
	)
	(segment
		(start 38.481 25.36637)
		(end 38.481 25.243968)
		(width 0.12065)
		(layer "In7.Cu")
		(net "NFP_JTAG_ARM_TDI")
	)
	(segment
		(start 38.581432 18.410809)
		(end 38.581432 18.314568)
		(width 0.12065)
		(layer "In7.Cu")
		(net "NFP_JTAG_ARM_TDI")
	)
	(segment
		(start 37.663171 24.914225)
		(end 37.404675 24.655729)
		(width 0.12065)
		(layer "In7.Cu")
		(net "NFP_JTAG_ARM_TDI")
	)
	(segment
		(start 35.366325 42.425671)
		(end 35.306 42.365346)
		(width 0.12065)
		(layer "In7.Cu")
		(net "NFP_JTAG_ARM_TDI")
	)
	(segment
		(start 39.243 15.367)
		(end 38.737007 14.861007)
		(width 0.12065)
		(layer "In7.Cu")
		(net "NFP_JTAG_ARM_TDI")
	)
	(segment
		(start 37.719 23.949355)
		(end 37.832132 23.836224)
		(width 0.12065)
		(layer "In7.Cu")
		(net "NFP_JTAG_ARM_TDI")
	)
	(segment
		(start 35.867975 44.92658)
		(end 35.687 44.745605)
		(width 0.12065)
		(layer "In7.Cu")
		(net "NFP_JTAG_ARM_TDI")
	)
	(segment
		(start 38.14633 18.845911)
		(end 38.581432 18.410809)
		(width 0.12065)
		(layer "In7.Cu")
		(net "NFP_JTAG_ARM_TDI")
	)
	(segment
		(start 37.404675 24.290071)
		(end 37.719 23.975746)
		(width 0.12065)
		(layer "In7.Cu")
		(net "NFP_JTAG_ARM_TDI")
	)
	(segment
		(start 35.306 42.851654)
		(end 35.366325 42.791329)
		(width 0.12065)
		(layer "In7.Cu")
		(net "NFP_JTAG_ARM_TDI")
	)
	(segment
		(start 37.404675 24.655729)
		(end 37.404675 24.290071)
		(width 0.12065)
		(layer "In7.Cu")
		(net "NFP_JTAG_ARM_TDI")
	)
	(segment
		(start 38.227 32.385)
		(end 38.608 32.004)
		(width 0.12065)
		(layer "In7.Cu")
		(net "NFP_JTAG_ARM_TDI")
	)
	(segment
		(start 37.832132 23.836224)
		(end 37.832132 19.166992)
		(width 0.12065)
		(layer "In7.Cu")
		(net "NFP_JTAG_ARM_TDI")
	)
	(segment
		(start 35.179 46.736)
		(end 35.867975 46.047025)
		(width 0.12065)
		(layer "In7.Cu")
		(net "NFP_JTAG_ARM_TDI")
	)
	(segment
		(start 38.14633 18.852794)
		(end 38.14633 18.845911)
		(width 0.12065)
		(layer "In7.Cu")
		(net "NFP_JTAG_ARM_TDI")
	)
	(segment
		(start 35.306 41.148)
		(end 36.883975 39.570025)
		(width 0.12065)
		(layer "In7.Cu")
		(net "NFP_JTAG_ARM_TDI")
	)
	(segment
		(start 35.687 44.704)
		(end 35.306 44.323)
		(width 0.12065)
		(layer "In7.Cu")
		(net "NFP_JTAG_ARM_TDI")
	)
	(segment
		(start 38.481 25.243968)
		(end 38.151257 24.914225)
		(width 0.12065)
		(layer "In7.Cu")
		(net "NFP_JTAG_ARM_TDI")
	)
	(segment
		(start 37.665025 33.581975)
		(end 37.665025 33.253528)
		(width 0.12065)
		(layer "In7.Cu")
		(net "NFP_JTAG_ARM_TDI")
	)
	(segment
		(start 37.665025 33.253528)
		(end 38.227 32.691553)
		(width 0.12065)
		(layer "In7.Cu")
		(net "NFP_JTAG_ARM_TDI")
	)
	(segment
		(start 35.867975 46.047025)
		(end 35.867975 44.92658)
		(width 0.12065)
		(layer "In7.Cu")
		(net "NFP_JTAG_ARM_TDI")
	)
	(segment
		(start 38.608 32.004)
		(end 38.608 25.49337)
		(width 0.12065)
		(layer "In7.Cu")
		(net "NFP_JTAG_ARM_TDI")
	)
	(segment
		(start 37.182425 39.311529)
		(end 37.182425 39.271575)
		(width 0.12065)
		(layer "In7.Cu")
		(net "NFP_JTAG_ARM_TDI")
	)
	(segment
		(start 38.151257 24.914225)
		(end 37.663171 24.914225)
		(width 0.12065)
		(layer "In7.Cu")
		(net "NFP_JTAG_ARM_TDI")
	)
	(segment
		(start 37.832132 19.166992)
		(end 38.14633 18.852794)
		(width 0.12065)
		(layer "In7.Cu")
		(net "NFP_JTAG_ARM_TDI")
	)
	(segment
		(start 36.883975 39.570025)
		(end 36.923929 39.570025)
		(width 0.12065)
		(layer "In7.Cu")
		(net "NFP_JTAG_ARM_TDI")
	)
	(segment
		(start 37.665025 35.506025)
		(end 37.338 35.179)
		(width 0.12065)
		(layer "In7.Cu")
		(net "NFP_JTAG_ARM_TDI")
	)
	(segment
		(start 35.366325 42.791329)
		(end 35.366325 42.425671)
		(width 0.12065)
		(layer "In7.Cu")
		(net "NFP_JTAG_ARM_TDI")
	)
	(segment
		(start 37.182425 39.271575)
		(end 37.665025 38.788975)
		(width 0.12065)
		(layer "In7.Cu")
		(net "NFP_JTAG_ARM_TDI")
	)
	(segment
		(start 38.737007 14.861007)
		(end 38.737007 14.542008)
		(width 0.12065)
		(layer "In7.Cu")
		(net "NFP_JTAG_ARM_TDI")
	)
	(segment
		(start 39.243 17.653)
		(end 39.243 15.367)
		(width 0.12065)
		(layer "In7.Cu")
		(net "NFP_JTAG_ARM_TDI")
	)
	(segment
		(start 36.923929 39.570025)
		(end 37.182425 39.311529)
		(width 0.12065)
		(layer "In7.Cu")
		(net "NFP_JTAG_ARM_TDI")
	)
	(segment
		(start 37.665025 38.788975)
		(end 37.665025 35.506025)
		(width 0.12065)
		(layer "In7.Cu")
		(net "NFP_JTAG_ARM_TDI")
	)
	(segment
		(start 38.608 25.49337)
		(end 38.481 25.36637)
		(width 0.12065)
		(layer "In7.Cu")
		(net "NFP_JTAG_ARM_TDI")
	)
	(segment
		(start 38.581432 18.314568)
		(end 39.243 17.653)
		(width 0.12065)
		(layer "In7.Cu")
		(net "NFP_JTAG_ARM_TDI")
	)
	(segment
		(start 38.227 32.691553)
		(end 38.227 32.385)
		(width 0.12065)
		(layer "In7.Cu")
		(net "NFP_JTAG_ARM_TDI")
	)
	(segment
		(start 35.306 42.365346)
		(end 35.306 41.148)
		(width 0.12065)
		(layer "In7.Cu")
		(net "NFP_JTAG_ARM_TDI")
	)
	(segment
		(start 37.338 35.179)
		(end 37.338 33.909)
		(width 0.12065)
		(layer "In7.Cu")
		(net "NFP_JTAG_ARM_TDI")
	)
	(segment
		(start 35.306 44.323)
		(end 35.306 42.851654)
		(width 0.12065)
		(layer "In7.Cu")
		(net "NFP_JTAG_ARM_TDI")
	)
	(segment
		(start 37.338 33.909)
		(end 37.665025 33.581975)
		(width 0.12065)
		(layer "In7.Cu")
		(net "NFP_JTAG_ARM_TDI")
	)
	(segment
		(start 40.237004 14.042009)
		(end 39.737005 13.54201)
		(width 0.13208)
		(layer "F.Cu")
		(net "NFP_JTAG_ARM_TCK")
	)
	(via
		(at 40.737003 27.542007)
		(size 0.4826)
		(drill 0.20574)
		(layers "F.Cu" "B.Cu")
		(net "NFP_JTAG_ARM_TCK")
	)
	(via
		(at 40.894 43.561)
		(size 0.508)
		(drill 0.2667)
		(layers "F.Cu" "B.Cu")
		(net "NFP_JTAG_ARM_TCK")
	)
	(via
		(at 39.737005 13.54201)
		(size 0.4826)
		(drill 0.20574)
		(layers "F.Cu" "B.Cu")
		(net "NFP_JTAG_ARM_TCK")
	)
	(via
		(at 11.43 45.9105)
		(size 0.508)
		(drill 0.25654)
		(layers "F.Cu" "B.Cu")
		(net "NFP_JTAG_ARM_TCK")
	)
	(via
		(at 33.274 46.736)
		(size 0.508)
		(drill 0.25654)
		(layers "F.Cu" "B.Cu")
		(net "NFP_JTAG_ARM_TCK")
	)
	(segment
		(start 12.7 44.958)
		(end 11.811 45.847)
		(width 0.14732)
		(layer "B.Cu")
		(net "NFP_JTAG_ARM_TCK")
	)
	(segment
		(start 40.64 28.4099)
		(end 40.737003 28.312897)
		(width 0.14732)
		(layer "B.Cu")
		(net "NFP_JTAG_ARM_TCK")
	)
	(segment
		(start 40.737003 28.312897)
		(end 40.737003 27.542007)
		(width 0.14732)
		(layer "B.Cu")
		(net "NFP_JTAG_ARM_TCK")
	)
	(segment
		(start 11.4935 45.847)
		(end 11.43 45.9105)
		(width 0.14732)
		(layer "B.Cu")
		(net "NFP_JTAG_ARM_TCK")
	)
	(segment
		(start 12.7 43.8785)
		(end 12.7 44.958)
		(width 0.14732)
		(layer "B.Cu")
		(net "NFP_JTAG_ARM_TCK")
	)
	(segment
		(start 11.811 45.847)
		(end 11.4935 45.847)
		(width 0.14732)
		(layer "B.Cu")
		(net "NFP_JTAG_ARM_TCK")
	)
	(segment
		(start 23.511942 47.513875)
		(end 24.898223 46.127594)
		(width 0.12065)
		(layer "In6.Cu")
		(net "NFP_JTAG_ARM_TCK")
	)
	(segment
		(start 21.982252 47.793199)
		(end 22.261576 47.513875)
		(width 0.12065)
		(layer "In6.Cu")
		(net "NFP_JTAG_ARM_TCK")
	)
	(segment
		(start 26.595121 46.459775)
		(end 28.87345 46.459775)
		(width 0.12065)
		(layer "In6.Cu")
		(net "NFP_JTAG_ARM_TCK")
	)
	(segment
		(start 24.898223 46.127594)
		(end 24.898223 45.766431)
		(width 0.12065)
		(layer "In6.Cu")
		(net "NFP_JTAG_ARM_TCK")
	)
	(segment
		(start 35.823347 47.4853)
		(end 36.036072 47.698025)
		(width 0.12065)
		(layer "In6.Cu")
		(net "NFP_JTAG_ARM_TCK")
	)
	(segment
		(start 37.093779 47.698025)
		(end 37.201729 47.805975)
		(width 0.12065)
		(layer "In6.Cu")
		(net "NFP_JTAG_ARM_TCK")
	)
	(segment
		(start 29.3243 46.910625)
		(end 32.212458 46.910625)
		(width 0.12065)
		(layer "In6.Cu")
		(net "NFP_JTAG_ARM_TCK")
	)
	(segment
		(start 33.274 46.736)
		(end 33.303769 46.765769)
		(width 0.12065)
		(layer "In6.Cu")
		(net "NFP_JTAG_ARM_TCK")
	)
	(segment
		(start 33.303769 46.765769)
		(end 33.96963 46.765769)
		(width 0.12065)
		(layer "In6.Cu")
		(net "NFP_JTAG_ARM_TCK")
	)
	(segment
		(start 37.201729 47.806127)
		(end 37.515902 48.1203)
		(width 0.12065)
		(layer "In6.Cu")
		(net "NFP_JTAG_ARM_TCK")
	)
	(segment
		(start 42.037 44.704)
		(end 40.894 43.561)
		(width 0.12065)
		(layer "In6.Cu")
		(net "NFP_JTAG_ARM_TCK")
	)
	(segment
		(start 13.312699 47.793199)
		(end 21.982252 47.793199)
		(width 0.12065)
		(layer "In6.Cu")
		(net "NFP_JTAG_ARM_TCK")
	)
	(segment
		(start 36.036072 47.698025)
		(end 37.093779 47.698025)
		(width 0.12065)
		(layer "In6.Cu")
		(net "NFP_JTAG_ARM_TCK")
	)
	(segment
		(start 33.96963 46.765769)
		(end 34.689161 47.4853)
		(width 0.12065)
		(layer "In6.Cu")
		(net "NFP_JTAG_ARM_TCK")
	)
	(segment
		(start 11.43 45.9105)
		(end 13.312699 47.793199)
		(width 0.12065)
		(layer "In6.Cu")
		(net "NFP_JTAG_ARM_TCK")
	)
	(segment
		(start 34.689161 47.4853)
		(end 35.823347 47.4853)
		(width 0.12065)
		(layer "In6.Cu")
		(net "NFP_JTAG_ARM_TCK")
	)
	(segment
		(start 33.22795 46.694725)
		(end 33.269225 46.736)
		(width 0.12065)
		(layer "In6.Cu")
		(net "NFP_JTAG_ARM_TCK")
	)
	(segment
		(start 24.898223 45.766431)
		(end 25.195479 45.469175)
		(width 0.12065)
		(layer "In6.Cu")
		(net "NFP_JTAG_ARM_TCK")
	)
	(segment
		(start 37.201729 47.805975)
		(end 37.201729 47.806127)
		(width 0.12065)
		(layer "In6.Cu")
		(net "NFP_JTAG_ARM_TCK")
	)
	(segment
		(start 22.261576 47.513875)
		(end 23.511942 47.513875)
		(width 0.12065)
		(layer "In6.Cu")
		(net "NFP_JTAG_ARM_TCK")
	)
	(segment
		(start 41.284627 47.678975)
		(end 42.037 46.926602)
		(width 0.12065)
		(layer "In6.Cu")
		(net "NFP_JTAG_ARM_TCK")
	)
	(segment
		(start 28.87345 46.459775)
		(end 29.3243 46.910625)
		(width 0.12065)
		(layer "In6.Cu")
		(net "NFP_JTAG_ARM_TCK")
	)
	(segment
		(start 25.604521 45.469175)
		(end 26.595121 46.459775)
		(width 0.12065)
		(layer "In6.Cu")
		(net "NFP_JTAG_ARM_TCK")
	)
	(segment
		(start 42.037 46.926602)
		(end 42.037 44.704)
		(width 0.12065)
		(layer "In6.Cu")
		(net "NFP_JTAG_ARM_TCK")
	)
	(segment
		(start 37.515902 48.1203)
		(end 39.404747 48.1203)
		(width 0.12065)
		(layer "In6.Cu")
		(net "NFP_JTAG_ARM_TCK")
	)
	(segment
		(start 32.428358 46.694725)
		(end 33.22795 46.694725)
		(width 0.12065)
		(layer "In6.Cu")
		(net "NFP_JTAG_ARM_TCK")
	)
	(segment
		(start 32.212458 46.910625)
		(end 32.428358 46.694725)
		(width 0.12065)
		(layer "In6.Cu")
		(net "NFP_JTAG_ARM_TCK")
	)
	(segment
		(start 33.269225 46.736)
		(end 33.274 46.736)
		(width 0.12065)
		(layer "In6.Cu")
		(net "NFP_JTAG_ARM_TCK")
	)
	(segment
		(start 39.846072 47.678975)
		(end 41.284627 47.678975)
		(width 0.12065)
		(layer "In6.Cu")
		(net "NFP_JTAG_ARM_TCK")
	)
	(segment
		(start 25.195479 45.469175)
		(end 25.604521 45.469175)
		(width 0.12065)
		(layer "In6.Cu")
		(net "NFP_JTAG_ARM_TCK")
	)
	(segment
		(start 39.404747 48.1203)
		(end 39.846072 47.678975)
		(width 0.12065)
		(layer "In6.Cu")
		(net "NFP_JTAG_ARM_TCK")
	)
	(segment
		(start 41.275 27.051)
		(end 41.275 18.923)
		(width 0.12065)
		(layer "In7.Cu")
		(net "NFP_JTAG_ARM_TCK")
	)
	(segment
		(start 41.904056 15.138781)
		(end 41.763493 15.138781)
		(width 0.12065)
		(layer "In7.Cu")
		(net "NFP_JTAG_ARM_TCK")
	)
	(segment
		(start 41.275 28.080005)
		(end 40.737003 27.542007)
		(width 0.12065)
		(layer "In7.Cu")
		(net "NFP_JTAG_ARM_TCK")
	)
	(segment
		(start 41.275 18.923)
		(end 42.291 17.907)
		(width 0.12065)
		(layer "In7.Cu")
		(net "NFP_JTAG_ARM_TCK")
	)
	(segment
		(start 40.737003 27.542007)
		(end 41.275 27.051)
		(width 0.12065)
		(layer "In7.Cu")
		(net "NFP_JTAG_ARM_TCK")
	)
	(segment
		(start 41.333776 14.709064)
		(end 41.333776 14.536776)
		(width 0.12065)
		(layer "In7.Cu")
		(net "NFP_JTAG_ARM_TCK")
	)
	(segment
		(start 40.64 37.719)
		(end 41.275 37.084)
		(width 0.12065)
		(layer "In7.Cu")
		(net "NFP_JTAG_ARM_TCK")
	)
	(segment
		(start 41.333776 14.536776)
		(end 40.33901 13.54201)
		(width 0.12065)
		(layer "In7.Cu")
		(net "NFP_JTAG_ARM_TCK")
	)
	(segment
		(start 41.763493 15.138781)
		(end 41.333776 14.709064)
		(width 0.12065)
		(layer "In7.Cu")
		(net "NFP_JTAG_ARM_TCK")
	)
	(segment
		(start 42.291 15.525725)
		(end 41.904056 15.138781)
		(width 0.12065)
		(layer "In7.Cu")
		(net "NFP_JTAG_ARM_TCK")
	)
	(segment
		(start 42.291 17.907)
		(end 42.291 15.525725)
		(width 0.12065)
		(layer "In7.Cu")
		(net "NFP_JTAG_ARM_TCK")
	)
	(segment
		(start 40.894 43.561)
		(end 40.64 43.307)
		(width 0.12065)
		(layer "In7.Cu")
		(net "NFP_JTAG_ARM_TCK")
	)
	(segment
		(start 41.275 37.084)
		(end 41.275 28.080005)
		(width 0.12065)
		(layer "In7.Cu")
		(net "NFP_JTAG_ARM_TCK")
	)
	(segment
		(start 40.33901 13.54201)
		(end 39.737005 13.54201)
		(width 0.12065)
		(layer "In7.Cu")
		(net "NFP_JTAG_ARM_TCK")
	)
	(segment
		(start 40.64 43.307)
		(end 40.64 37.719)
		(width 0.12065)
		(layer "In7.Cu")
		(net "NFP_JTAG_ARM_TCK")
	)
	(segment
		(start 22.856012 34.0868)
		(end 22.856012 34.540012)
		(width 0.14732)
		(layer "F.Cu")
		(net "NFP_CPLD_PRGM_JTAG_TMS")
	)
	(segment
		(start 22.856012 34.540012)
		(end 23.114 34.798)
		(width 0.14732)
		(layer "F.Cu")
		(net "NFP_CPLD_PRGM_JTAG_TMS")
	)
	(segment
		(start 23.2791 34.798)
		(end 23.749 35.2679)
		(width 0.14732)
		(layer "F.Cu")
		(net "NFP_CPLD_PRGM_JTAG_TMS")
	)
	(segment
		(start 23.114 34.798)
		(end 23.2791 34.798)
		(width 0.14732)
		(layer "F.Cu")
		(net "NFP_CPLD_PRGM_JTAG_TMS")
	)
	(segment
		(start 41.237002 12.041988)
		(end 40.737003 11.541989)
		(width 0.13208)
		(layer "F.Cu")
		(net "NFP_CPLD_PRGM_JTAG_TMS")
	)
	(via
		(at 23.749 35.2425)
		(size 0.508)
		(drill 0.25654)
		(layers "F.Cu" "B.Cu")
		(net "NFP_CPLD_PRGM_JTAG_TMS")
	)
	(via
		(at 25.019 26.797)
		(size 0.508)
		(drill 0.2667)
		(layers "F.Cu" "B.Cu")
		(net "NFP_CPLD_PRGM_JTAG_TMS")
	)
	(via
		(at 40.737003 11.541989)
		(size 0.4826)
		(drill 0.20574)
		(layers "F.Cu" "B.Cu")
		(net "NFP_CPLD_PRGM_JTAG_TMS")
	)
	(segment
		(start 44.33377 14.5685)
		(end 43.904052 14.138783)
		(width 0.12065)
		(layer "In2.Cu")
		(net "NFP_CPLD_PRGM_JTAG_TMS")
	)
	(segment
		(start 27.061516 23.103459)
		(end 27.812975 22.352)
		(width 0.12065)
		(layer "In2.Cu")
		(net "NFP_CPLD_PRGM_JTAG_TMS")
	)
	(segment
		(start 43.821223 17.138777)
		(end 44.33377 16.62623)
		(width 0.12065)
		(layer "In2.Cu")
		(net "NFP_CPLD_PRGM_JTAG_TMS")
	)
	(segment
		(start 26.532459 23.332796)
		(end 26.761796 23.103459)
		(width 0.12065)
		(layer "In2.Cu")
		(net "NFP_CPLD_PRGM_JTAG_TMS")
	)
	(segment
		(start 43.569941 17.138777)
		(end 43.821223 17.138777)
		(width 0.12065)
		(layer "In2.Cu")
		(net "NFP_CPLD_PRGM_JTAG_TMS")
	)
	(segment
		(start 42.291 12.827)
		(end 42.291 12.319)
		(width 0.12065)
		(layer "In2.Cu")
		(net "NFP_CPLD_PRGM_JTAG_TMS")
	)
	(segment
		(start 23.434675 25.085675)
		(end 23.434675 23.312171)
		(width 0.12065)
		(layer "In2.Cu")
		(net "NFP_CPLD_PRGM_JTAG_TMS")
	)
	(segment
		(start 45.212 15.367)
		(end 44.790233 14.945233)
		(width 0.12065)
		(layer "In2.Cu")
		(net "NFP_CPLD_PRGM_JTAG_TMS")
	)
	(segment
		(start 44.33377 16.62623)
		(end 44.33377 16.374948)
		(width 0.12065)
		(layer "In2.Cu")
		(net "NFP_CPLD_PRGM_JTAG_TMS")
	)
	(segment
		(start 44.569939 14.945233)
		(end 44.33377 14.709064)
		(width 0.12065)
		(layer "In2.Cu")
		(net "NFP_CPLD_PRGM_JTAG_TMS")
	)
	(segment
		(start 36.873155 21.717)
		(end 37.010696 21.579459)
		(width 0.12065)
		(layer "In2.Cu")
		(net "NFP_CPLD_PRGM_JTAG_TMS")
	)
	(segment
		(start 43.333772 17.374946)
		(end 43.569941 17.138777)
		(width 0.12065)
		(layer "In2.Cu")
		(net "NFP_CPLD_PRGM_JTAG_TMS")
	)
	(segment
		(start 44.569939 16.138779)
		(end 44.821221 16.138779)
		(width 0.12065)
		(layer "In2.Cu")
		(net "NFP_CPLD_PRGM_JTAG_TMS")
	)
	(segment
		(start 23.693171 23.053675)
		(end 24.704675 23.053675)
		(width 0.12065)
		(layer "In2.Cu")
		(net "NFP_CPLD_PRGM_JTAG_TMS")
	)
	(segment
		(start 35.179 21.717)
		(end 36.873155 21.717)
		(width 0.12065)
		(layer "In2.Cu")
		(net "NFP_CPLD_PRGM_JTAG_TMS")
	)
	(segment
		(start 37.010696 21.579459)
		(end 37.348541 21.579459)
		(width 0.12065)
		(layer "In2.Cu")
		(net "NFP_CPLD_PRGM_JTAG_TMS")
	)
	(segment
		(start 42.846269 13.081)
		(end 42.545 13.081)
		(width 0.12065)
		(layer "In2.Cu")
		(net "NFP_CPLD_PRGM_JTAG_TMS")
	)
	(segment
		(start 43.333772 13.709066)
		(end 43.333772 13.568502)
		(width 0.12065)
		(layer "In2.Cu")
		(net "NFP_CPLD_PRGM_JTAG_TMS")
	)
	(segment
		(start 43.333772 13.568502)
		(end 42.846269 13.081)
		(width 0.12065)
		(layer "In2.Cu")
		(net "NFP_CPLD_PRGM_JTAG_TMS")
	)
	(segment
		(start 25.019 26.797)
		(end 25.019 26.67)
		(width 0.12065)
		(layer "In2.Cu")
		(net "NFP_CPLD_PRGM_JTAG_TMS")
	)
	(segment
		(start 23.434675 23.312171)
		(end 23.693171 23.053675)
		(width 0.12065)
		(layer "In2.Cu")
		(net "NFP_CPLD_PRGM_JTAG_TMS")
	)
	(segment
		(start 26.761796 23.103459)
		(end 27.061516 23.103459)
		(width 0.12065)
		(layer "In2.Cu")
		(net "NFP_CPLD_PRGM_JTAG_TMS")
	)
	(segment
		(start 45.212 15.748)
		(end 45.212 15.367)
		(width 0.12065)
		(layer "In2.Cu")
		(net "NFP_CPLD_PRGM_JTAG_TMS")
	)
	(segment
		(start 42.291 12.319)
		(end 42.037 12.065)
		(width 0.12065)
		(layer "In2.Cu")
		(net "NFP_CPLD_PRGM_JTAG_TMS")
	)
	(segment
		(start 26.532459 23.632516)
		(end 26.532459 23.332796)
		(width 0.12065)
		(layer "In2.Cu")
		(net "NFP_CPLD_PRGM_JTAG_TMS")
	)
	(segment
		(start 37.348541 21.579459)
		(end 39.243 19.685)
		(width 0.12065)
		(layer "In2.Cu")
		(net "NFP_CPLD_PRGM_JTAG_TMS")
	)
	(segment
		(start 26.223316 23.941659)
		(end 26.532459 23.632516)
		(width 0.12065)
		(layer "In2.Cu")
		(net "NFP_CPLD_PRGM_JTAG_TMS")
	)
	(segment
		(start 43.333772 17.626228)
		(end 43.333772 17.374946)
		(width 0.12065)
		(layer "In2.Cu")
		(net "NFP_CPLD_PRGM_JTAG_TMS")
	)
	(segment
		(start 44.33377 14.709064)
		(end 44.33377 14.5685)
		(width 0.12065)
		(layer "In2.Cu")
		(net "NFP_CPLD_PRGM_JTAG_TMS")
	)
	(segment
		(start 25.592659 23.941659)
		(end 26.223316 23.941659)
		(width 0.12065)
		(layer "In2.Cu")
		(net "NFP_CPLD_PRGM_JTAG_TMS")
	)
	(segment
		(start 27.812975 22.352)
		(end 34.544 22.352)
		(width 0.12065)
		(layer "In2.Cu")
		(net "NFP_CPLD_PRGM_JTAG_TMS")
	)
	(segment
		(start 42.037 12.065)
		(end 41.260014 12.065)
		(width 0.12065)
		(layer "In2.Cu")
		(net "NFP_CPLD_PRGM_JTAG_TMS")
	)
	(segment
		(start 42.545 13.081)
		(end 42.291 12.827)
		(width 0.12065)
		(layer "In2.Cu")
		(net "NFP_CPLD_PRGM_JTAG_TMS")
	)
	(segment
		(start 43.904052 14.138783)
		(end 43.763489 14.138783)
		(width 0.12065)
		(layer "In2.Cu")
		(net "NFP_CPLD_PRGM_JTAG_TMS")
	)
	(segment
		(start 44.821221 16.138779)
		(end 45.212 15.748)
		(width 0.12065)
		(layer "In2.Cu")
		(net "NFP_CPLD_PRGM_JTAG_TMS")
	)
	(segment
		(start 40.005 18.542)
		(end 42.418 18.542)
		(width 0.12065)
		(layer "In2.Cu")
		(net "NFP_CPLD_PRGM_JTAG_TMS")
	)
	(segment
		(start 44.33377 16.374948)
		(end 44.569939 16.138779)
		(width 0.12065)
		(layer "In2.Cu")
		(net "NFP_CPLD_PRGM_JTAG_TMS")
	)
	(segment
		(start 43.763489 14.138783)
		(end 43.333772 13.709066)
		(width 0.12065)
		(layer "In2.Cu")
		(net "NFP_CPLD_PRGM_JTAG_TMS")
	)
	(segment
		(start 39.243 19.304)
		(end 40.005 18.542)
		(width 0.12065)
		(layer "In2.Cu")
		(net "NFP_CPLD_PRGM_JTAG_TMS")
	)
	(segment
		(start 42.418 18.542)
		(end 43.333772 17.626228)
		(width 0.12065)
		(layer "In2.Cu")
		(net "NFP_CPLD_PRGM_JTAG_TMS")
	)
	(segment
		(start 39.243 19.685)
		(end 39.243 19.304)
		(width 0.12065)
		(layer "In2.Cu")
		(net "NFP_CPLD_PRGM_JTAG_TMS")
	)
	(segment
		(start 41.260014 12.065)
		(end 40.737003 11.541989)
		(width 0.12065)
		(layer "In2.Cu")
		(net "NFP_CPLD_PRGM_JTAG_TMS")
	)
	(segment
		(start 34.544 22.352)
		(end 35.179 21.717)
		(width 0.12065)
		(layer "In2.Cu")
		(net "NFP_CPLD_PRGM_JTAG_TMS")
	)
	(segment
		(start 44.790233 14.945233)
		(end 44.569939 14.945233)
		(width 0.12065)
		(layer "In2.Cu")
		(net "NFP_CPLD_PRGM_JTAG_TMS")
	)
	(segment
		(start 24.704675 23.053675)
		(end 25.592659 23.941659)
		(width 0.12065)
		(layer "In2.Cu")
		(net "NFP_CPLD_PRGM_JTAG_TMS")
	)
	(segment
		(start 25.019 26.67)
		(end 23.434675 25.085675)
		(width 0.12065)
		(layer "In2.Cu")
		(net "NFP_CPLD_PRGM_JTAG_TMS")
	)
	(segment
		(start 25.019 27.713254)
		(end 23.869675 28.862579)
		(width 0.12065)
		(layer "In6.Cu")
		(net "NFP_CPLD_PRGM_JTAG_TMS")
	)
	(segment
		(start 23.869675 28.862579)
		(end 23.86965 28.862579)
		(width 0.12065)
		(layer "In6.Cu")
		(net "NFP_CPLD_PRGM_JTAG_TMS")
	)
	(segment
		(start 23.749 28.983229)
		(end 23.749 35.2425)
		(width 0.12065)
		(layer "In6.Cu")
		(net "NFP_CPLD_PRGM_JTAG_TMS")
	)
	(segment
		(start 23.86965 28.862579)
		(end 23.749 28.983229)
		(width 0.12065)
		(layer "In6.Cu")
		(net "NFP_CPLD_PRGM_JTAG_TMS")
	)
	(segment
		(start 25.019 26.797)
		(end 25.019 27.713254)
		(width 0.12065)
		(layer "In6.Cu")
		(net "NFP_CPLD_PRGM_JTAG_TMS")
	)
	(segment
		(start 21.1074 35.2425)
		(end 21.35599 34.99391)
		(width 0.14732)
		(layer "F.Cu")
		(net "NFP_CPLD_PRGM_JTAG_TDO")
	)
	(segment
		(start 21.35599 34.99391)
		(end 21.35599 34.0868)
		(width 0.14732)
		(layer "F.Cu")
		(net "NFP_CPLD_PRGM_JTAG_TDO")
	)
	(segment
		(start 21.082 35.2679)
		(end 21.1074 35.2425)
		(width 0.14732)
		(layer "F.Cu")
		(net "NFP_CPLD_PRGM_JTAG_TDO")
	)
	(segment
		(start 43.236998 12.041988)
		(end 42.736999 11.541989)
		(width 0.13208)
		(layer "F.Cu")
		(net "NFP_CPLD_PRGM_JTAG_TDO")
	)
	(via
		(at 23.876 23.495)
		(size 0.508)
		(drill 0.254)
		(layers "F.Cu" "B.Cu")
		(net "NFP_CPLD_PRGM_JTAG_TDO")
	)
	(via
		(at 42.736999 11.541989)
		(size 0.4826)
		(drill 0.20574)
		(layers "F.Cu" "B.Cu")
		(net "NFP_CPLD_PRGM_JTAG_TDO")
	)
	(via
		(at 21.1074 35.2425)
		(size 0.508)
		(drill 0.25654)
		(layers "F.Cu" "B.Cu")
		(net "NFP_CPLD_PRGM_JTAG_TDO")
	)
	(segment
		(start 46.228 15.367)
		(end 46.228 15.621279)
		(width 0.12065)
		(layer "In2.Cu")
		(net "NFP_CPLD_PRGM_JTAG_TDO")
	)
	(segment
		(start 43.904052 17.945227)
		(end 43.569941 17.945227)
		(width 0.12065)
		(layer "In2.Cu")
		(net "NFP_CPLD_PRGM_JTAG_TDO")
	)
	(segment
		(start 26.502741 24.200714)
		(end 26.502741 24.495404)
		(width 0.12065)
		(layer "In2.Cu")
		(net "NFP_CPLD_PRGM_JTAG_TDO")
	)
	(segment
		(start 43.569941 17.945227)
		(end 42.505046 19.010122)
		(width 0.12065)
		(layer "In2.Cu")
		(net "NFP_CPLD_PRGM_JTAG_TDO")
	)
	(segment
		(start 26.273404 24.724741)
		(end 25.105741 24.724741)
		(width 0.12065)
		(layer "In2.Cu")
		(net "NFP_CPLD_PRGM_JTAG_TDO")
	)
	(segment
		(start 27.086204 23.941659)
		(end 26.761796 23.941659)
		(width 0.12065)
		(layer "In2.Cu")
		(net "NFP_CPLD_PRGM_JTAG_TDO")
	)
	(segment
		(start 26.502741 24.495404)
		(end 26.273404 24.724741)
		(width 0.12065)
		(layer "In2.Cu")
		(net "NFP_CPLD_PRGM_JTAG_TDO")
	)
	(segment
		(start 40.14023 19.709054)
		(end 39.710512 20.138771)
		(width 0.12065)
		(layer "In2.Cu")
		(net "NFP_CPLD_PRGM_JTAG_TDO")
	)
	(segment
		(start 35.113341 22.544659)
		(end 34.925 22.733)
		(width 0.12065)
		(layer "In2.Cu")
		(net "NFP_CPLD_PRGM_JTAG_TDO")
	)
	(segment
		(start 44.140222 13.533222)
		(end 44.745783 14.138783)
		(width 0.12065)
		(layer "In2.Cu")
		(net "NFP_CPLD_PRGM_JTAG_TDO")
	)
	(segment
		(start 43.18 12.573)
		(end 43.745785 13.138785)
		(width 0.12065)
		(layer "In2.Cu")
		(net "NFP_CPLD_PRGM_JTAG_TDO")
	)
	(segment
		(start 45.974 15.113)
		(end 46.228 15.367)
		(width 0.12065)
		(layer "In2.Cu")
		(net "NFP_CPLD_PRGM_JTAG_TDO")
	)
	(segment
		(start 40.679878 19.010122)
		(end 40.14023 19.54977)
		(width 0.12065)
		(layer "In2.Cu")
		(net "NFP_CPLD_PRGM_JTAG_TDO")
	)
	(segment
		(start 45.14022 14.53322)
		(end 45.72 15.113)
		(width 0.12065)
		(layer "In2.Cu")
		(net "NFP_CPLD_PRGM_JTAG_TDO")
	)
	(segment
		(start 43.745785 13.138785)
		(end 43.904052 13.138785)
		(width 0.12065)
		(layer "In2.Cu")
		(net "NFP_CPLD_PRGM_JTAG_TDO")
	)
	(segment
		(start 44.140222 17.709058)
		(end 43.904052 17.945227)
		(width 0.12065)
		(layer "In2.Cu")
		(net "NFP_CPLD_PRGM_JTAG_TDO")
	)
	(segment
		(start 34.925 22.733)
		(end 28.294863 22.733)
		(width 0.12065)
		(layer "In2.Cu")
		(net "NFP_CPLD_PRGM_JTAG_TDO")
	)
	(segment
		(start 38.333782 21.483193)
		(end 37.272316 22.544659)
		(width 0.12065)
		(layer "In2.Cu")
		(net "NFP_CPLD_PRGM_JTAG_TDO")
	)
	(segment
		(start 45.72 15.113)
		(end 45.974 15.113)
		(width 0.12065)
		(layer "In2.Cu")
		(net "NFP_CPLD_PRGM_JTAG_TDO")
	)
	(segment
		(start 45.14022 16.374948)
		(end 45.14022 16.70906)
		(width 0.12065)
		(layer "In2.Cu")
		(net "NFP_CPLD_PRGM_JTAG_TDO")
	)
	(segment
		(start 44.140222 13.374954)
		(end 44.140222 13.533222)
		(width 0.12065)
		(layer "In2.Cu")
		(net "NFP_CPLD_PRGM_JTAG_TDO")
	)
	(segment
		(start 44.90405 16.945229)
		(end 44.569939 16.945229)
		(width 0.12065)
		(layer "In2.Cu")
		(net "NFP_CPLD_PRGM_JTAG_TDO")
	)
	(segment
		(start 42.736999 11.541989)
		(end 43.18 11.98499)
		(width 0.12065)
		(layer "In2.Cu")
		(net "NFP_CPLD_PRGM_JTAG_TDO")
	)
	(segment
		(start 38.333782 21.374938)
		(end 38.333782 21.483193)
		(width 0.12065)
		(layer "In2.Cu")
		(net "NFP_CPLD_PRGM_JTAG_TDO")
	)
	(segment
		(start 28.294863 22.733)
		(end 27.086204 23.941659)
		(width 0.12065)
		(layer "In2.Cu")
		(net "NFP_CPLD_PRGM_JTAG_TDO")
	)
	(segment
		(start 42.505046 19.010122)
		(end 40.679878 19.010122)
		(width 0.12065)
		(layer "In2.Cu")
		(net "NFP_CPLD_PRGM_JTAG_TDO")
	)
	(segment
		(start 40.14023 19.54977)
		(end 40.14023 19.709054)
		(width 0.12065)
		(layer "In2.Cu")
		(net "NFP_CPLD_PRGM_JTAG_TDO")
	)
	(segment
		(start 37.272316 22.544659)
		(end 35.113341 22.544659)
		(width 0.12065)
		(layer "In2.Cu")
		(net "NFP_CPLD_PRGM_JTAG_TDO")
	)
	(segment
		(start 45.569937 15.945231)
		(end 45.14022 16.374948)
		(width 0.12065)
		(layer "In2.Cu")
		(net "NFP_CPLD_PRGM_JTAG_TDO")
	)
	(segment
		(start 39.710512 20.138771)
		(end 39.569949 20.138771)
		(width 0.12065)
		(layer "In2.Cu")
		(net "NFP_CPLD_PRGM_JTAG_TDO")
	)
	(segment
		(start 26.761796 23.941659)
		(end 26.502741 24.200714)
		(width 0.12065)
		(layer "In2.Cu")
		(net "NFP_CPLD_PRGM_JTAG_TDO")
	)
	(segment
		(start 45.14022 16.70906)
		(end 44.90405 16.945229)
		(width 0.12065)
		(layer "In2.Cu")
		(net "NFP_CPLD_PRGM_JTAG_TDO")
	)
	(segment
		(start 39.569949 20.138771)
		(end 38.333782 21.374938)
		(width 0.12065)
		(layer "In2.Cu")
		(net "NFP_CPLD_PRGM_JTAG_TDO")
	)
	(segment
		(start 44.569939 16.945229)
		(end 44.140222 17.374946)
		(width 0.12065)
		(layer "In2.Cu")
		(net "NFP_CPLD_PRGM_JTAG_TDO")
	)
	(segment
		(start 44.90405 14.138783)
		(end 45.14022 14.374952)
		(width 0.12065)
		(layer "In2.Cu")
		(net "NFP_CPLD_PRGM_JTAG_TDO")
	)
	(segment
		(start 45.14022 14.374952)
		(end 45.14022 14.53322)
		(width 0.12065)
		(layer "In2.Cu")
		(net "NFP_CPLD_PRGM_JTAG_TDO")
	)
	(segment
		(start 44.745783 14.138783)
		(end 44.90405 14.138783)
		(width 0.12065)
		(layer "In2.Cu")
		(net "NFP_CPLD_PRGM_JTAG_TDO")
	)
	(segment
		(start 43.904052 13.138785)
		(end 44.140222 13.374954)
		(width 0.12065)
		(layer "In2.Cu")
		(net "NFP_CPLD_PRGM_JTAG_TDO")
	)
	(segment
		(start 45.904048 15.945231)
		(end 45.569937 15.945231)
		(width 0.12065)
		(layer "In2.Cu")
		(net "NFP_CPLD_PRGM_JTAG_TDO")
	)
	(segment
		(start 44.140222 17.374946)
		(end 44.140222 17.709058)
		(width 0.12065)
		(layer "In2.Cu")
		(net "NFP_CPLD_PRGM_JTAG_TDO")
	)
	(segment
		(start 46.228 15.621279)
		(end 45.904048 15.945231)
		(width 0.12065)
		(layer "In2.Cu")
		(net "NFP_CPLD_PRGM_JTAG_TDO")
	)
	(segment
		(start 43.18 11.98499)
		(end 43.18 12.573)
		(width 0.12065)
		(layer "In2.Cu")
		(net "NFP_CPLD_PRGM_JTAG_TDO")
	)
	(segment
		(start 25.105741 24.724741)
		(end 23.876 23.495)
		(width 0.12065)
		(layer "In2.Cu")
		(net "NFP_CPLD_PRGM_JTAG_TDO")
	)
	(segment
		(start 22.860076 24.510924)
		(end 23.876 23.495)
		(width 0.12065)
		(layer "In7.Cu")
		(net "NFP_CPLD_PRGM_JTAG_TDO")
	)
	(segment
		(start 20.447 30.226)
		(end 20.447 29.591)
		(width 0.12065)
		(layer "In7.Cu")
		(net "NFP_CPLD_PRGM_JTAG_TDO")
	)
	(segment
		(start 21.1074 35.2425)
		(end 21.082 34.417)
		(width 0.12065)
		(layer "In7.Cu")
		(net "NFP_CPLD_PRGM_JTAG_TDO")
	)
	(segment
		(start 20.701 34.036)
		(end 20.701 30.48)
		(width 0.12065)
		(layer "In7.Cu")
		(net "NFP_CPLD_PRGM_JTAG_TDO")
	)
	(segment
		(start 22.860076 27.40467)
		(end 22.860076 24.510924)
		(width 0.12065)
		(layer "In7.Cu")
		(net "NFP_CPLD_PRGM_JTAG_TDO")
	)
	(segment
		(start 20.701 30.48)
		(end 20.447 30.226)
		(width 0.12065)
		(layer "In7.Cu")
		(net "NFP_CPLD_PRGM_JTAG_TDO")
	)
	(segment
		(start 20.704175 29.333825)
		(end 21.137829 29.333825)
		(width 0.12065)
		(layer "In7.Cu")
		(net "NFP_CPLD_PRGM_JTAG_TDO")
	)
	(segment
		(start 22.098 28.166746)
		(end 22.860076 27.40467)
		(width 0.12065)
		(layer "In7.Cu")
		(net "NFP_CPLD_PRGM_JTAG_TDO")
	)
	(segment
		(start 20.447 29.591)
		(end 20.704175 29.333825)
		(width 0.12065)
		(layer "In7.Cu")
		(net "NFP_CPLD_PRGM_JTAG_TDO")
	)
	(segment
		(start 22.098 28.373654)
		(end 22.098 28.166746)
		(width 0.12065)
		(layer "In7.Cu")
		(net "NFP_CPLD_PRGM_JTAG_TDO")
	)
	(segment
		(start 21.137829 29.333825)
		(end 22.098 28.373654)
		(width 0.12065)
		(layer "In7.Cu")
		(net "NFP_CPLD_PRGM_JTAG_TDO")
	)
	(segment
		(start 21.082 34.417)
		(end 20.701 34.036)
		(width 0.12065)
		(layer "In7.Cu")
		(net "NFP_CPLD_PRGM_JTAG_TDO")
	)
	(segment
		(start 20.50034 28.166466)
		(end 20.50034 30.152315)
		(width 0.14732)
		(layer "F.Cu")
		(net "NFP_CPLD_PRGM_JTAG_TDI")
	)
	(segment
		(start 20.193 27.60406)
		(end 20.193 27.859126)
		(width 0.14732)
		(layer "F.Cu")
		(net "NFP_CPLD_PRGM_JTAG_TDI")
	)
	(segment
		(start 19.05 27.051)
		(end 19.63994 27.051)
		(width 0.14732)
		(layer "F.Cu")
		(net "NFP_CPLD_PRGM_JTAG_TDI")
	)
	(segment
		(start 20.50034 30.152315)
		(end 21.209025 30.861)
		(width 0.14732)
		(layer "F.Cu")
		(net "NFP_CPLD_PRGM_JTAG_TDI")
	)
	(segment
		(start 21.59 30.861)
		(end 21.855989 31.126989)
		(width 0.14732)
		(layer "F.Cu")
		(net "NFP_CPLD_PRGM_JTAG_TDI")
	)
	(segment
		(start 21.209025 30.861)
		(end 21.59 30.861)
		(width 0.14732)
		(layer "F.Cu")
		(net "NFP_CPLD_PRGM_JTAG_TDI")
	)
	(segment
		(start 44.236996 12.041988)
		(end 43.736997 11.541989)
		(width 0.13208)
		(layer "F.Cu")
		(net "NFP_CPLD_PRGM_JTAG_TDI")
	)
	(segment
		(start 21.855989 31.126989)
		(end 21.855989 31.6992)
		(width 0.14732)
		(layer "F.Cu")
		(net "NFP_CPLD_PRGM_JTAG_TDI")
	)
	(segment
		(start 20.193 27.859126)
		(end 20.50034 28.166466)
		(width 0.14732)
		(layer "F.Cu")
		(net "NFP_CPLD_PRGM_JTAG_TDI")
	)
	(segment
		(start 19.4691 28.448)
		(end 19.4691 28.008199)
		(width 0.14732)
		(layer "F.Cu")
		(net "NFP_CPLD_PRGM_JTAG_TDI")
	)
	(segment
		(start 19.63994 27.051)
		(end 20.193 27.60406)
		(width 0.14732)
		(layer "F.Cu")
		(net "NFP_CPLD_PRGM_JTAG_TDI")
	)
	(segment
		(start 19.4691 28.008199)
		(end 19.05 27.589099)
		(width 0.14732)
		(layer "F.Cu")
		(net "NFP_CPLD_PRGM_JTAG_TDI")
	)
	(segment
		(start 19.05 27.589099)
		(end 19.05 27.051)
		(width 0.14732)
		(layer "F.Cu")
		(net "NFP_CPLD_PRGM_JTAG_TDI")
	)
	(via
		(at 19.05 27.051)
		(size 0.762)
		(drill 0.381)
		(layers "F.Cu" "B.Cu")
		(net "NFP_CPLD_PRGM_JTAG_TDI")
	)
	(via
		(at 19.4691 28.448)
		(size 0.508)
		(drill 0.25654)
		(layers "F.Cu" "B.Cu")
		(net "NFP_CPLD_PRGM_JTAG_TDI")
	)
	(via
		(at 43.736997 11.541989)
		(size 0.4826)
		(drill 0.20574)
		(layers "F.Cu" "B.Cu")
		(net "NFP_CPLD_PRGM_JTAG_TDI")
	)
	(segment
		(start 20.574 30.226)
		(end 20.32 29.972)
		(width 0.12065)
		(layer "In3.Cu")
		(net "NFP_CPLD_PRGM_JTAG_TDI")
	)
	(segment
		(start 38.1 23.48865)
		(end 37.97935 23.368)
		(width 0.12065)
		(layer "In3.Cu")
		(net "NFP_CPLD_PRGM_JTAG_TDI")
	)
	(segment
		(start 26.67 29.337)
		(end 25.781 30.226)
		(width 0.12065)
		(layer "In3.Cu")
		(net "NFP_CPLD_PRGM_JTAG_TDI")
	)
	(segment
		(start 34.29 23.368)
		(end 33.909 23.749)
		(width 0.12065)
		(layer "In3.Cu")
		(net "NFP_CPLD_PRGM_JTAG_TDI")
	)
	(segment
		(start 43.805221 16.138779)
		(end 43.569941 16.138779)
		(width 0.12065)
		(layer "In3.Cu")
		(net "NFP_CPLD_PRGM_JTAG_TDI")
	)
	(segment
		(start 38.1 23.495)
		(end 38.1 23.48865)
		(width 0.12065)
		(layer "In3.Cu")
		(net "NFP_CPLD_PRGM_JTAG_TDI")
	)
	(segment
		(start 42.904054 16.945229)
		(end 42.763491 16.945229)
		(width 0.12065)
		(layer "In3.Cu")
		(net "NFP_CPLD_PRGM_JTAG_TDI")
	)
	(segment
		(start 20.32 29.972)
		(end 20.32 29.2989)
		(width 0.12065)
		(layer "In3.Cu")
		(net "NFP_CPLD_PRGM_JTAG_TDI")
	)
	(segment
		(start 37.97935 23.368)
		(end 36.418545 23.368)
		(width 0.12065)
		(layer "In3.Cu")
		(net "NFP_CPLD_PRGM_JTAG_TDI")
	)
	(segment
		(start 31.623 29.337)
		(end 26.67 29.337)
		(width 0.12065)
		(layer "In3.Cu")
		(net "NFP_CPLD_PRGM_JTAG_TDI")
	)
	(segment
		(start 43.736997 11.541989)
		(end 44.196 12.000992)
		(width 0.12065)
		(layer "In3.Cu")
		(net "NFP_CPLD_PRGM_JTAG_TDI")
	)
	(segment
		(start 42.763491 16.945229)
		(end 42.291 17.41772)
		(width 0.12065)
		(layer "In3.Cu")
		(net "NFP_CPLD_PRGM_JTAG_TDI")
	)
	(segment
		(start 33.909 23.749)
		(end 33.909 27.051)
		(width 0.12065)
		(layer "In3.Cu")
		(net "NFP_CPLD_PRGM_JTAG_TDI")
	)
	(segment
		(start 20.32 29.2989)
		(end 19.4691 28.448)
		(width 0.12065)
		(layer "In3.Cu")
		(net "NFP_CPLD_PRGM_JTAG_TDI")
	)
	(segment
		(start 36.408004 23.357459)
		(end 35.270796 23.357459)
		(width 0.12065)
		(layer "In3.Cu")
		(net "NFP_CPLD_PRGM_JTAG_TDI")
	)
	(segment
		(start 25.781 30.226)
		(end 20.574 30.226)
		(width 0.12065)
		(layer "In3.Cu")
		(net "NFP_CPLD_PRGM_JTAG_TDI")
	)
	(segment
		(start 33.909 27.051)
		(end 31.623 29.337)
		(width 0.12065)
		(layer "In3.Cu")
		(net "NFP_CPLD_PRGM_JTAG_TDI")
	)
	(segment
		(start 42.291 17.41772)
		(end 42.291 23.622)
		(width 0.12065)
		(layer "In3.Cu")
		(net "NFP_CPLD_PRGM_JTAG_TDI")
	)
	(segment
		(start 43.333772 16.515512)
		(end 42.904054 16.945229)
		(width 0.12065)
		(layer "In3.Cu")
		(net "NFP_CPLD_PRGM_JTAG_TDI")
	)
	(segment
		(start 44.196 12.000992)
		(end 44.196 15.748)
		(width 0.12065)
		(layer "In3.Cu")
		(net "NFP_CPLD_PRGM_JTAG_TDI")
	)
	(segment
		(start 43.333772 16.374948)
		(end 43.333772 16.515512)
		(width 0.12065)
		(layer "In3.Cu")
		(net "NFP_CPLD_PRGM_JTAG_TDI")
	)
	(segment
		(start 35.260255 23.368)
		(end 34.29 23.368)
		(width 0.12065)
		(layer "In3.Cu")
		(net "NFP_CPLD_PRGM_JTAG_TDI")
	)
	(segment
		(start 44.196 15.748)
		(end 43.805221 16.138779)
		(width 0.12065)
		(layer "In3.Cu")
		(net "NFP_CPLD_PRGM_JTAG_TDI")
	)
	(segment
		(start 38.608 24.003)
		(end 38.1 23.495)
		(width 0.12065)
		(layer "In3.Cu")
		(net "NFP_CPLD_PRGM_JTAG_TDI")
	)
	(segment
		(start 35.270796 23.357459)
		(end 35.260255 23.368)
		(width 0.12065)
		(layer "In3.Cu")
		(net "NFP_CPLD_PRGM_JTAG_TDI")
	)
	(segment
		(start 36.418545 23.368)
		(end 36.408004 23.357459)
		(width 0.12065)
		(layer "In3.Cu")
		(net "NFP_CPLD_PRGM_JTAG_TDI")
	)
	(segment
		(start 43.569941 16.138779)
		(end 43.333772 16.374948)
		(width 0.12065)
		(layer "In3.Cu")
		(net "NFP_CPLD_PRGM_JTAG_TDI")
	)
	(segment
		(start 42.291 23.622)
		(end 41.91 24.003)
		(width 0.12065)
		(layer "In3.Cu")
		(net "NFP_CPLD_PRGM_JTAG_TDI")
	)
	(segment
		(start 41.91 24.003)
		(end 38.608 24.003)
		(width 0.12065)
		(layer "In3.Cu")
		(net "NFP_CPLD_PRGM_JTAG_TDI")
	)
	(segment
		(start 23.356011 30.976011)
		(end 23.356011 31.6992)
		(width 0.14732)
		(layer "F.Cu")
		(net "NFP_CPLD_PRGM_JTAG_TCK")
	)
	(segment
		(start 43.236998 11.04199)
		(end 42.736999 10.541991)
		(width 0.13208)
		(layer "F.Cu")
		(net "NFP_CPLD_PRGM_JTAG_TCK")
	)
	(segment
		(start 23.241 29.7561)
		(end 23.241 30.861)
		(width 0.14732)
		(layer "F.Cu")
		(net "NFP_CPLD_PRGM_JTAG_TCK")
	)
	(segment
		(start 23.241 30.861)
		(end 23.356011 30.976011)
		(width 0.14732)
		(layer "F.Cu")
		(net "NFP_CPLD_PRGM_JTAG_TCK")
	)
	(via
		(at 42.736999 10.541991)
		(size 0.4826)
		(drill 0.20574)
		(layers "F.Cu" "B.Cu")
		(net "NFP_CPLD_PRGM_JTAG_TCK")
	)
	(via
		(at 23.241 29.7561)
		(size 0.508)
		(drill 0.25654)
		(layers "F.Cu" "B.Cu")
		(net "NFP_CPLD_PRGM_JTAG_TCK")
	)
	(segment
		(start 35.879659 22.255886)
		(end 35.879659 21.961196)
		(width 0.12065)
		(layer "In3.Cu")
		(net "NFP_CPLD_PRGM_JTAG_TCK")
	)
	(segment
		(start 32.755459 25.405486)
		(end 32.755459 23.535996)
		(width 0.12065)
		(layer "In3.Cu")
		(net "NFP_CPLD_PRGM_JTAG_TCK")
	)
	(segment
		(start 33.528025 23.114)
		(end 33.908975 22.733051)
		(width 0.12065)
		(layer "In3.Cu")
		(net "NFP_CPLD_PRGM_JTAG_TCK")
	)
	(segment
		(start 33.908975 22.733051)
		(end 35.402495 22.733051)
		(width 0.12065)
		(layer "In3.Cu")
		(net "NFP_CPLD_PRGM_JTAG_TCK")
	)
	(segment
		(start 26.289 28.448)
		(end 26.705941 28.031059)
		(width 0.12065)
		(layer "In3.Cu")
		(net "NFP_CPLD_PRGM_JTAG_TCK")
	)
	(segment
		(start 31.760541 26.400404)
		(end 32.755459 25.405486)
		(width 0.12065)
		(layer "In3.Cu")
		(net "NFP_CPLD_PRGM_JTAG_TCK")
	)
	(segment
		(start 35.879659 21.961196)
		(end 36.123855 21.717)
		(width 0.12065)
		(layer "In3.Cu")
		(net "NFP_CPLD_PRGM_JTAG_TCK")
	)
	(segment
		(start 40.763495 16.945229)
		(end 40.904058 16.945229)
		(width 0.12065)
		(layer "In3.Cu")
		(net "NFP_CPLD_PRGM_JTAG_TCK")
	)
	(segment
		(start 26.705941 28.031059)
		(end 31.023941 28.031059)
		(width 0.12065)
		(layer "In3.Cu")
		(net "NFP_CPLD_PRGM_JTAG_TCK")
	)
	(segment
		(start 36.662741 21.961196)
		(end 36.662741 22.014586)
		(width 0.12065)
		(layer "In3.Cu")
		(net "NFP_CPLD_PRGM_JTAG_TCK")
	)
	(segment
		(start 36.662741 22.014586)
		(end 37.010696 22.362541)
		(width 0.12065)
		(layer "In3.Cu")
		(net "NFP_CPLD_PRGM_JTAG_TCK")
	)
	(segment
		(start 40.259 21.717)
		(end 40.259 20.590281)
		(width 0.12065)
		(layer "In3.Cu")
		(net "NFP_CPLD_PRGM_JTAG_TCK")
	)
	(segment
		(start 39.878 22.098)
		(end 40.259 21.717)
		(width 0.12065)
		(layer "In3.Cu")
		(net "NFP_CPLD_PRGM_JTAG_TCK")
	)
	(segment
		(start 24.5491 28.448)
		(end 26.289 28.448)
		(width 0.12065)
		(layer "In3.Cu")
		(net "NFP_CPLD_PRGM_JTAG_TCK")
	)
	(segment
		(start 40.333778 20.515504)
		(end 40.333778 17.374946)
		(width 0.12065)
		(layer "In3.Cu")
		(net "NFP_CPLD_PRGM_JTAG_TCK")
	)
	(segment
		(start 40.904058 16.945229)
		(end 41.148 16.701287)
		(width 0.12065)
		(layer "In3.Cu")
		(net "NFP_CPLD_PRGM_JTAG_TCK")
	)
	(segment
		(start 42.763491 12.945237)
		(end 43.061763 12.945237)
		(width 0.12065)
		(layer "In3.Cu")
		(net "NFP_CPLD_PRGM_JTAG_TCK")
	)
	(segment
		(start 32.755459 23.535996)
		(end 33.177455 23.114)
		(width 0.12065)
		(layer "In3.Cu")
		(net "NFP_CPLD_PRGM_JTAG_TCK")
	)
	(segment
		(start 41.904056 15.945231)
		(end 42.291 15.558287)
		(width 0.12065)
		(layer "In3.Cu")
		(net "NFP_CPLD_PRGM_JTAG_TCK")
	)
	(segment
		(start 31.760541 27.294459)
		(end 31.760541 26.400404)
		(width 0.12065)
		(layer "In3.Cu")
		(net "NFP_CPLD_PRGM_JTAG_TCK")
	)
	(segment
		(start 38.354 22.098)
		(end 39.878 22.098)
		(width 0.12065)
		(layer "In3.Cu")
		(net "NFP_CPLD_PRGM_JTAG_TCK")
	)
	(segment
		(start 37.010696 22.362541)
		(end 38.089459 22.362541)
		(width 0.12065)
		(layer "In3.Cu")
		(net "NFP_CPLD_PRGM_JTAG_TCK")
	)
	(segment
		(start 38.089459 22.362541)
		(end 38.354 22.098)
		(width 0.12065)
		(layer "In3.Cu")
		(net "NFP_CPLD_PRGM_JTAG_TCK")
	)
	(segment
		(start 41.148 16.701287)
		(end 41.148 16.51)
		(width 0.12065)
		(layer "In3.Cu")
		(net "NFP_CPLD_PRGM_JTAG_TCK")
	)
	(segment
		(start 40.259 20.590281)
		(end 40.333778 20.515504)
		(width 0.12065)
		(layer "In3.Cu")
		(net "NFP_CPLD_PRGM_JTAG_TCK")
	)
	(segment
		(start 43.307 11.111992)
		(end 42.736999 10.541991)
		(width 0.12065)
		(layer "In3.Cu")
		(net "NFP_CPLD_PRGM_JTAG_TCK")
	)
	(segment
		(start 35.402495 22.733051)
		(end 35.879659 22.255886)
		(width 0.12065)
		(layer "In3.Cu")
		(net "NFP_CPLD_PRGM_JTAG_TCK")
	)
	(segment
		(start 33.177455 23.114)
		(end 33.528025 23.114)
		(width 0.12065)
		(layer "In3.Cu")
		(net "NFP_CPLD_PRGM_JTAG_TCK")
	)
	(segment
		(start 42.291 13.417728)
		(end 42.763491 12.945237)
		(width 0.12065)
		(layer "In3.Cu")
		(net "NFP_CPLD_PRGM_JTAG_TCK")
	)
	(segment
		(start 41.712769 15.945231)
		(end 41.904056 15.945231)
		(width 0.12065)
		(layer "In3.Cu")
		(net "NFP_CPLD_PRGM_JTAG_TCK")
	)
	(segment
		(start 36.418545 21.717)
		(end 36.662741 21.961196)
		(width 0.12065)
		(layer "In3.Cu")
		(net "NFP_CPLD_PRGM_JTAG_TCK")
	)
	(segment
		(start 40.333778 17.374946)
		(end 40.763495 16.945229)
		(width 0.12065)
		(layer "In3.Cu")
		(net "NFP_CPLD_PRGM_JTAG_TCK")
	)
	(segment
		(start 41.148 16.51)
		(end 41.712769 15.945231)
		(width 0.12065)
		(layer "In3.Cu")
		(net "NFP_CPLD_PRGM_JTAG_TCK")
	)
	(segment
		(start 42.291 15.558287)
		(end 42.291 13.417728)
		(width 0.12065)
		(layer "In3.Cu")
		(net "NFP_CPLD_PRGM_JTAG_TCK")
	)
	(segment
		(start 23.241 29.7561)
		(end 24.5491 28.448)
		(width 0.12065)
		(layer "In3.Cu")
		(net "NFP_CPLD_PRGM_JTAG_TCK")
	)
	(segment
		(start 36.123855 21.717)
		(end 36.418545 21.717)
		(width 0.12065)
		(layer "In3.Cu")
		(net "NFP_CPLD_PRGM_JTAG_TCK")
	)
	(segment
		(start 43.061763 12.945237)
		(end 43.307 12.7)
		(width 0.12065)
		(layer "In3.Cu")
		(net "NFP_CPLD_PRGM_JTAG_TCK")
	)
	(segment
		(start 31.023941 28.031059)
		(end 31.760541 27.294459)
		(width 0.12065)
		(layer "In3.Cu")
		(net "NFP_CPLD_PRGM_JTAG_TCK")
	)
	(segment
		(start 43.307 12.7)
		(end 43.307 11.111992)
		(width 0.12065)
		(layer "In3.Cu")
		(net "NFP_CPLD_PRGM_JTAG_TCK")
	)
	(segment
		(start 36.3601 8.636)
		(end 37.084 8.636)
		(width 0.099314)
		(layer "F.Cu")
		(net "NFP_CLK_REF_P")
	)
	(segment
		(start 44.236996 20.041997)
		(end 43.736997 20.541996)
		(width 0.099314)
		(layer "F.Cu")
		(net "NFP_CLK_REF_P")
	)
	(via
		(at 43.736997 20.541996)
		(size 0.4826)
		(drill 0.20574)
		(layers "F.Cu" "B.Cu")
		(net "NFP_CLK_REF_P")
	)
	(via
		(at 37.084 8.636)
		(size 0.508)
		(drill 0.2667)
		(layers "F.Cu" "B.Cu")
		(net "NFP_CLK_REF_P")
	)
	(segment
		(start 43.736997 20.541996)
		(end 44.236894 20.042099)
		(width 0.099314)
		(layer "B.Cu")
		(net "NFP_CLK_REF_P")
	)
	(segment
		(start 44.236894 20.042099)
		(end 44.236894 20.041997)
		(width 0.099314)
		(layer "B.Cu")
		(net "NFP_CLK_REF_P")
	)
	(segment
		(start 38.113233 8.873109)
		(end 38.04031 8.873109)
		(width 0.095758)
		(layer "In2.Cu")
		(net "NFP_CLK_REF_P")
	)
	(segment
		(start 38.04031 8.873109)
		(end 38.040183 8.872982)
		(width 0.095758)
		(layer "In2.Cu")
		(net "NFP_CLK_REF_P")
	)
	(segment
		(start 43.736997 20.541996)
		(end 44.132094 20.146899)
		(width 0.095758)
		(layer "In2.Cu")
		(net "NFP_CLK_REF_P")
	)
	(segment
		(start 45.346214 13.295706)
		(end 44.987616 12.937109)
		(width 0.095758)
		(layer "In2.Cu")
		(net "NFP_CLK_REF_P")
	)
	(segment
		(start 38.987603 8.937092)
		(end 38.177216 8.937092)
		(width 0.095758)
		(layer "In2.Cu")
		(net "NFP_CLK_REF_P")
	)
	(segment
		(start 46.427898 13.932789)
		(end 45.575118 13.932789)
		(width 0.095758)
		(layer "In2.Cu")
		(net "NFP_CLK_REF_P")
	)
	(segment
		(start 40.34061 9.93709)
		(end 39.341933 8.938412)
		(width 0.095758)
		(layer "In2.Cu")
		(net "NFP_CLK_REF_P")
	)
	(segment
		(start 38.009525 8.872982)
		(end 37.963424 8.826881)
		(width 0.095758)
		(layer "In2.Cu")
		(net "NFP_CLK_REF_P")
	)
	(segment
		(start 40.987624 9.93709)
		(end 40.34061 9.93709)
		(width 0.095758)
		(layer "In2.Cu")
		(net "NFP_CLK_REF_P")
	)
	(segment
		(start 37.963424 8.826881)
		(end 37.951435 8.826881)
		(width 0.095758)
		(layer "In2.Cu")
		(net "NFP_CLK_REF_P")
	)
	(segment
		(start 46.987612 20.146899)
		(end 47.341892 19.79262)
		(width 0.095758)
		(layer "In2.Cu")
		(net "NFP_CLK_REF_P")
	)
	(segment
		(start 41.341904 10.291369)
		(end 40.987624 9.93709)
		(width 0.095758)
		(layer "In2.Cu")
		(net "NFP_CLK_REF_P")
	)
	(segment
		(start 37.951435 8.826881)
		(end 37.274881 8.826881)
		(width 0.096012)
		(layer "In2.Cu")
		(net "NFP_CLK_REF_P")
	)
	(segment
		(start 38.040183 8.872982)
		(end 38.009525 8.872982)
		(width 0.095758)
		(layer "In2.Cu")
		(net "NFP_CLK_REF_P")
	)
	(segment
		(start 37.274881 8.826881)
		(end 37.084 8.636)
		(width 0.096012)
		(layer "In2.Cu")
		(net "NFP_CLK_REF_P")
	)
	(segment
		(start 45.346214 13.703884)
		(end 45.346214 13.295706)
		(width 0.095758)
		(layer "In2.Cu")
		(net "NFP_CLK_REF_P")
	)
	(segment
		(start 44.987616 12.937109)
		(end 44.579438 12.937109)
		(width 0.095758)
		(layer "In2.Cu")
		(net "NFP_CLK_REF_P")
	)
	(segment
		(start 44.346216 12.297512)
		(end 44.341898 12.293194)
		(width 0.095758)
		(layer "In2.Cu")
		(net "NFP_CLK_REF_P")
	)
	(segment
		(start 41.460014 10.937088)
		(end 41.341904 10.818978)
		(width 0.095758)
		(layer "In2.Cu")
		(net "NFP_CLK_REF_P")
	)
	(segment
		(start 47.341892 14.846783)
		(end 46.427898 13.932789)
		(width 0.095758)
		(layer "In2.Cu")
		(net "NFP_CLK_REF_P")
	)
	(segment
		(start 38.988924 8.938412)
		(end 38.987603 8.937092)
		(width 0.095758)
		(layer "In2.Cu")
		(net "NFP_CLK_REF_P")
	)
	(segment
		(start 39.341933 8.938412)
		(end 38.988924 8.938412)
		(width 0.095758)
		(layer "In2.Cu")
		(net "NFP_CLK_REF_P")
	)
	(segment
		(start 44.346216 12.703886)
		(end 44.346216 12.297512)
		(width 0.095758)
		(layer "In2.Cu")
		(net "NFP_CLK_REF_P")
	)
	(segment
		(start 44.341898 11.291367)
		(end 43.987618 10.937088)
		(width 0.095758)
		(layer "In2.Cu")
		(net "NFP_CLK_REF_P")
	)
	(segment
		(start 44.132094 20.146899)
		(end 46.987612 20.146899)
		(width 0.095758)
		(layer "In2.Cu")
		(net "NFP_CLK_REF_P")
	)
	(segment
		(start 44.341898 12.293194)
		(end 44.341898 11.291367)
		(width 0.095758)
		(layer "In2.Cu")
		(net "NFP_CLK_REF_P")
	)
	(segment
		(start 41.341904 10.818978)
		(end 41.341904 10.291369)
		(width 0.095758)
		(layer "In2.Cu")
		(net "NFP_CLK_REF_P")
	)
	(segment
		(start 43.987618 10.937088)
		(end 41.460014 10.937088)
		(width 0.095758)
		(layer "In2.Cu")
		(net "NFP_CLK_REF_P")
	)
	(segment
		(start 47.341892 19.79262)
		(end 47.341892 14.846783)
		(width 0.095758)
		(layer "In2.Cu")
		(net "NFP_CLK_REF_P")
	)
	(segment
		(start 44.579438 12.937109)
		(end 44.346216 12.703886)
		(width 0.095758)
		(layer "In2.Cu")
		(net "NFP_CLK_REF_P")
	)
	(segment
		(start 38.177216 8.937092)
		(end 38.113233 8.873109)
		(width 0.095758)
		(layer "In2.Cu")
		(net "NFP_CLK_REF_P")
	)
	(segment
		(start 45.575118 13.932789)
		(end 45.346214 13.703884)
		(width 0.095758)
		(layer "In2.Cu")
		(net "NFP_CLK_REF_P")
	)
	(segment
		(start 44.236996 19.041999)
		(end 43.736997 19.541998)
		(width 0.099314)
		(layer "F.Cu")
		(net "NFP_CLK_REF_N")
	)
	(segment
		(start 36.3601 9.779)
		(end 37.084 9.779)
		(width 0.099314)
		(layer "F.Cu")
		(net "NFP_CLK_REF_N")
	)
	(via
		(at 37.084 9.779)
		(size 0.508)
		(drill 0.2667)
		(layers "F.Cu" "B.Cu")
		(net "NFP_CLK_REF_N")
	)
	(via
		(at 43.736997 19.541998)
		(size 0.4826)
		(drill 0.20574)
		(layers "F.Cu" "B.Cu")
		(net "NFP_CLK_REF_N")
	)
	(segment
		(start 43.736997 19.541998)
		(end 44.236894 19.042101)
		(width 0.099314)
		(layer "B.Cu")
		(net "NFP_CLK_REF_N")
	)
	(segment
		(start 44.236894 19.042101)
		(end 44.236894 19.041999)
		(width 0.099314)
		(layer "B.Cu")
		(net "NFP_CLK_REF_N")
	)
	(segment
		(start 38.898906 9.151214)
		(end 38.900227 9.152534)
		(width 0.095758)
		(layer "In2.Cu")
		(net "NFP_CLK_REF_N")
	)
	(segment
		(start 40.251913 10.151212)
		(end 40.898928 10.151212)
		(width 0.095758)
		(layer "In2.Cu")
		(net "NFP_CLK_REF_N")
	)
	(segment
		(start 47.12777 14.935479)
		(end 47.12777 19.703923)
		(width 0.095758)
		(layer "In2.Cu")
		(net "NFP_CLK_REF_N")
	)
	(segment
		(start 44.132094 12.386208)
		(end 44.132094 12.792583)
		(width 0.095758)
		(layer "In2.Cu")
		(net "NFP_CLK_REF_N")
	)
	(segment
		(start 37.084 9.779)
		(end 37.084 9.37768)
		(width 0.096012)
		(layer "In2.Cu")
		(net "NFP_CLK_REF_N")
	)
	(segment
		(start 38.024537 9.087231)
		(end 38.08984 9.152534)
		(width 0.095758)
		(layer "In2.Cu")
		(net "NFP_CLK_REF_N")
	)
	(segment
		(start 40.898928 10.151212)
		(end 41.127782 10.380066)
		(width 0.095758)
		(layer "In2.Cu")
		(net "NFP_CLK_REF_N")
	)
	(segment
		(start 43.834812 19.932777)
		(end 43.736997 19.834962)
		(width 0.095758)
		(layer "In2.Cu")
		(net "NFP_CLK_REF_N")
	)
	(segment
		(start 38.486334 9.151214)
		(end 38.898906 9.151214)
		(width 0.095758)
		(layer "In2.Cu")
		(net "NFP_CLK_REF_N")
	)
	(segment
		(start 44.490742 13.151231)
		(end 44.89892 13.151231)
		(width 0.095758)
		(layer "In2.Cu")
		(net "NFP_CLK_REF_N")
	)
	(segment
		(start 44.127776 12.38189)
		(end 44.132094 12.386208)
		(width 0.095758)
		(layer "In2.Cu")
		(net "NFP_CLK_REF_N")
	)
	(segment
		(start 41.127782 10.380066)
		(end 41.127782 10.907674)
		(width 0.095758)
		(layer "In2.Cu")
		(net "NFP_CLK_REF_N")
	)
	(segment
		(start 37.084 9.37768)
		(end 37.374449 9.087231)
		(width 0.096012)
		(layer "In2.Cu")
		(net "NFP_CLK_REF_N")
	)
	(segment
		(start 38.485013 9.152534)
		(end 38.486334 9.151214)
		(width 0.095758)
		(layer "In2.Cu")
		(net "NFP_CLK_REF_N")
	)
	(segment
		(start 41.371317 11.15121)
		(end 43.898922 11.15121)
		(width 0.095758)
		(layer "In2.Cu")
		(net "NFP_CLK_REF_N")
	)
	(segment
		(start 46.898916 19.932777)
		(end 43.834812 19.932777)
		(width 0.095758)
		(layer "In2.Cu")
		(net "NFP_CLK_REF_N")
	)
	(segment
		(start 43.898922 11.15121)
		(end 44.127776 11.380064)
		(width 0.095758)
		(layer "In2.Cu")
		(net "NFP_CLK_REF_N")
	)
	(segment
		(start 45.486422 14.146911)
		(end 46.339201 14.146911)
		(width 0.095758)
		(layer "In2.Cu")
		(net "NFP_CLK_REF_N")
	)
	(segment
		(start 44.132094 12.792583)
		(end 44.490742 13.151231)
		(width 0.095758)
		(layer "In2.Cu")
		(net "NFP_CLK_REF_N")
	)
	(segment
		(start 41.127782 10.907674)
		(end 41.371317 11.15121)
		(width 0.095758)
		(layer "In2.Cu")
		(net "NFP_CLK_REF_N")
	)
	(segment
		(start 38.900227 9.152534)
		(end 39.253236 9.152534)
		(width 0.095758)
		(layer "In2.Cu")
		(net "NFP_CLK_REF_N")
	)
	(segment
		(start 46.339201 14.146911)
		(end 47.12777 14.935479)
		(width 0.095758)
		(layer "In2.Cu")
		(net "NFP_CLK_REF_N")
	)
	(segment
		(start 47.12777 19.703923)
		(end 46.898916 19.932777)
		(width 0.095758)
		(layer "In2.Cu")
		(net "NFP_CLK_REF_N")
	)
	(segment
		(start 44.89892 13.151231)
		(end 45.132092 13.384403)
		(width 0.095758)
		(layer "In2.Cu")
		(net "NFP_CLK_REF_N")
	)
	(segment
		(start 43.736997 19.834962)
		(end 43.736997 19.541998)
		(width 0.095758)
		(layer "In2.Cu")
		(net "NFP_CLK_REF_N")
	)
	(segment
		(start 38.08984 9.152534)
		(end 38.485013 9.152534)
		(width 0.095758)
		(layer "In2.Cu")
		(net "NFP_CLK_REF_N")
	)
	(segment
		(start 44.127776 11.380064)
		(end 44.127776 12.38189)
		(width 0.095758)
		(layer "In2.Cu")
		(net "NFP_CLK_REF_N")
	)
	(segment
		(start 39.253236 9.152534)
		(end 40.251913 10.151212)
		(width 0.095758)
		(layer "In2.Cu")
		(net "NFP_CLK_REF_N")
	)
	(segment
		(start 45.132092 13.792581)
		(end 45.486422 14.146911)
		(width 0.095758)
		(layer "In2.Cu")
		(net "NFP_CLK_REF_N")
	)
	(segment
		(start 37.374449 9.087231)
		(end 37.951435 9.087231)
		(width 0.096012)
		(layer "In2.Cu")
		(net "NFP_CLK_REF_N")
	)
	(segment
		(start 37.951435 9.087231)
		(end 38.024537 9.087231)
		(width 0.095758)
		(layer "In2.Cu")
		(net "NFP_CLK_REF_N")
	)
	(segment
		(start 45.132092 13.384403)
		(end 45.132092 13.792581)
		(width 0.095758)
		(layer "In2.Cu")
		(net "NFP_CLK_REF_N")
	)
	(segment
		(start 24.765 15.494)
		(end 23.876 15.494)
		(width 0.14732)
		(layer "F.Cu")
		(net "NFP_CFG_SPI_FLASH_WP_L")
	)
	(segment
		(start 26.55824 23.9141)
		(end 27.097634 23.9141)
		(width 0.127)
		(layer "F.Cu")
		(net "NFP_CFG_SPI_FLASH_WP_L")
	)
	(segment
		(start 27.231924 24.04839)
		(end 28.245994 24.04839)
		(width 0.127)
		(layer "F.Cu")
		(net "NFP_CFG_SPI_FLASH_WP_L")
	)
	(segment
		(start 27.097634 23.9141)
		(end 27.231924 24.04839)
		(width 0.127)
		(layer "F.Cu")
		(net "NFP_CFG_SPI_FLASH_WP_L")
	)
	(segment
		(start 23.876 15.494)
		(end 23.495 15.113)
		(width 0.14732)
		(layer "F.Cu")
		(net "NFP_CFG_SPI_FLASH_WP_L")
	)
	(segment
		(start 26.1112 24.3332)
		(end 26.55824 23.9141)
		(width 0.127)
		(layer "F.Cu")
		(net "NFP_CFG_SPI_FLASH_WP_L")
	)
	(segment
		(start 23.495 15.113)
		(end 23.495 13.843)
		(width 0.14732)
		(layer "F.Cu")
		(net "NFP_CFG_SPI_FLASH_WP_L")
	)
	(via
		(at 26.1112 24.3332)
		(size 0.4572)
		(drill 0.20574)
		(layers "F.Cu" "B.Cu")
		(net "NFP_CFG_SPI_FLASH_WP_L")
	)
	(via
		(at 24.765 15.494)
		(size 0.508)
		(drill 0.2667)
		(layers "F.Cu" "B.Cu")
		(net "NFP_CFG_SPI_FLASH_WP_L")
	)
	(segment
		(start 23.876 15.494)
		(end 23.495 15.113)
		(width 0.14732)
		(layer "B.Cu")
		(net "NFP_CFG_SPI_FLASH_WP_L")
	)
	(segment
		(start 24.765 15.494)
		(end 23.876 15.494)
		(width 0.14732)
		(layer "B.Cu")
		(net "NFP_CFG_SPI_FLASH_WP_L")
	)
	(segment
		(start 23.495 15.113)
		(end 23.495 14.0081)
		(width 0.14732)
		(layer "B.Cu")
		(net "NFP_CFG_SPI_FLASH_WP_L")
	)
	(segment
		(start 22.9362 24.3332)
		(end 26.1112 24.3332)
		(width 0.12065)
		(layer "In6.Cu")
		(net "NFP_CFG_SPI_FLASH_WP_L")
	)
	(segment
		(start 25.019 15.748)
		(end 25.019 17.819954)
		(width 0.12065)
		(layer "In6.Cu")
		(net "NFP_CFG_SPI_FLASH_WP_L")
	)
	(segment
		(start 24.765 15.494)
		(end 25.019 15.748)
		(width 0.12065)
		(layer "In6.Cu")
		(net "NFP_CFG_SPI_FLASH_WP_L")
	)
	(segment
		(start 22.772954 20.066)
		(end 21.336 20.066)
		(width 0.12065)
		(layer "In6.Cu")
		(net "NFP_CFG_SPI_FLASH_WP_L")
	)
	(segment
		(start 25.019 17.819954)
		(end 22.772954 20.066)
		(width 0.12065)
		(layer "In6.Cu")
		(net "NFP_CFG_SPI_FLASH_WP_L")
	)
	(segment
		(start 20.193 21.209)
		(end 20.193 21.59)
		(width 0.12065)
		(layer "In6.Cu")
		(net "NFP_CFG_SPI_FLASH_WP_L")
	)
	(segment
		(start 21.336 20.066)
		(end 20.193 21.209)
		(width 0.12065)
		(layer "In6.Cu")
		(net "NFP_CFG_SPI_FLASH_WP_L")
	)
	(segment
		(start 20.193 21.59)
		(end 22.9362 24.3332)
		(width 0.12065)
		(layer "In6.Cu")
		(net "NFP_CFG_SPI_FLASH_WP_L")
	)
	(segment
		(start 20.955 14.986)
		(end 21.336 15.367)
		(width 0.14732)
		(layer "F.Cu")
		(net "NFP_CFG_SPI_FLASH_SEL")
	)
	(segment
		(start 20.955 13.843)
		(end 20.955 14.986)
		(width 0.14732)
		(layer "F.Cu")
		(net "NFP_CFG_SPI_FLASH_SEL")
	)
	(segment
		(start 21.082 15.621)
		(end 21.336 15.367)
		(width 0.14732)
		(layer "F.Cu")
		(net "NFP_CFG_SPI_FLASH_SEL")
	)
	(segment
		(start 19.558 15.621)
		(end 21.082 15.621)
		(width 0.14732)
		(layer "F.Cu")
		(net "NFP_CFG_SPI_FLASH_SEL")
	)
	(via
		(at 21.336 15.367)
		(size 0.508)
		(drill 0.254)
		(layers "F.Cu" "B.Cu")
		(net "NFP_CFG_SPI_FLASH_SEL")
	)
	(via
		(at 37.1729 20.193)
		(size 0.4572)
		(drill 0.20574)
		(layers "F.Cu" "B.Cu")
		(net "NFP_CFG_SPI_FLASH_SEL")
	)
	(via
		(at 19.558 15.621)
		(size 0.762)
		(drill 0.381)
		(layers "F.Cu" "B.Cu")
		(net "NFP_CFG_SPI_FLASH_SEL")
	)
	(segment
		(start 21.336 14.0081)
		(end 20.32 14.0081)
		(width 0.14732)
		(layer "B.Cu")
		(net "NFP_CFG_SPI_FLASH_SEL")
	)
	(segment
		(start 21.336 14.0081)
		(end 21.336 15.367)
		(width 0.14732)
		(layer "B.Cu")
		(net "NFP_CFG_SPI_FLASH_SEL")
	)
	(segment
		(start 37.1729 20.193)
		(end 36.703 19.7231)
		(width 0.12065)
		(layer "In3.Cu")
		(net "NFP_CFG_SPI_FLASH_SEL")
	)
	(segment
		(start 37.726214 17.999075)
		(end 36.356925 17.999075)
		(width 0.12065)
		(layer "In3.Cu")
		(net "NFP_CFG_SPI_FLASH_SEL")
	)
	(segment
		(start 33.340675 19.110325)
		(end 32.668566 19.110325)
		(width 0.12065)
		(layer "In3.Cu")
		(net "NFP_CFG_SPI_FLASH_SEL")
	)
	(segment
		(start 22.146946 17.272)
		(end 21.336 16.461054)
		(width 0.12065)
		(layer "In3.Cu")
		(net "NFP_CFG_SPI_FLASH_SEL")
	)
	(segment
		(start 36.840541 18.912459)
		(end 37.64468 18.912459)
		(width 0.12065)
		(layer "In3.Cu")
		(net "NFP_CFG_SPI_FLASH_SEL")
	)
	(segment
		(start 30.10535 18.54835)
		(end 29.21 17.653)
		(width 0.12065)
		(layer "In3.Cu")
		(net "NFP_CFG_SPI_FLASH_SEL")
	)
	(segment
		(start 36.703 19.7231)
		(end 36.703 19.05)
		(width 0.12065)
		(layer "In3.Cu")
		(net "NFP_CFG_SPI_FLASH_SEL")
	)
	(segment
		(start 37.969825 18.587314)
		(end 37.969825 18.242686)
		(width 0.12065)
		(layer "In3.Cu")
		(net "NFP_CFG_SPI_FLASH_SEL")
	)
	(segment
		(start 32.668566 19.110325)
		(end 32.106591 18.54835)
		(width 0.12065)
		(layer "In3.Cu")
		(net "NFP_CFG_SPI_FLASH_SEL")
	)
	(segment
		(start 36.356925 17.999075)
		(end 35.687 18.669)
		(width 0.12065)
		(layer "In3.Cu")
		(net "NFP_CFG_SPI_FLASH_SEL")
	)
	(segment
		(start 32.106591 18.54835)
		(end 30.10535 18.54835)
		(width 0.12065)
		(layer "In3.Cu")
		(net "NFP_CFG_SPI_FLASH_SEL")
	)
	(segment
		(start 23.776254 17.653)
		(end 23.395254 17.272)
		(width 0.12065)
		(layer "In3.Cu")
		(net "NFP_CFG_SPI_FLASH_SEL")
	)
	(segment
		(start 36.703 19.05)
		(end 36.840541 18.912459)
		(width 0.12065)
		(layer "In3.Cu")
		(net "NFP_CFG_SPI_FLASH_SEL")
	)
	(segment
		(start 33.782 18.669)
		(end 33.340675 19.110325)
		(width 0.12065)
		(layer "In3.Cu")
		(net "NFP_CFG_SPI_FLASH_SEL")
	)
	(segment
		(start 35.687 18.669)
		(end 33.782 18.669)
		(width 0.12065)
		(layer "In3.Cu")
		(net "NFP_CFG_SPI_FLASH_SEL")
	)
	(segment
		(start 37.969825 18.242686)
		(end 37.726214 17.999075)
		(width 0.12065)
		(layer "In3.Cu")
		(net "NFP_CFG_SPI_FLASH_SEL")
	)
	(segment
		(start 29.21 17.653)
		(end 23.776254 17.653)
		(width 0.12065)
		(layer "In3.Cu")
		(net "NFP_CFG_SPI_FLASH_SEL")
	)
	(segment
		(start 21.336 16.461054)
		(end 21.336 15.367)
		(width 0.12065)
		(layer "In3.Cu")
		(net "NFP_CFG_SPI_FLASH_SEL")
	)
	(segment
		(start 37.64468 18.912459)
		(end 37.969825 18.587314)
		(width 0.12065)
		(layer "In3.Cu")
		(net "NFP_CFG_SPI_FLASH_SEL")
	)
	(segment
		(start 23.395254 17.272)
		(end 22.146946 17.272)
		(width 0.12065)
		(layer "In3.Cu")
		(net "NFP_CFG_SPI_FLASH_SEL")
	)
	(via
		(at 37.1729 21.082)
		(size 0.4572)
		(drill 0.20574)
		(layers "F.Cu" "B.Cu")
		(net "NFP_CFG_SPI_FLASH_SCK")
	)
	(via
		(at 23.495 9.271)
		(size 0.508)
		(drill 0.25654)
		(layers "F.Cu" "B.Cu")
		(net "NFP_CFG_SPI_FLASH_SCK")
	)
	(segment
		(start 23.495 8.2931)
		(end 23.495 9.271)
		(width 0.14732)
		(layer "B.Cu")
		(net "NFP_CFG_SPI_FLASH_SCK")
	)
	(segment
		(start 22.098 15.494)
		(end 22.606 16.002)
		(width 0.12065)
		(layer "In3.Cu")
		(net "NFP_CFG_SPI_FLASH_SCK")
	)
	(segment
		(start 33.847329 17.894071)
		(end 33.95505 17.78635)
		(width 0.12065)
		(layer "In3.Cu")
		(net "NFP_CFG_SPI_FLASH_SCK")
	)
	(segment
		(start 32.33895 17.78635)
		(end 32.446671 17.894071)
		(width 0.12065)
		(layer "In3.Cu")
		(net "NFP_CFG_SPI_FLASH_SCK")
	)
	(segment
		(start 37.846 17.145)
		(end 37.950775 17.249775)
		(width 0.12065)
		(layer "In3.Cu")
		(net "NFP_CFG_SPI_FLASH_SCK")
	)
	(segment
		(start 29.591 16.002)
		(end 31.37535 17.78635)
		(width 0.12065)
		(layer "In3.Cu")
		(net "NFP_CFG_SPI_FLASH_SCK")
	)
	(segment
		(start 34.798 17.78)
		(end 35.433 17.145)
		(width 0.12065)
		(layer "In3.Cu")
		(net "NFP_CFG_SPI_FLASH_SCK")
	)
	(segment
		(start 34.766072 17.78635)
		(end 34.798 17.78)
		(width 0.12065)
		(layer "In3.Cu")
		(net "NFP_CFG_SPI_FLASH_SCK")
	)
	(segment
		(start 22.01705 11.43635)
		(end 21.72335 11.73005)
		(width 0.12065)
		(layer "In3.Cu")
		(net "NFP_CFG_SPI_FLASH_SCK")
	)
	(segment
		(start 38.321082 17.534255)
		(end 38.321082 17.714316)
		(width 0.12065)
		(layer "In3.Cu")
		(net "NFP_CFG_SPI_FLASH_SCK")
	)
	(segment
		(start 38.208026 20.046874)
		(end 37.1729 21.082)
		(width 0.12065)
		(layer "In3.Cu")
		(net "NFP_CFG_SPI_FLASH_SCK")
	)
	(segment
		(start 35.433 17.145)
		(end 37.846 17.145)
		(width 0.12065)
		(layer "In3.Cu")
		(net "NFP_CFG_SPI_FLASH_SCK")
	)
	(segment
		(start 22.098 13.208)
		(end 22.098 15.494)
		(width 0.12065)
		(layer "In3.Cu")
		(net "NFP_CFG_SPI_FLASH_SCK")
	)
	(segment
		(start 23.495 10.16)
		(end 22.21865 11.43635)
		(width 0.12065)
		(layer "In3.Cu")
		(net "NFP_CFG_SPI_FLASH_SCK")
	)
	(segment
		(start 21.72335 12.14595)
		(end 21.844 12.2666)
		(width 0.12065)
		(layer "In3.Cu")
		(net "NFP_CFG_SPI_FLASH_SCK")
	)
	(segment
		(start 21.844 12.954)
		(end 22.098 13.208)
		(width 0.12065)
		(layer "In3.Cu")
		(net "NFP_CFG_SPI_FLASH_SCK")
	)
	(segment
		(start 37.950775 17.249775)
		(end 38.036602 17.249775)
		(width 0.12065)
		(layer "In3.Cu")
		(net "NFP_CFG_SPI_FLASH_SCK")
	)
	(segment
		(start 38.333782 19.374942)
		(end 38.333782 19.525666)
		(width 0.12065)
		(layer "In3.Cu")
		(net "NFP_CFG_SPI_FLASH_SCK")
	)
	(segment
		(start 38.208026 19.651421)
		(end 38.208026 20.046874)
		(width 0.12065)
		(layer "In3.Cu")
		(net "NFP_CFG_SPI_FLASH_SCK")
	)
	(segment
		(start 33.95505 17.78635)
		(end 34.766072 17.78635)
		(width 0.12065)
		(layer "In3.Cu")
		(net "NFP_CFG_SPI_FLASH_SCK")
	)
	(segment
		(start 32.446671 17.894071)
		(end 33.847329 17.894071)
		(width 0.12065)
		(layer "In3.Cu")
		(net "NFP_CFG_SPI_FLASH_SCK")
	)
	(segment
		(start 38.321082 17.714316)
		(end 38.474777 17.868011)
		(width 0.12065)
		(layer "In3.Cu")
		(net "NFP_CFG_SPI_FLASH_SCK")
	)
	(segment
		(start 38.036602 17.249775)
		(end 38.321082 17.534255)
		(width 0.12065)
		(layer "In3.Cu")
		(net "NFP_CFG_SPI_FLASH_SCK")
	)
	(segment
		(start 22.606 16.002)
		(end 29.591 16.002)
		(width 0.12065)
		(layer "In3.Cu")
		(net "NFP_CFG_SPI_FLASH_SCK")
	)
	(segment
		(start 38.333782 19.525666)
		(end 38.208026 19.651421)
		(width 0.12065)
		(layer "In3.Cu")
		(net "NFP_CFG_SPI_FLASH_SCK")
	)
	(segment
		(start 31.37535 17.78635)
		(end 32.33895 17.78635)
		(width 0.12065)
		(layer "In3.Cu")
		(net "NFP_CFG_SPI_FLASH_SCK")
	)
	(segment
		(start 38.474777 17.868011)
		(end 38.474777 19.233947)
		(width 0.12065)
		(layer "In3.Cu")
		(net "NFP_CFG_SPI_FLASH_SCK")
	)
	(segment
		(start 21.844 12.2666)
		(end 21.844 12.954)
		(width 0.12065)
		(layer "In3.Cu")
		(net "NFP_CFG_SPI_FLASH_SCK")
	)
	(segment
		(start 38.474777 19.233947)
		(end 38.333782 19.374942)
		(width 0.12065)
		(layer "In3.Cu")
		(net "NFP_CFG_SPI_FLASH_SCK")
	)
	(segment
		(start 22.21865 11.43635)
		(end 22.01705 11.43635)
		(width 0.12065)
		(layer "In3.Cu")
		(net "NFP_CFG_SPI_FLASH_SCK")
	)
	(segment
		(start 21.72335 11.73005)
		(end 21.72335 12.14595)
		(width 0.12065)
		(layer "In3.Cu")
		(net "NFP_CFG_SPI_FLASH_SCK")
	)
	(segment
		(start 23.495 9.271)
		(end 23.495 10.16)
		(width 0.12065)
		(layer "In3.Cu")
		(net "NFP_CFG_SPI_FLASH_SCK")
	)
	(via
		(at 24.765 9.271)
		(size 0.508)
		(drill 0.25654)
		(layers "F.Cu" "B.Cu")
		(net "NFP_CFG_SPI_FLASH_MOSI")
	)
	(via
		(at 37.1729 19.304)
		(size 0.4572)
		(drill 0.20574)
		(layers "F.Cu" "B.Cu")
		(net "NFP_CFG_SPI_FLASH_MOSI")
	)
	(segment
		(start 24.765 8.2931)
		(end 24.765 9.271)
		(width 0.14732)
		(layer "B.Cu")
		(net "NFP_CFG_SPI_FLASH_MOSI")
	)
	(segment
		(start 21.2217 12.353747)
		(end 21.336 12.468047)
		(width 0.12065)
		(layer "In3.Cu")
		(net "NFP_CFG_SPI_FLASH_MOSI")
	)
	(segment
		(start 32.903846 18.288)
		(end 32.964171 18.227675)
		(width 0.12065)
		(layer "In3.Cu")
		(net "NFP_CFG_SPI_FLASH_MOSI")
	)
	(segment
		(start 21.777325 15.046325)
		(end 21.777325 15.654071)
		(width 0.12065)
		(layer "In3.Cu")
		(net "NFP_CFG_SPI_FLASH_MOSI")
	)
	(segment
		(start 35.433 18.288)
		(end 35.969575 17.751425)
		(width 0.12065)
		(layer "In3.Cu")
		(net "NFP_CFG_SPI_FLASH_MOSI")
	)
	(segment
		(start 30.353 18.288)
		(end 32.903846 18.288)
		(width 0.12065)
		(layer "In3.Cu")
		(net "NFP_CFG_SPI_FLASH_MOSI")
	)
	(segment
		(start 37.828804 17.751425)
		(end 38.227 18.149621)
		(width 0.12065)
		(layer "In3.Cu")
		(net "NFP_CFG_SPI_FLASH_MOSI")
	)
	(segment
		(start 23.622 16.891)
		(end 24.003 17.272)
		(width 0.12065)
		(layer "In3.Cu")
		(net "NFP_CFG_SPI_FLASH_MOSI")
	)
	(segment
		(start 33.390154 18.288)
		(end 35.433 18.288)
		(width 0.12065)
		(layer "In3.Cu")
		(net "NFP_CFG_SPI_FLASH_MOSI")
	)
	(segment
		(start 23.241 8.763)
		(end 22.86 9.144)
		(width 0.12065)
		(layer "In3.Cu")
		(net "NFP_CFG_SPI_FLASH_MOSI")
	)
	(segment
		(start 33.329829 18.227675)
		(end 33.390154 18.288)
		(width 0.12065)
		(layer "In3.Cu")
		(net "NFP_CFG_SPI_FLASH_MOSI")
	)
	(segment
		(start 21.2217 11.522253)
		(end 21.2217 12.353747)
		(width 0.12065)
		(layer "In3.Cu")
		(net "NFP_CFG_SPI_FLASH_MOSI")
	)
	(segment
		(start 38.227 18.772276)
		(end 37.832132 19.167145)
		(width 0.12065)
		(layer "In3.Cu")
		(net "NFP_CFG_SPI_FLASH_MOSI")
	)
	(segment
		(start 37.711482 19.304)
		(end 37.1729 19.304)
		(width 0.12065)
		(layer "In3.Cu")
		(net "NFP_CFG_SPI_FLASH_MOSI")
	)
	(segment
		(start 22.86 9.144)
		(end 22.86 9.906)
		(width 0.12065)
		(layer "In3.Cu")
		(net "NFP_CFG_SPI_FLASH_MOSI")
	)
	(segment
		(start 35.969575 17.751425)
		(end 37.828804 17.751425)
		(width 0.12065)
		(layer "In3.Cu")
		(net "NFP_CFG_SPI_FLASH_MOSI")
	)
	(segment
		(start 21.777325 15.654071)
		(end 23.014254 16.891)
		(width 0.12065)
		(layer "In3.Cu")
		(net "NFP_CFG_SPI_FLASH_MOSI")
	)
	(segment
		(start 24.257 8.763)
		(end 23.241 8.763)
		(width 0.12065)
		(layer "In3.Cu")
		(net "NFP_CFG_SPI_FLASH_MOSI")
	)
	(segment
		(start 29.337 17.272)
		(end 30.353 18.288)
		(width 0.12065)
		(layer "In3.Cu")
		(net "NFP_CFG_SPI_FLASH_MOSI")
	)
	(segment
		(start 21.336 12.468047)
		(end 21.336 14.605)
		(width 0.12065)
		(layer "In3.Cu")
		(net "NFP_CFG_SPI_FLASH_MOSI")
	)
	(segment
		(start 24.765 9.271)
		(end 24.257 8.763)
		(width 0.12065)
		(layer "In3.Cu")
		(net "NFP_CFG_SPI_FLASH_MOSI")
	)
	(segment
		(start 21.336 14.605)
		(end 21.777325 15.046325)
		(width 0.12065)
		(layer "In3.Cu")
		(net "NFP_CFG_SPI_FLASH_MOSI")
	)
	(segment
		(start 37.832132 19.18335)
		(end 37.711482 19.304)
		(width 0.12065)
		(layer "In3.Cu")
		(net "NFP_CFG_SPI_FLASH_MOSI")
	)
	(segment
		(start 21.8313 10.9347)
		(end 21.809253 10.9347)
		(width 0.12065)
		(layer "In3.Cu")
		(net "NFP_CFG_SPI_FLASH_MOSI")
	)
	(segment
		(start 21.809253 10.9347)
		(end 21.2217 11.522253)
		(width 0.12065)
		(layer "In3.Cu")
		(net "NFP_CFG_SPI_FLASH_MOSI")
	)
	(segment
		(start 32.964171 18.227675)
		(end 33.329829 18.227675)
		(width 0.12065)
		(layer "In3.Cu")
		(net "NFP_CFG_SPI_FLASH_MOSI")
	)
	(segment
		(start 22.86 9.906)
		(end 21.8313 10.9347)
		(width 0.12065)
		(layer "In3.Cu")
		(net "NFP_CFG_SPI_FLASH_MOSI")
	)
	(segment
		(start 24.003 17.272)
		(end 29.337 17.272)
		(width 0.12065)
		(layer "In3.Cu")
		(net "NFP_CFG_SPI_FLASH_MOSI")
	)
	(segment
		(start 37.832132 19.167145)
		(end 37.832132 19.18335)
		(width 0.12065)
		(layer "In3.Cu")
		(net "NFP_CFG_SPI_FLASH_MOSI")
	)
	(segment
		(start 38.227 18.149621)
		(end 38.227 18.772276)
		(width 0.12065)
		(layer "In3.Cu")
		(net "NFP_CFG_SPI_FLASH_MOSI")
	)
	(segment
		(start 23.014254 16.891)
		(end 23.622 16.891)
		(width 0.12065)
		(layer "In3.Cu")
		(net "NFP_CFG_SPI_FLASH_MOSI")
	)
	(segment
		(start 22.606 15.367)
		(end 22.225 14.986)
		(width 0.14732)
		(layer "F.Cu")
		(net "NFP_CFG_SPI_FLASH_MISO")
	)
	(segment
		(start 22.225 14.986)
		(end 22.225 13.843)
		(width 0.14732)
		(layer "F.Cu")
		(net "NFP_CFG_SPI_FLASH_MISO")
	)
	(segment
		(start 41.237002 17.042003)
		(end 40.737003 16.542004)
		(width 0.13208)
		(layer "F.Cu")
		(net "NFP_CFG_SPI_FLASH_MISO")
	)
	(via
		(at 40.737003 16.542004)
		(size 0.4826)
		(drill 0.20574)
		(layers "F.Cu" "B.Cu")
		(net "NFP_CFG_SPI_FLASH_MISO")
	)
	(via
		(at 22.606 15.367)
		(size 0.508)
		(drill 0.2667)
		(layers "F.Cu" "B.Cu")
		(net "NFP_CFG_SPI_FLASH_MISO")
	)
	(segment
		(start 22.606 15.367)
		(end 22.606 14.732)
		(width 0.14732)
		(layer "B.Cu")
		(net "NFP_CFG_SPI_FLASH_MISO")
	)
	(segment
		(start 22.352 14.478)
		(end 22.352 14.0081)
		(width 0.14732)
		(layer "B.Cu")
		(net "NFP_CFG_SPI_FLASH_MISO")
	)
	(segment
		(start 22.606 14.732)
		(end 22.352 14.478)
		(width 0.14732)
		(layer "B.Cu")
		(net "NFP_CFG_SPI_FLASH_MISO")
	)
	(segment
		(start 36.515675 14.914829)
		(end 36.774171 15.173325)
		(width 0.12065)
		(layer "In3.Cu")
		(net "NFP_CFG_SPI_FLASH_MISO")
	)
	(segment
		(start 37.137213 15.306675)
		(end 37.139829 15.306675)
		(width 0.12065)
		(layer "In3.Cu")
		(net "NFP_CFG_SPI_FLASH_MISO")
	)
	(segment
		(start 40.14023 15.945231)
		(end 40.737003 16.542004)
		(width 0.12065)
		(layer "In3.Cu")
		(net "NFP_CFG_SPI_FLASH_MISO")
	)
	(segment
		(start 37.139829 15.306675)
		(end 37.398325 15.565171)
		(width 0.12065)
		(layer "In3.Cu")
		(net "NFP_CFG_SPI_FLASH_MISO")
	)
	(segment
		(start 22.606 15.367)
		(end 23.241 14.732)
		(width 0.12065)
		(layer "In3.Cu")
		(net "NFP_CFG_SPI_FLASH_MISO")
	)
	(segment
		(start 28.575 14.732)
		(end 31.623 11.684)
		(width 0.12065)
		(layer "In3.Cu")
		(net "NFP_CFG_SPI_FLASH_MISO")
	)
	(segment
		(start 37.398325 15.565171)
		(end 37.398325 15.567787)
		(width 0.12065)
		(layer "In3.Cu")
		(net "NFP_CFG_SPI_FLASH_MISO")
	)
	(segment
		(start 37.398325 15.567787)
		(end 37.775769 15.945231)
		(width 0.12065)
		(layer "In3.Cu")
		(net "NFP_CFG_SPI_FLASH_MISO")
	)
	(segment
		(start 37.775769 15.945231)
		(end 40.14023 15.945231)
		(width 0.12065)
		(layer "In3.Cu")
		(net "NFP_CFG_SPI_FLASH_MISO")
	)
	(segment
		(start 31.623 11.684)
		(end 34.417 11.684)
		(width 0.12065)
		(layer "In3.Cu")
		(net "NFP_CFG_SPI_FLASH_MISO")
	)
	(segment
		(start 37.003863 15.173325)
		(end 37.137213 15.306675)
		(width 0.12065)
		(layer "In3.Cu")
		(net "NFP_CFG_SPI_FLASH_MISO")
	)
	(segment
		(start 36.515675 13.782675)
		(end 36.515675 14.914829)
		(width 0.12065)
		(layer "In3.Cu")
		(net "NFP_CFG_SPI_FLASH_MISO")
	)
	(segment
		(start 34.417 11.684)
		(end 36.515675 13.782675)
		(width 0.12065)
		(layer "In3.Cu")
		(net "NFP_CFG_SPI_FLASH_MISO")
	)
	(segment
		(start 23.241 14.732)
		(end 28.575 14.732)
		(width 0.12065)
		(layer "In3.Cu")
		(net "NFP_CFG_SPI_FLASH_MISO")
	)
	(segment
		(start 36.774171 15.173325)
		(end 37.003863 15.173325)
		(width 0.12065)
		(layer "In3.Cu")
		(net "NFP_CFG_SPI_FLASH_MISO")
	)
	(segment
		(start 29.48399 24.04839)
		(end 29.8958 24.4602)
		(width 0.14732)
		(layer "F.Cu")
		(net "NFP_CFG_SPI_FLASH_HOLD_L")
	)
	(segment
		(start 29.245992 24.04839)
		(end 29.48399 24.04839)
		(width 0.14732)
		(layer "F.Cu")
		(net "NFP_CFG_SPI_FLASH_HOLD_L")
	)
	(via
		(at 29.8958 24.4602)
		(size 0.4572)
		(drill 0.20574)
		(layers "F.Cu" "B.Cu")
		(net "NFP_CFG_SPI_FLASH_HOLD_L")
	)
	(via
		(at 24.13 44.7675)
		(size 0.508)
		(drill 0.25654)
		(layers "F.Cu" "B.Cu")
		(net "NFP_CFG_SPI_FLASH_HOLD_L")
	)
	(via
		(at 40.894 44.831)
		(size 0.508)
		(drill 0.25654)
		(layers "F.Cu" "B.Cu")
		(net "NFP_CFG_SPI_FLASH_HOLD_L")
	)
	(via
		(at 22.225 9.271)
		(size 0.508)
		(drill 0.25654)
		(layers "F.Cu" "B.Cu")
		(net "NFP_CFG_SPI_FLASH_HOLD_L")
	)
	(segment
		(start 22.225 8.5471)
		(end 22.225 9.271)
		(width 0.14732)
		(layer "B.Cu")
		(net "NFP_CFG_SPI_FLASH_HOLD_L")
	)
	(segment
		(start 31.551829 45.278675)
		(end 31.186171 45.278675)
		(width 0.12065)
		(layer "In6.Cu")
		(net "NFP_CFG_SPI_FLASH_HOLD_L")
	)
	(segment
		(start 27.498675 45.204304)
		(end 27.498675 44.972046)
		(width 0.12065)
		(layer "In6.Cu")
		(net "NFP_CFG_SPI_FLASH_HOLD_L")
	)
	(segment
		(start 37.266829 46.675675)
		(end 35.814 46.675675)
		(width 0.12065)
		(layer "In6.Cu")
		(net "NFP_CFG_SPI_FLASH_HOLD_L")
	)
	(segment
		(start 25.012015 43.640375)
		(end 24.463375 44.189015)
		(width 0.12065)
		(layer "In6.Cu")
		(net "NFP_CFG_SPI_FLASH_HOLD_L")
	)
	(segment
		(start 41.335325 46.918804)
		(end 41.076804 47.177325)
		(width 0.12065)
		(layer "In6.Cu")
		(net "NFP_CFG_SPI_FLASH_HOLD_L")
	)
	(segment
		(start 34.71733 46.083931)
		(end 34.331173 45.697775)
		(width 0.12065)
		(layer "In6.Cu")
		(net "NFP_CFG_SPI_FLASH_HOLD_L")
	)
	(segment
		(start 35.814 46.675675)
		(end 35.222256 46.083931)
		(width 0.12065)
		(layer "In6.Cu")
		(net "NFP_CFG_SPI_FLASH_HOLD_L")
	)
	(segment
		(start 38.149479 47.558325)
		(end 37.266829 46.675675)
		(width 0.12065)
		(layer "In6.Cu")
		(net "NFP_CFG_SPI_FLASH_HOLD_L")
	)
	(segment
		(start 27.757196 45.462825)
		(end 27.498675 45.204304)
		(width 0.12065)
		(layer "In6.Cu")
		(net "NFP_CFG_SPI_FLASH_HOLD_L")
	)
	(segment
		(start 24.463375 44.189015)
		(end 24.463375 44.434125)
		(width 0.12065)
		(layer "In6.Cu")
		(net "NFP_CFG_SPI_FLASH_HOLD_L")
	)
	(segment
		(start 29.591229 45.767625)
		(end 29.286429 45.462825)
		(width 0.12065)
		(layer "In6.Cu")
		(net "NFP_CFG_SPI_FLASH_HOLD_L")
	)
	(segment
		(start 34.331173 45.697775)
		(end 31.970929 45.697775)
		(width 0.12065)
		(layer "In6.Cu")
		(net "NFP_CFG_SPI_FLASH_HOLD_L")
	)
	(segment
		(start 35.222256 46.083931)
		(end 34.71733 46.083931)
		(width 0.12065)
		(layer "In6.Cu")
		(net "NFP_CFG_SPI_FLASH_HOLD_L")
	)
	(segment
		(start 29.286429 45.462825)
		(end 27.757196 45.462825)
		(width 0.12065)
		(layer "In6.Cu")
		(net "NFP_CFG_SPI_FLASH_HOLD_L")
	)
	(segment
		(start 40.894 44.831)
		(end 41.335325 45.272325)
		(width 0.12065)
		(layer "In6.Cu")
		(net "NFP_CFG_SPI_FLASH_HOLD_L")
	)
	(segment
		(start 41.335325 45.272325)
		(end 41.335325 46.918804)
		(width 0.12065)
		(layer "In6.Cu")
		(net "NFP_CFG_SPI_FLASH_HOLD_L")
	)
	(segment
		(start 27.498675 44.972046)
		(end 26.167004 43.640375)
		(width 0.12065)
		(layer "In6.Cu")
		(net "NFP_CFG_SPI_FLASH_HOLD_L")
	)
	(segment
		(start 30.697221 45.767625)
		(end 29.591229 45.767625)
		(width 0.12065)
		(layer "In6.Cu")
		(net "NFP_CFG_SPI_FLASH_HOLD_L")
	)
	(segment
		(start 31.186171 45.278675)
		(end 30.697221 45.767625)
		(width 0.12065)
		(layer "In6.Cu")
		(net "NFP_CFG_SPI_FLASH_HOLD_L")
	)
	(segment
		(start 39.638275 47.177325)
		(end 39.257275 47.558325)
		(width 0.12065)
		(layer "In6.Cu")
		(net "NFP_CFG_SPI_FLASH_HOLD_L")
	)
	(segment
		(start 41.076804 47.177325)
		(end 39.638275 47.177325)
		(width 0.12065)
		(layer "In6.Cu")
		(net "NFP_CFG_SPI_FLASH_HOLD_L")
	)
	(segment
		(start 31.970929 45.697775)
		(end 31.551829 45.278675)
		(width 0.12065)
		(layer "In6.Cu")
		(net "NFP_CFG_SPI_FLASH_HOLD_L")
	)
	(segment
		(start 24.463375 44.434125)
		(end 24.13 44.7675)
		(width 0.12065)
		(layer "In6.Cu")
		(net "NFP_CFG_SPI_FLASH_HOLD_L")
	)
	(segment
		(start 26.167004 43.640375)
		(end 25.012015 43.640375)
		(width 0.12065)
		(layer "In6.Cu")
		(net "NFP_CFG_SPI_FLASH_HOLD_L")
	)
	(segment
		(start 39.257275 47.558325)
		(end 38.149479 47.558325)
		(width 0.12065)
		(layer "In6.Cu")
		(net "NFP_CFG_SPI_FLASH_HOLD_L")
	)
	(segment
		(start 23.495 11.938)
		(end 22.225 10.668)
		(width 0.12065)
		(layer "In7.Cu")
		(net "NFP_CFG_SPI_FLASH_HOLD_L")
	)
	(segment
		(start 29.845 29.570655)
		(end 29.845 26.289)
		(width 0.12065)
		(layer "In7.Cu")
		(net "NFP_CFG_SPI_FLASH_HOLD_L")
	)
	(segment
		(start 26.736675 36.774171)
		(end 26.863675 36.647171)
		(width 0.12065)
		(layer "In7.Cu")
		(net "NFP_CFG_SPI_FLASH_HOLD_L")
	)
	(segment
		(start 25.146 12.319)
		(end 24.638 12.827)
		(width 0.12065)
		(layer "In7.Cu")
		(net "NFP_CFG_SPI_FLASH_HOLD_L")
	)
	(segment
		(start 25.781 12.319)
		(end 25.146 12.319)
		(width 0.12065)
		(layer "In7.Cu")
		(net "NFP_CFG_SPI_FLASH_HOLD_L")
	)
	(segment
		(start 24.003 44.6405)
		(end 24.003 40.833675)
		(width 0.12065)
		(layer "In7.Cu")
		(net "NFP_CFG_SPI_FLASH_HOLD_L")
	)
	(segment
		(start 26.863675 37.973)
		(end 26.863675 37.266829)
		(width 0.12065)
		(layer "In7.Cu")
		(net "NFP_CFG_SPI_FLASH_HOLD_L")
	)
	(segment
		(start 24.13 44.7675)
		(end 24.003 44.6405)
		(width 0.12065)
		(layer "In7.Cu")
		(net "NFP_CFG_SPI_FLASH_HOLD_L")
	)
	(segment
		(start 29.855541 21.325459)
		(end 29.855541 20.945196)
		(width 0.12065)
		(layer "In7.Cu")
		(net "NFP_CFG_SPI_FLASH_HOLD_L")
	)
	(segment
		(start 29.072459 20.055484)
		(end 26.543076 17.526102)
		(width 0.12065)
		(layer "In7.Cu")
		(net "NFP_CFG_SPI_FLASH_HOLD_L")
	)
	(segment
		(start 26.543076 13.081076)
		(end 25.781 12.319)
		(width 0.12065)
		(layer "In7.Cu")
		(net "NFP_CFG_SPI_FLASH_HOLD_L")
	)
	(segment
		(start 28.762325 31.054675)
		(end 29.834459 29.982541)
		(width 0.12065)
		(layer "In7.Cu")
		(net "NFP_CFG_SPI_FLASH_HOLD_L")
	)
	(segment
		(start 29.072459 20.431404)
		(end 29.072459 20.055484)
		(width 0.12065)
		(layer "In7.Cu")
		(net "NFP_CFG_SPI_FLASH_HOLD_L")
	)
	(segment
		(start 29.845 26.289)
		(end 29.464 25.908)
		(width 0.12065)
		(layer "In7.Cu")
		(net "NFP_CFG_SPI_FLASH_HOLD_L")
	)
	(segment
		(start 29.5402 24.4602)
		(end 29.21 24.13)
		(width 0.12065)
		(layer "In7.Cu")
		(net "NFP_CFG_SPI_FLASH_HOLD_L")
	)
	(segment
		(start 29.834459 29.982541)
		(end 29.834459 29.581196)
		(width 0.12065)
		(layer "In7.Cu")
		(net "NFP_CFG_SPI_FLASH_HOLD_L")
	)
	(segment
		(start 29.21 24.13)
		(end 29.21 21.971)
		(width 0.12065)
		(layer "In7.Cu")
		(net "NFP_CFG_SPI_FLASH_HOLD_L")
	)
	(segment
		(start 26.863675 33.588325)
		(end 28.762325 31.689675)
		(width 0.12065)
		(layer "In7.Cu")
		(net "NFP_CFG_SPI_FLASH_HOLD_L")
	)
	(segment
		(start 29.571086 20.660741)
		(end 29.301796 20.660741)
		(width 0.12065)
		(layer "In7.Cu")
		(net "NFP_CFG_SPI_FLASH_HOLD_L")
	)
	(segment
		(start 29.834459 29.581196)
		(end 29.845 29.570655)
		(width 0.12065)
		(layer "In7.Cu")
		(net "NFP_CFG_SPI_FLASH_HOLD_L")
	)
	(segment
		(start 28.762325 31.689675)
		(end 28.762325 31.054675)
		(width 0.12065)
		(layer "In7.Cu")
		(net "NFP_CFG_SPI_FLASH_HOLD_L")
	)
	(segment
		(start 29.855541 20.945196)
		(end 29.571086 20.660741)
		(width 0.12065)
		(layer "In7.Cu")
		(net "NFP_CFG_SPI_FLASH_HOLD_L")
	)
	(segment
		(start 29.8958 24.5872)
		(end 29.8958 24.4602)
		(width 0.12065)
		(layer "In7.Cu")
		(net "NFP_CFG_SPI_FLASH_HOLD_L")
	)
	(segment
		(start 24.13 12.827)
		(end 23.495 12.192)
		(width 0.12065)
		(layer "In7.Cu")
		(net "NFP_CFG_SPI_FLASH_HOLD_L")
	)
	(segment
		(start 26.543076 17.526102)
		(end 26.543076 13.081076)
		(width 0.12065)
		(layer "In7.Cu")
		(net "NFP_CFG_SPI_FLASH_HOLD_L")
	)
	(segment
		(start 29.301796 20.660741)
		(end 29.072459 20.431404)
		(width 0.12065)
		(layer "In7.Cu")
		(net "NFP_CFG_SPI_FLASH_HOLD_L")
	)
	(segment
		(start 29.8958 24.4602)
		(end 29.5402 24.4602)
		(width 0.12065)
		(layer "In7.Cu")
		(net "NFP_CFG_SPI_FLASH_HOLD_L")
	)
	(segment
		(start 29.464 25.019)
		(end 29.8958 24.5872)
		(width 0.12065)
		(layer "In7.Cu")
		(net "NFP_CFG_SPI_FLASH_HOLD_L")
	)
	(segment
		(start 29.21 21.971)
		(end 29.855541 21.325459)
		(width 0.12065)
		(layer "In7.Cu")
		(net "NFP_CFG_SPI_FLASH_HOLD_L")
	)
	(segment
		(start 22.225 10.668)
		(end 22.225 9.271)
		(width 0.12065)
		(layer "In7.Cu")
		(net "NFP_CFG_SPI_FLASH_HOLD_L")
	)
	(segment
		(start 26.736675 37.139829)
		(end 26.736675 36.774171)
		(width 0.12065)
		(layer "In7.Cu")
		(net "NFP_CFG_SPI_FLASH_HOLD_L")
	)
	(segment
		(start 26.863675 37.266829)
		(end 26.736675 37.139829)
		(width 0.12065)
		(layer "In7.Cu")
		(net "NFP_CFG_SPI_FLASH_HOLD_L")
	)
	(segment
		(start 24.638 12.827)
		(end 24.13 12.827)
		(width 0.12065)
		(layer "In7.Cu")
		(net "NFP_CFG_SPI_FLASH_HOLD_L")
	)
	(segment
		(start 24.003 40.833675)
		(end 26.863675 37.973)
		(width 0.12065)
		(layer "In7.Cu")
		(net "NFP_CFG_SPI_FLASH_HOLD_L")
	)
	(segment
		(start 23.495 12.192)
		(end 23.495 11.938)
		(width 0.12065)
		(layer "In7.Cu")
		(net "NFP_CFG_SPI_FLASH_HOLD_L")
	)
	(segment
		(start 26.863675 36.647171)
		(end 26.863675 33.588325)
		(width 0.12065)
		(layer "In7.Cu")
		(net "NFP_CFG_SPI_FLASH_HOLD_L")
	)
	(segment
		(start 29.464 25.908)
		(end 29.464 25.019)
		(width 0.12065)
		(layer "In7.Cu")
		(net "NFP_CFG_SPI_FLASH_HOLD_L")
	)
	(segment
		(start 18.923 22.606)
		(end 18.923 25.25268)
		(width 0.14732)
		(layer "F.Cu")
		(net "NFP_ARM_SPI_FLASH_SEL")
	)
	(segment
		(start 18.669 22.352)
		(end 18.923 22.606)
		(width 0.14732)
		(layer "F.Cu")
		(net "NFP_ARM_SPI_FLASH_SEL")
	)
	(segment
		(start 19.939 25.4)
		(end 20.2438 25.7048)
		(width 0.14732)
		(layer "F.Cu")
		(net "NFP_ARM_SPI_FLASH_SEL")
	)
	(segment
		(start 20.2438 26.7208)
		(end 20.701 27.178)
		(width 0.14732)
		(layer "F.Cu")
		(net "NFP_ARM_SPI_FLASH_SEL")
	)
	(segment
		(start 20.2438 26.1239)
		(end 20.2438 26.7208)
		(width 0.14732)
		(layer "F.Cu")
		(net "NFP_ARM_SPI_FLASH_SEL")
	)
	(segment
		(start 20.2438 25.7048)
		(end 20.2438 26.1239)
		(width 0.14732)
		(layer "F.Cu")
		(net "NFP_ARM_SPI_FLASH_SEL")
	)
	(segment
		(start 18.923 25.25268)
		(end 19.07032 25.4)
		(width 0.14732)
		(layer "F.Cu")
		(net "NFP_ARM_SPI_FLASH_SEL")
	)
	(segment
		(start 20.701 27.178)
		(end 20.701 27.7241)
		(width 0.14732)
		(layer "F.Cu")
		(net "NFP_ARM_SPI_FLASH_SEL")
	)
	(segment
		(start 19.07032 25.4)
		(end 19.939 25.4)
		(width 0.14732)
		(layer "F.Cu")
		(net "NFP_ARM_SPI_FLASH_SEL")
	)
	(segment
		(start 18.161 22.352)
		(end 18.669 22.352)
		(width 0.14732)
		(layer "F.Cu")
		(net "NFP_ARM_SPI_FLASH_SEL")
	)
	(via
		(at 20.701 27.7241)
		(size 0.508)
		(drill 0.25654)
		(layers "F.Cu" "B.Cu")
		(net "NFP_ARM_SPI_FLASH_SEL")
	)
	(via
		(at 18.161 22.352)
		(size 0.762)
		(drill 0.381)
		(layers "F.Cu" "B.Cu")
		(net "NFP_ARM_SPI_FLASH_SEL")
	)
	(via
		(at 20.701 21.336)
		(size 0.508)
		(drill 0.254)
		(layers "F.Cu" "B.Cu")
		(net "NFP_ARM_SPI_FLASH_SEL")
	)
	(via
		(at 38.737007 16.542004)
		(size 0.4826)
		(drill 0.20574)
		(layers "F.Cu" "B.Cu")
		(net "NFP_ARM_SPI_FLASH_SEL")
	)
	(segment
		(start 21.336 22.86)
		(end 20.701 22.225)
		(width 0.14732)
		(layer "B.Cu")
		(net "NFP_ARM_SPI_FLASH_SEL")
	)
	(segment
		(start 20.701 19.685)
		(end 20.701 21.336)
		(width 0.14732)
		(layer "B.Cu")
		(net "NFP_ARM_SPI_FLASH_SEL")
	)
	(segment
		(start 21.336 27.559)
		(end 21.336 22.86)
		(width 0.14732)
		(layer "B.Cu")
		(net "NFP_ARM_SPI_FLASH_SEL")
	)
	(segment
		(start 20.701 27.7241)
		(end 20.7391 27.686)
		(width 0.14732)
		(layer "B.Cu")
		(net "NFP_ARM_SPI_FLASH_SEL")
	)
	(segment
		(start 21.209 27.686)
		(end 21.336 27.559)
		(width 0.14732)
		(layer "B.Cu")
		(net "NFP_ARM_SPI_FLASH_SEL")
	)
	(segment
		(start 20.701 22.225)
		(end 20.701 21.336)
		(width 0.14732)
		(layer "B.Cu")
		(net "NFP_ARM_SPI_FLASH_SEL")
	)
	(segment
		(start 20.701 19.685)
		(end 20.701 17.3101)
		(width 0.14732)
		(layer "B.Cu")
		(net "NFP_ARM_SPI_FLASH_SEL")
	)
	(segment
		(start 20.7391 27.686)
		(end 21.209 27.686)
		(width 0.14732)
		(layer "B.Cu")
		(net "NFP_ARM_SPI_FLASH_SEL")
	)
	(segment
		(start 35.535286 19.679793)
		(end 35.540493 19.685)
		(width 0.12065)
		(layer "In3.Cu")
		(net "NFP_ARM_SPI_FLASH_SEL")
	)
	(segment
		(start 28.575 19.05)
		(end 31.877 19.05)
		(width 0.12065)
		(layer "In3.Cu")
		(net "NFP_ARM_SPI_FLASH_SEL")
	)
	(segment
		(start 38.767004 16.542004)
		(end 38.737007 16.542004)
		(width 0.12065)
		(layer "In3.Cu")
		(net "NFP_ARM_SPI_FLASH_SEL")
	)
	(segment
		(start 22.87999 17.633036)
		(end 23.915954 18.669)
		(width 0.12065)
		(layer "In3.Cu")
		(net "NFP_ARM_SPI_FLASH_SEL")
	)
	(segment
		(start 35.540493 19.685)
		(end 35.813975 19.685)
		(width 0.12065)
		(layer "In3.Cu")
		(net "NFP_ARM_SPI_FLASH_SEL")
	)
	(segment
		(start 37.708459 21.473541)
		(end 38.597459 20.584541)
		(width 0.12065)
		(layer "In3.Cu")
		(net "NFP_ARM_SPI_FLASH_SEL")
	)
	(segment
		(start 22.625964 17.633036)
		(end 22.87999 17.633036)
		(width 0.12065)
		(layer "In3.Cu")
		(net "NFP_ARM_SPI_FLASH_SEL")
	)
	(segment
		(start 23.915954 18.669)
		(end 24.257 18.669)
		(width 0.12065)
		(layer "In3.Cu")
		(net "NFP_ARM_SPI_FLASH_SEL")
	)
	(segment
		(start 37.010696 21.473541)
		(end 37.708459 21.473541)
		(width 0.12065)
		(layer "In3.Cu")
		(net "NFP_ARM_SPI_FLASH_SEL")
	)
	(segment
		(start 21.463 19.05)
		(end 21.971 18.542)
		(width 0.12065)
		(layer "In3.Cu")
		(net "NFP_ARM_SPI_FLASH_SEL")
	)
	(segment
		(start 32.506793 19.679793)
		(end 35.535286 19.679793)
		(width 0.12065)
		(layer "In3.Cu")
		(net "NFP_ARM_SPI_FLASH_SEL")
	)
	(segment
		(start 39.33378 17.10878)
		(end 38.767004 16.542004)
		(width 0.12065)
		(layer "In3.Cu")
		(net "NFP_ARM_SPI_FLASH_SEL")
	)
	(segment
		(start 20.701 21.336)
		(end 21.463 20.574)
		(width 0.12065)
		(layer "In3.Cu")
		(net "NFP_ARM_SPI_FLASH_SEL")
	)
	(segment
		(start 39.33378 19.97522)
		(end 39.33378 17.10878)
		(width 0.12065)
		(layer "In3.Cu")
		(net "NFP_ARM_SPI_FLASH_SEL")
	)
	(segment
		(start 31.877 19.05)
		(end 32.506793 19.679793)
		(width 0.12065)
		(layer "In3.Cu")
		(net "NFP_ARM_SPI_FLASH_SEL")
	)
	(segment
		(start 27.94 18.415)
		(end 28.575 19.05)
		(width 0.12065)
		(layer "In3.Cu")
		(net "NFP_ARM_SPI_FLASH_SEL")
	)
	(segment
		(start 38.597459 20.584541)
		(end 38.724459 20.584541)
		(width 0.12065)
		(layer "In3.Cu")
		(net "NFP_ARM_SPI_FLASH_SEL")
	)
	(segment
		(start 24.511 18.415)
		(end 27.94 18.415)
		(width 0.12065)
		(layer "In3.Cu")
		(net "NFP_ARM_SPI_FLASH_SEL")
	)
	(segment
		(start 35.813975 19.685)
		(end 36.322076 20.193102)
		(width 0.12065)
		(layer "In3.Cu")
		(net "NFP_ARM_SPI_FLASH_SEL")
	)
	(segment
		(start 21.971 18.288)
		(end 22.625964 17.633036)
		(width 0.12065)
		(layer "In3.Cu")
		(net "NFP_ARM_SPI_FLASH_SEL")
	)
	(segment
		(start 21.463 20.574)
		(end 21.463 19.05)
		(width 0.12065)
		(layer "In3.Cu")
		(net "NFP_ARM_SPI_FLASH_SEL")
	)
	(segment
		(start 36.322076 20.193102)
		(end 36.322076 20.784922)
		(width 0.12065)
		(layer "In3.Cu")
		(net "NFP_ARM_SPI_FLASH_SEL")
	)
	(segment
		(start 24.257 18.669)
		(end 24.511 18.415)
		(width 0.12065)
		(layer "In3.Cu")
		(net "NFP_ARM_SPI_FLASH_SEL")
	)
	(segment
		(start 21.971 18.542)
		(end 21.971 18.288)
		(width 0.12065)
		(layer "In3.Cu")
		(net "NFP_ARM_SPI_FLASH_SEL")
	)
	(segment
		(start 36.322076 20.784922)
		(end 37.010696 21.473541)
		(width 0.12065)
		(layer "In3.Cu")
		(net "NFP_ARM_SPI_FLASH_SEL")
	)
	(segment
		(start 38.724459 20.584541)
		(end 39.33378 19.97522)
		(width 0.12065)
		(layer "In3.Cu")
		(net "NFP_ARM_SPI_FLASH_SEL")
	)
	(segment
		(start 22.7838 18.8341)
		(end 22.7838 18.161)
		(width 0.14732)
		(layer "F.Cu")
		(net "NFP_ARM_SPI_FLASH_SCK")
	)
	(segment
		(start 23.241 17.7038)
		(end 22.7838 18.161)
		(width 0.14732)
		(layer "F.Cu")
		(net "NFP_ARM_SPI_FLASH_SCK")
	)
	(segment
		(start 23.241 17.272)
		(end 23.241 17.7038)
		(width 0.14732)
		(layer "F.Cu")
		(net "NFP_ARM_SPI_FLASH_SCK")
	)
	(via
		(at 22.7838 18.161)
		(size 0.508)
		(drill 0.25654)
		(layers "F.Cu" "B.Cu")
		(net "NFP_ARM_SPI_FLASH_SCK")
	)
	(via
		(at 25.391796 28.013812)
		(size 0.762)
		(drill 0.381)
		(layers "F.Cu" "B.Cu")
		(net "NFP_ARM_SPI_FLASH_SCK")
	)
	(via
		(at 37.1729 21.971)
		(size 0.4572)
		(drill 0.20574)
		(layers "F.Cu" "B.Cu")
		(net "NFP_ARM_SPI_FLASH_SCK")
	)
	(segment
		(start 23.241 22.86)
		(end 23.241 25.019)
		(width 0.14732)
		(layer "B.Cu")
		(net "NFP_ARM_SPI_FLASH_SCK")
	)
	(segment
		(start 24.45766 27.12466)
		(end 23.865434 27.12466)
		(width 0.14732)
		(layer "B.Cu")
		(net "NFP_ARM_SPI_FLASH_SCK")
	)
	(segment
		(start 25.391796 28.013812)
		(end 25.346812 28.013812)
		(width 0.14732)
		(layer "B.Cu")
		(net "NFP_ARM_SPI_FLASH_SCK")
	)
	(segment
		(start 23.241 26.500226)
		(end 23.241 25.019)
		(width 0.14732)
		(layer "B.Cu")
		(net "NFP_ARM_SPI_FLASH_SCK")
	)
	(segment
		(start 22.606 18.3388)
		(end 22.606 22.225)
		(width 0.14732)
		(layer "B.Cu")
		(net "NFP_ARM_SPI_FLASH_SCK")
	)
	(segment
		(start 22.606 22.225)
		(end 23.241 22.86)
		(width 0.14732)
		(layer "B.Cu")
		(net "NFP_ARM_SPI_FLASH_SCK")
	)
	(segment
		(start 25.346812 28.013812)
		(end 24.45766 27.12466)
		(width 0.14732)
		(layer "B.Cu")
		(net "NFP_ARM_SPI_FLASH_SCK")
	)
	(segment
		(start 22.7838 18.161)
		(end 22.606 18.3388)
		(width 0.14732)
		(layer "B.Cu")
		(net "NFP_ARM_SPI_FLASH_SCK")
	)
	(segment
		(start 23.865434 27.12466)
		(end 23.241 26.500226)
		(width 0.14732)
		(layer "B.Cu")
		(net "NFP_ARM_SPI_FLASH_SCK")
	)
	(segment
		(start 23.6728 19.05)
		(end 22.7838 18.161)
		(width 0.12065)
		(layer "In3.Cu")
		(net "NFP_ARM_SPI_FLASH_SCK")
	)
	(segment
		(start 27.94 19.05)
		(end 23.6728 19.05)
		(width 0.12065)
		(layer "In3.Cu")
		(net "NFP_ARM_SPI_FLASH_SCK")
	)
	(segment
		(start 32.349059 19.903059)
		(end 31.75 19.304)
		(width 0.12065)
		(layer "In3.Cu")
		(net "NFP_ARM_SPI_FLASH_SCK")
	)
	(segment
		(start 28.194 19.304)
		(end 27.94 19.05)
		(width 0.12065)
		(layer "In3.Cu")
		(net "NFP_ARM_SPI_FLASH_SCK")
	)
	(segment
		(start 37.1729 21.971)
		(end 36.6649 21.463)
		(width 0.12065)
		(layer "In3.Cu")
		(net "NFP_ARM_SPI_FLASH_SCK")
	)
	(segment
		(start 35.442804 19.903059)
		(end 32.349059 19.903059)
		(width 0.12065)
		(layer "In3.Cu")
		(net "NFP_ARM_SPI_FLASH_SCK")
	)
	(segment
		(start 35.849941 21.117941)
		(end 35.849941 20.310196)
		(width 0.12065)
		(layer "In3.Cu")
		(net "NFP_ARM_SPI_FLASH_SCK")
	)
	(segment
		(start 36.195 21.463)
		(end 35.849941 21.117941)
		(width 0.12065)
		(layer "In3.Cu")
		(net "NFP_ARM_SPI_FLASH_SCK")
	)
	(segment
		(start 35.849941 20.310196)
		(end 35.442804 19.903059)
		(width 0.12065)
		(layer "In3.Cu")
		(net "NFP_ARM_SPI_FLASH_SCK")
	)
	(segment
		(start 31.75 19.304)
		(end 28.194 19.304)
		(width 0.12065)
		(layer "In3.Cu")
		(net "NFP_ARM_SPI_FLASH_SCK")
	)
	(segment
		(start 36.6649 21.463)
		(end 36.195 21.463)
		(width 0.12065)
		(layer "In3.Cu")
		(net "NFP_ARM_SPI_FLASH_SCK")
	)
	(segment
		(start 24.511 17.272)
		(end 24.511 17.573092)
		(width 0.14732)
		(layer "F.Cu")
		(net "NFP_ARM_SPI_FLASH_MOSI")
	)
	(segment
		(start 24.0538 18.8341)
		(end 24.0538 18.161)
		(width 0.14732)
		(layer "F.Cu")
		(net "NFP_ARM_SPI_FLASH_MOSI")
	)
	(segment
		(start 24.20559 17.878501)
		(end 24.0538 18.161)
		(width 0.14732)
		(layer "F.Cu")
		(net "NFP_ARM_SPI_FLASH_MOSI")
	)
	(segment
		(start 24.511 17.573092)
		(end 24.20559 17.878501)
		(width 0.14732)
		(layer "F.Cu")
		(net "NFP_ARM_SPI_FLASH_MOSI")
	)
	(via
		(at 24.0538 18.161)
		(size 0.508)
		(drill 0.25654)
		(layers "F.Cu" "B.Cu")
		(net "NFP_ARM_SPI_FLASH_MOSI")
	)
	(via
		(at 24.638 17.526)
		(size 0.762)
		(drill 0.381)
		(layers "F.Cu" "B.Cu")
		(net "NFP_ARM_SPI_FLASH_MOSI")
	)
	(via
		(at 37.5539 18.415)
		(size 0.4572)
		(drill 0.20574)
		(layers "F.Cu" "B.Cu")
		(net "NFP_ARM_SPI_FLASH_MOSI")
	)
	(segment
		(start 24.0538 18.1102)
		(end 24.638 17.526)
		(width 0.14732)
		(layer "B.Cu")
		(net "NFP_ARM_SPI_FLASH_MOSI")
	)
	(segment
		(start 24.0538 18.161)
		(end 24.0538 18.1102)
		(width 0.14732)
		(layer "B.Cu")
		(net "NFP_ARM_SPI_FLASH_MOSI")
	)
	(segment
		(start 23.876 18.30832)
		(end 23.876 21.844)
		(width 0.14732)
		(layer "B.Cu")
		(net "NFP_ARM_SPI_FLASH_MOSI")
	)
	(segment
		(start 24.02332 18.161)
		(end 23.876 18.30832)
		(width 0.14732)
		(layer "B.Cu")
		(net "NFP_ARM_SPI_FLASH_MOSI")
	)
	(segment
		(start 24.511 22.479)
		(end 24.511 25.019)
		(width 0.14732)
		(layer "B.Cu")
		(net "NFP_ARM_SPI_FLASH_MOSI")
	)
	(segment
		(start 23.876 21.844)
		(end 24.511 22.479)
		(width 0.14732)
		(layer "B.Cu")
		(net "NFP_ARM_SPI_FLASH_MOSI")
	)
	(segment
		(start 24.0538 18.161)
		(end 24.02332 18.161)
		(width 0.14732)
		(layer "B.Cu")
		(net "NFP_ARM_SPI_FLASH_MOSI")
	)
	(segment
		(start 36.322 18.415)
		(end 35.814 18.923)
		(width 0.12065)
		(layer "In3.Cu")
		(net "NFP_ARM_SPI_FLASH_MOSI")
	)
	(segment
		(start 29.718025 18.796)
		(end 28.956025 18.034)
		(width 0.12065)
		(layer "In3.Cu")
		(net "NFP_ARM_SPI_FLASH_MOSI")
	)
	(segment
		(start 33.401 19.431)
		(end 32.639 19.431)
		(width 0.12065)
		(layer "In3.Cu")
		(net "NFP_ARM_SPI_FLASH_MOSI")
	)
	(segment
		(start 33.909 18.923)
		(end 33.401 19.431)
		(width 0.12065)
		(layer "In3.Cu")
		(net "NFP_ARM_SPI_FLASH_MOSI")
	)
	(segment
		(start 28.956025 18.034)
		(end 24.17445 18.034)
		(width 0.12065)
		(layer "In3.Cu")
		(net "NFP_ARM_SPI_FLASH_MOSI")
	)
	(segment
		(start 32.004 18.796)
		(end 29.718025 18.796)
		(width 0.12065)
		(layer "In3.Cu")
		(net "NFP_ARM_SPI_FLASH_MOSI")
	)
	(segment
		(start 24.17445 18.034)
		(end 24.0538 18.15465)
		(width 0.12065)
		(layer "In3.Cu")
		(net "NFP_ARM_SPI_FLASH_MOSI")
	)
	(segment
		(start 35.814 18.923)
		(end 33.909 18.923)
		(width 0.12065)
		(layer "In3.Cu")
		(net "NFP_ARM_SPI_FLASH_MOSI")
	)
	(segment
		(start 24.0538 18.15465)
		(end 24.0538 18.161)
		(width 0.12065)
		(layer "In3.Cu")
		(net "NFP_ARM_SPI_FLASH_MOSI")
	)
	(segment
		(start 37.5539 18.415)
		(end 36.322 18.415)
		(width 0.12065)
		(layer "In3.Cu")
		(net "NFP_ARM_SPI_FLASH_MOSI")
	)
	(segment
		(start 32.639 19.431)
		(end 32.004 18.796)
		(width 0.12065)
		(layer "In3.Cu")
		(net "NFP_ARM_SPI_FLASH_MOSI")
	)
	(segment
		(start 21.5138 26.1239)
		(end 21.5138 21.7932)
		(width 0.14732)
		(layer "F.Cu")
		(net "NFP_ARM_SPI_FLASH_MISO")
	)
	(segment
		(start 21.5138 21.7932)
		(end 21.971 21.336)
		(width 0.14732)
		(layer "F.Cu")
		(net "NFP_ARM_SPI_FLASH_MISO")
	)
	(segment
		(start 24.003 20.447)
		(end 22.86 20.447)
		(width 0.14732)
		(layer "F.Cu")
		(net "NFP_ARM_SPI_FLASH_MISO")
	)
	(segment
		(start 24.96566 17.621834)
		(end 24.765 17.822494)
		(width 0.14732)
		(layer "F.Cu")
		(net "NFP_ARM_SPI_FLASH_MISO")
	)
	(segment
		(start 24.96566 16.256)
		(end 24.96566 17.621834)
		(width 0.14732)
		(layer "F.Cu")
		(net "NFP_ARM_SPI_FLASH_MISO")
	)
	(segment
		(start 25.908 14.986)
		(end 25.43683 15.45717)
		(width 0.14732)
		(layer "F.Cu")
		(net "NFP_ARM_SPI_FLASH_MISO")
	)
	(segment
		(start 42.237 21.041995)
		(end 41.737001 21.541994)
		(width 0.13208)
		(layer "F.Cu")
		(net "NFP_ARM_SPI_FLASH_MISO")
	)
	(segment
		(start 25.43683 15.45717)
		(end 25.43683 15.78483)
		(width 0.14732)
		(layer "F.Cu")
		(net "NFP_ARM_SPI_FLASH_MISO")
	)
	(segment
		(start 25.43683 15.78483)
		(end 24.96566 16.256)
		(width 0.14732)
		(layer "F.Cu")
		(net "NFP_ARM_SPI_FLASH_MISO")
	)
	(segment
		(start 22.86 20.447)
		(end 21.971 21.336)
		(width 0.14732)
		(layer "F.Cu")
		(net "NFP_ARM_SPI_FLASH_MISO")
	)
	(segment
		(start 24.765 17.822494)
		(end 24.765 19.685)
		(width 0.14732)
		(layer "F.Cu")
		(net "NFP_ARM_SPI_FLASH_MISO")
	)
	(segment
		(start 24.765 19.685)
		(end 24.003 20.447)
		(width 0.14732)
		(layer "F.Cu")
		(net "NFP_ARM_SPI_FLASH_MISO")
	)
	(via
		(at 41.737001 21.541994)
		(size 0.4826)
		(drill 0.20574)
		(layers "F.Cu" "B.Cu")
		(net "NFP_ARM_SPI_FLASH_MISO")
	)
	(via
		(at 25.908 14.986)
		(size 0.762)
		(drill 0.381)
		(layers "F.Cu" "B.Cu")
		(net "NFP_ARM_SPI_FLASH_MISO")
	)
	(via
		(at 21.971 21.336)
		(size 0.508)
		(drill 0.254)
		(layers "F.Cu" "B.Cu")
		(net "NFP_ARM_SPI_FLASH_MISO")
	)
	(segment
		(start 22.098 18.118226)
		(end 21.971 18.245226)
		(width 0.14732)
		(layer "B.Cu")
		(net "NFP_ARM_SPI_FLASH_MISO")
	)
	(segment
		(start 21.971 19.685)
		(end 21.971 21.336)
		(width 0.14732)
		(layer "B.Cu")
		(net "NFP_ARM_SPI_FLASH_MISO")
	)
	(segment
		(start 21.971 18.245226)
		(end 21.971 19.685)
		(width 0.14732)
		(layer "B.Cu")
		(net "NFP_ARM_SPI_FLASH_MISO")
	)
	(segment
		(start 21.971 17.3101)
		(end 22.098 17.4371)
		(width 0.14732)
		(layer "B.Cu")
		(net "NFP_ARM_SPI_FLASH_MISO")
	)
	(segment
		(start 22.098 17.4371)
		(end 22.098 18.118226)
		(width 0.14732)
		(layer "B.Cu")
		(net "NFP_ARM_SPI_FLASH_MISO")
	)
	(segment
		(start 39.90406 19.138773)
		(end 38.265227 19.138773)
		(width 0.12065)
		(layer "In6.Cu")
		(net "NFP_ARM_SPI_FLASH_MISO")
	)
	(segment
		(start 27.949804 21.498941)
		(end 26.705941 21.498941)
		(width 0.12065)
		(layer "In6.Cu")
		(net "NFP_ARM_SPI_FLASH_MISO")
	)
	(segment
		(start 29.910659 20.127341)
		(end 29.910659 20.381341)
		(width 0.12065)
		(layer "In6.Cu")
		(net "NFP_ARM_SPI_FLASH_MISO")
	)
	(segment
		(start 41.021 20.066)
		(end 40.513 20.066)
		(width 0.12065)
		(layer "In6.Cu")
		(net "NFP_ARM_SPI_FLASH_MISO")
	)
	(segment
		(start 41.274949 21.079943)
		(end 41.274949 20.319949)
		(width 0.12065)
		(layer "In6.Cu")
		(net "NFP_ARM_SPI_FLASH_MISO")
	)
	(segment
		(start 26.543 21.336)
		(end 25.527 21.336)
		(width 0.12065)
		(layer "In6.Cu")
		(net "NFP_ARM_SPI_FLASH_MISO")
	)
	(segment
		(start 25.527 21.336)
		(end 24.638 22.225)
		(width 0.12065)
		(layer "In6.Cu")
		(net "NFP_ARM_SPI_FLASH_MISO")
	)
	(segment
		(start 28.179141 21.269604)
		(end 27.949804 21.498941)
		(width 0.12065)
		(layer "In6.Cu")
		(net "NFP_ARM_SPI_FLASH_MISO")
	)
	(segment
		(start 40.513 20.066)
		(end 40.259 19.812)
		(width 0.12065)
		(layer "In6.Cu")
		(net "NFP_ARM_SPI_FLASH_MISO")
	)
	(segment
		(start 24.638 22.225)
		(end 23.368 22.225)
		(width 0.12065)
		(layer "In6.Cu")
		(net "NFP_ARM_SPI_FLASH_MISO")
	)
	(segment
		(start 37.010696 19.801459)
		(end 37.000155 19.812)
		(width 0.12065)
		(layer "In6.Cu")
		(net "NFP_ARM_SPI_FLASH_MISO")
	)
	(segment
		(start 37.000155 19.812)
		(end 30.226 19.812)
		(width 0.12065)
		(layer "In6.Cu")
		(net "NFP_ARM_SPI_FLASH_MISO")
	)
	(segment
		(start 40.259 19.812)
		(end 40.259 19.557975)
		(width 0.12065)
		(layer "In6.Cu")
		(net "NFP_ARM_SPI_FLASH_MISO")
	)
	(segment
		(start 26.705941 21.498941)
		(end 26.543 21.336)
		(width 0.12065)
		(layer "In6.Cu")
		(net "NFP_ARM_SPI_FLASH_MISO")
	)
	(segment
		(start 38.265227 19.138773)
		(end 37.602541 19.801459)
		(width 0.12065)
		(layer "In6.Cu")
		(net "NFP_ARM_SPI_FLASH_MISO")
	)
	(segment
		(start 37.602541 19.801459)
		(end 37.010696 19.801459)
		(width 0.12065)
		(layer "In6.Cu")
		(net "NFP_ARM_SPI_FLASH_MISO")
	)
	(segment
		(start 41.737001 21.541994)
		(end 41.274949 21.079943)
		(width 0.12065)
		(layer "In6.Cu")
		(net "NFP_ARM_SPI_FLASH_MISO")
	)
	(segment
		(start 23.368 22.225)
		(end 22.479 21.336)
		(width 0.12065)
		(layer "In6.Cu")
		(net "NFP_ARM_SPI_FLASH_MISO")
	)
	(segment
		(start 40.14023 19.374942)
		(end 39.90406 19.138773)
		(width 0.12065)
		(layer "In6.Cu")
		(net "NFP_ARM_SPI_FLASH_MISO")
	)
	(segment
		(start 41.274949 20.319949)
		(end 41.021 20.066)
		(width 0.12065)
		(layer "In6.Cu")
		(net "NFP_ARM_SPI_FLASH_MISO")
	)
	(segment
		(start 29.910659 20.381341)
		(end 29.591 20.701)
		(width 0.12065)
		(layer "In6.Cu")
		(net "NFP_ARM_SPI_FLASH_MISO")
	)
	(segment
		(start 22.479 21.336)
		(end 21.971 21.336)
		(width 0.12065)
		(layer "In6.Cu")
		(net "NFP_ARM_SPI_FLASH_MISO")
	)
	(segment
		(start 40.259 19.557975)
		(end 40.14023 19.439204)
		(width 0.12065)
		(layer "In6.Cu")
		(net "NFP_ARM_SPI_FLASH_MISO")
	)
	(segment
		(start 40.14023 19.439204)
		(end 40.14023 19.374942)
		(width 0.12065)
		(layer "In6.Cu")
		(net "NFP_ARM_SPI_FLASH_MISO")
	)
	(segment
		(start 29.591 20.701)
		(end 28.478455 20.701)
		(width 0.12065)
		(layer "In6.Cu")
		(net "NFP_ARM_SPI_FLASH_MISO")
	)
	(segment
		(start 28.179141 21.000314)
		(end 28.179141 21.269604)
		(width 0.12065)
		(layer "In6.Cu")
		(net "NFP_ARM_SPI_FLASH_MISO")
	)
	(segment
		(start 30.226 19.812)
		(end 29.910659 20.127341)
		(width 0.12065)
		(layer "In6.Cu")
		(net "NFP_ARM_SPI_FLASH_MISO")
	)
	(segment
		(start 28.478455 20.701)
		(end 28.179141 21.000314)
		(width 0.12065)
		(layer "In6.Cu")
		(net "NFP_ARM_SPI_FLASH_MISO")
	)
	(segment
		(start 22.479 47.752)
		(end 21.72716 48.50384)
		(width 0.14732)
		(layer "F.Cu")
		(net "HOST_RESET_REQ_L")
	)
	(segment
		(start 19.25066 48.50384)
		(end 19.05 48.7045)
		(width 0.14732)
		(layer "F.Cu")
		(net "HOST_RESET_REQ_L")
	)
	(segment
		(start 36.2458 24.8412)
		(end 35.8267 25.2603)
		(width 0.127)
		(layer "F.Cu")
		(net "HOST_RESET_REQ_L")
	)
	(segment
		(start 34.957918 25.2603)
		(end 34.746006 25.048388)
		(width 0.127)
		(layer "F.Cu")
		(net "HOST_RESET_REQ_L")
	)
	(segment
		(start 35.8267 25.2603)
		(end 34.957918 25.2603)
		(width 0.127)
		(layer "F.Cu")
		(net "HOST_RESET_REQ_L")
	)
	(segment
		(start 21.72716 48.50384)
		(end 19.25066 48.50384)
		(width 0.14732)
		(layer "F.Cu")
		(net "HOST_RESET_REQ_L")
	)
	(segment
		(start 22.479 47.498)
		(end 22.479 47.752)
		(width 0.14732)
		(layer "F.Cu")
		(net "HOST_RESET_REQ_L")
	)
	(via
		(at 22.098 27.432)
		(size 0.508)
		(drill 0.254)
		(layers "F.Cu" "B.Cu")
		(net "HOST_RESET_REQ_L")
	)
	(via
		(at 19.05 48.7045)
		(size 0.508)
		(drill 0.25654)
		(layers "F.Cu" "B.Cu")
		(net "HOST_RESET_REQ_L")
	)
	(via
		(at 36.2458 24.8412)
		(size 0.4572)
		(drill 0.20574)
		(layers "F.Cu" "B.Cu")
		(net "HOST_RESET_REQ_L")
	)
	(segment
		(start 34.5821 25.6159)
		(end 34.9377 25.2603)
		(width 0.127)
		(layer "B.Cu")
		(net "HOST_RESET_REQ_L")
	)
	(segment
		(start 34.9377 25.2603)
		(end 35.8267 25.2603)
		(width 0.127)
		(layer "B.Cu")
		(net "HOST_RESET_REQ_L")
	)
	(segment
		(start 35.8267 25.2603)
		(end 36.2458 24.8412)
		(width 0.127)
		(layer "B.Cu")
		(net "HOST_RESET_REQ_L")
	)
	(segment
		(start 34.5821 26.162)
		(end 34.5821 25.6159)
		(width 0.127)
		(layer "B.Cu")
		(net "HOST_RESET_REQ_L")
	)
	(segment
		(start 35.879659 24.449659)
		(end 36.2458 24.8158)
		(width 0.12065)
		(layer "In2.Cu")
		(net "HOST_RESET_REQ_L")
	)
	(segment
		(start 32.506945 24.892)
		(end 33.401 24.892)
		(width 0.12065)
		(layer "In2.Cu")
		(net "HOST_RESET_REQ_L")
	)
	(segment
		(start 24.638 28.448)
		(end 26.416 26.67)
		(width 0.12065)
		(layer "In2.Cu")
		(net "HOST_RESET_REQ_L")
	)
	(segment
		(start 24.003 28.448)
		(end 24.638 28.448)
		(width 0.12065)
		(layer "In2.Cu")
		(net "HOST_RESET_REQ_L")
	)
	(segment
		(start 33.401 24.892)
		(end 33.843341 24.449659)
		(width 0.12065)
		(layer "In2.Cu")
		(net "HOST_RESET_REQ_L")
	)
	(segment
		(start 22.987 27.432)
		(end 24.003 28.448)
		(width 0.12065)
		(layer "In2.Cu")
		(net "HOST_RESET_REQ_L")
	)
	(segment
		(start 31.308396 24.881459)
		(end 31.359196 24.830659)
		(width 0.12065)
		(layer "In2.Cu")
		(net "HOST_RESET_REQ_L")
	)
	(segment
		(start 26.416 26.67)
		(end 27.559 26.67)
		(width 0.12065)
		(layer "In2.Cu")
		(net "HOST_RESET_REQ_L")
	)
	(segment
		(start 29.347541 24.881459)
		(end 31.308396 24.881459)
		(width 0.12065)
		(layer "In2.Cu")
		(net "HOST_RESET_REQ_L")
	)
	(segment
		(start 31.734404 24.881459)
		(end 32.496404 24.881459)
		(width 0.12065)
		(layer "In2.Cu")
		(net "HOST_RESET_REQ_L")
	)
	(segment
		(start 31.359196 24.830659)
		(end 31.683604 24.830659)
		(width 0.12065)
		(layer "In2.Cu")
		(net "HOST_RESET_REQ_L")
	)
	(segment
		(start 27.559 26.67)
		(end 29.347541 24.881459)
		(width 0.12065)
		(layer "In2.Cu")
		(net "HOST_RESET_REQ_L")
	)
	(segment
		(start 33.843341 24.449659)
		(end 35.879659 24.449659)
		(width 0.12065)
		(layer "In2.Cu")
		(net "HOST_RESET_REQ_L")
	)
	(segment
		(start 31.683604 24.830659)
		(end 31.734404 24.881459)
		(width 0.12065)
		(layer "In2.Cu")
		(net "HOST_RESET_REQ_L")
	)
	(segment
		(start 32.496404 24.881459)
		(end 32.506945 24.892)
		(width 0.12065)
		(layer "In2.Cu")
		(net "HOST_RESET_REQ_L")
	)
	(segment
		(start 22.098 27.432)
		(end 22.987 27.432)
		(width 0.12065)
		(layer "In2.Cu")
		(net "HOST_RESET_REQ_L")
	)
	(segment
		(start 36.2458 24.8158)
		(end 36.2458 24.8412)
		(width 0.12065)
		(layer "In2.Cu")
		(net "HOST_RESET_REQ_L")
	)
	(segment
		(start 20.955 38.481)
		(end 19.558 39.878)
		(width 0.12065)
		(layer "In7.Cu")
		(net "HOST_RESET_REQ_L")
	)
	(segment
		(start 20.899171 35.683825)
		(end 21.264829 35.683825)
		(width 0.12065)
		(layer "In7.Cu")
		(net "HOST_RESET_REQ_L")
	)
	(segment
		(start 20.6375 34.925)
		(end 20.6375 35.422154)
		(width 0.12065)
		(layer "In7.Cu")
		(net "HOST_RESET_REQ_L")
	)
	(segment
		(start 21.264829 35.683825)
		(end 21.523325 35.942321)
		(width 0.12065)
		(layer "In7.Cu")
		(net "HOST_RESET_REQ_L")
	)
	(segment
		(start 19.558 41.275)
		(end 18.415 42.418)
		(width 0.12065)
		(layer "In7.Cu")
		(net "HOST_RESET_REQ_L")
	)
	(segment
		(start 20.955 37.338)
		(end 20.955 38.481)
		(width 0.12065)
		(layer "In7.Cu")
		(net "HOST_RESET_REQ_L")
	)
	(segment
		(start 19.558 39.878)
		(end 19.558 41.275)
		(width 0.12065)
		(layer "In7.Cu")
		(net "HOST_RESET_REQ_L")
	)
	(segment
		(start 21.523325 35.942321)
		(end 21.523325 36.769675)
		(width 0.12065)
		(layer "In7.Cu")
		(net "HOST_RESET_REQ_L")
	)
	(segment
		(start 20.320076 31.877076)
		(end 20.320076 34.607576)
		(width 0.12065)
		(layer "In7.Cu")
		(net "HOST_RESET_REQ_L")
	)
	(segment
		(start 20.066 31.623)
		(end 20.320076 31.877076)
		(width 0.12065)
		(layer "In7.Cu")
		(net "HOST_RESET_REQ_L")
	)
	(segment
		(start 21.209 28.321)
		(end 20.701 28.321)
		(width 0.12065)
		(layer "In7.Cu")
		(net "HOST_RESET_REQ_L")
	)
	(segment
		(start 20.6375 35.422154)
		(end 20.899171 35.683825)
		(width 0.12065)
		(layer "In7.Cu")
		(net "HOST_RESET_REQ_L")
	)
	(segment
		(start 20.320076 34.607576)
		(end 20.6375 34.925)
		(width 0.12065)
		(layer "In7.Cu")
		(net "HOST_RESET_REQ_L")
	)
	(segment
		(start 18.415 46.482)
		(end 19.05 47.117)
		(width 0.12065)
		(layer "In7.Cu")
		(net "HOST_RESET_REQ_L")
	)
	(segment
		(start 19.05 47.117)
		(end 19.05 48.7045)
		(width 0.12065)
		(layer "In7.Cu")
		(net "HOST_RESET_REQ_L")
	)
	(segment
		(start 20.066 28.956)
		(end 20.066 31.623)
		(width 0.12065)
		(layer "In7.Cu")
		(net "HOST_RESET_REQ_L")
	)
	(segment
		(start 18.415 42.418)
		(end 18.415 46.482)
		(width 0.12065)
		(layer "In7.Cu")
		(net "HOST_RESET_REQ_L")
	)
	(segment
		(start 21.523325 36.769675)
		(end 20.955 37.338)
		(width 0.12065)
		(layer "In7.Cu")
		(net "HOST_RESET_REQ_L")
	)
	(segment
		(start 20.701 28.321)
		(end 20.066 28.956)
		(width 0.12065)
		(layer "In7.Cu")
		(net "HOST_RESET_REQ_L")
	)
	(segment
		(start 22.098 27.432)
		(end 21.209 28.321)
		(width 0.12065)
		(layer "In7.Cu")
		(net "HOST_RESET_REQ_L")
	)
	(segment
		(start 41.91 51.9049)
		(end 42.418 51.3969)
		(width 0.14732)
		(layer "F.Cu")
		(net "EXT_12.0V_THRESHOLD")
	)
	(segment
		(start 41.91 50.165)
		(end 42.418 50.673)
		(width 0.14732)
		(layer "F.Cu")
		(net "EXT_12.0V_THRESHOLD")
	)
	(segment
		(start 41.91 49.7967)
		(end 41.91 50.165)
		(width 0.14732)
		(layer "F.Cu")
		(net "EXT_12.0V_THRESHOLD")
	)
	(segment
		(start 42.35958 49.34712)
		(end 41.91 49.7967)
		(width 0.14732)
		(layer "F.Cu")
		(net "EXT_12.0V_THRESHOLD")
	)
	(segment
		(start 42.3291 53.1368)
		(end 42.3291 52.9971)
		(width 0.14732)
		(layer "F.Cu")
		(net "EXT_12.0V_THRESHOLD")
	)
	(segment
		(start 43.688 49.34712)
		(end 42.35958 49.34712)
		(width 0.14732)
		(layer "F.Cu")
		(net "EXT_12.0V_THRESHOLD")
	)
	(segment
		(start 43.307 51.3969)
		(end 42.418 51.3969)
		(width 0.14732)
		(layer "F.Cu")
		(net "EXT_12.0V_THRESHOLD")
	)
	(segment
		(start 42.3291 52.9971)
		(end 41.91 52.578)
		(width 0.14732)
		(layer "F.Cu")
		(net "EXT_12.0V_THRESHOLD")
	)
	(segment
		(start 41.91 52.578)
		(end 41.91 51.9049)
		(width 0.14732)
		(layer "F.Cu")
		(net "EXT_12.0V_THRESHOLD")
	)
	(segment
		(start 42.418 51.3969)
		(end 42.418 50.673)
		(width 0.14732)
		(layer "F.Cu")
		(net "EXT_12.0V_THRESHOLD")
	)
	(via
		(at 42.418 50.673)
		(size 0.508)
		(drill 0.2667)
		(layers "F.Cu" "B.Cu")
		(net "EXT_12.0V_THRESHOLD")
	)
	(segment
		(start 44.91736 48.04664)
		(end 45.212 47.752)
		(width 0.14732)
		(layer "F.Cu")
		(net "EXT_12.0V_PGOOD")
	)
	(segment
		(start 40.9829 49.784)
		(end 41.91 48.9585)
		(width 0.14732)
		(layer "F.Cu")
		(net "EXT_12.0V_PGOOD")
	)
	(segment
		(start 41.91254 48.04664)
		(end 43.688 48.04664)
		(width 0.14732)
		(layer "F.Cu")
		(net "EXT_12.0V_PGOOD")
	)
	(segment
		(start 41.91 48.0441)
		(end 41.91254 48.04664)
		(width 0.14732)
		(layer "F.Cu")
		(net "EXT_12.0V_PGOOD")
	)
	(segment
		(start 43.688 48.04664)
		(end 44.91736 48.04664)
		(width 0.14732)
		(layer "F.Cu")
		(net "EXT_12.0V_PGOOD")
	)
	(segment
		(start 34.972498 27.7749)
		(end 34.746006 27.548408)
		(width 0.127)
		(layer "F.Cu")
		(net "EXT_12.0V_PGOOD")
	)
	(segment
		(start 35.8267 27.7749)
		(end 34.972498 27.7749)
		(width 0.127)
		(layer "F.Cu")
		(net "EXT_12.0V_PGOOD")
	)
	(segment
		(start 36.2458 27.3558)
		(end 35.8267 27.7749)
		(width 0.127)
		(layer "F.Cu")
		(net "EXT_12.0V_PGOOD")
	)
	(segment
		(start 40.259 49.784)
		(end 40.9829 49.784)
		(width 0.14732)
		(layer "F.Cu")
		(net "EXT_12.0V_PGOOD")
	)
	(segment
		(start 41.91 48.0441)
		(end 41.91 48.9585)
		(width 0.14732)
		(layer "F.Cu")
		(net "EXT_12.0V_PGOOD")
	)
	(via
		(at 41.737001 28.575)
		(size 0.4826)
		(drill 0.20574)
		(layers "F.Cu" "B.Cu")
		(net "EXT_12.0V_PGOOD")
	)
	(via
		(at 45.212 47.752)
		(size 0.508)
		(drill 0.254)
		(layers "F.Cu" "B.Cu")
		(net "EXT_12.0V_PGOOD")
	)
	(via
		(at 36.2458 27.3558)
		(size 0.4572)
		(drill 0.20574)
		(layers "F.Cu" "B.Cu")
		(net "EXT_12.0V_PGOOD")
	)
	(segment
		(start 36.957 28.067)
		(end 36.2458 27.3558)
		(width 0.12065)
		(layer "In2.Cu")
		(net "EXT_12.0V_PGOOD")
	)
	(segment
		(start 38.227 28.067)
		(end 36.957 28.067)
		(width 0.12065)
		(layer "In2.Cu")
		(net "EXT_12.0V_PGOOD")
	)
	(segment
		(start 38.735 28.575)
		(end 38.227 28.067)
		(width 0.12065)
		(layer "In2.Cu")
		(net "EXT_12.0V_PGOOD")
	)
	(segment
		(start 41.737001 28.575)
		(end 38.735 28.575)
		(width 0.12065)
		(layer "In2.Cu")
		(net "EXT_12.0V_PGOOD")
	)
	(segment
		(start 45.593 45.974)
		(end 45.593 47.371)
		(width 0.12065)
		(layer "In7.Cu")
		(net "EXT_12.0V_PGOOD")
	)
	(segment
		(start 45.593 47.371)
		(end 45.212 47.752)
		(width 0.12065)
		(layer "In7.Cu")
		(net "EXT_12.0V_PGOOD")
	)
	(segment
		(start 42.164 38.618846)
		(end 41.849675 38.933171)
		(width 0.12065)
		(layer "In7.Cu")
		(net "EXT_12.0V_PGOOD")
	)
	(segment
		(start 41.94175 28.779749)
		(end 41.94175 35.157359)
		(width 0.12065)
		(layer "In7.Cu")
		(net "EXT_12.0V_PGOOD")
	)
	(segment
		(start 41.94175 35.157359)
		(end 41.91635 35.182759)
		(width 0.12065)
		(layer "In7.Cu")
		(net "EXT_12.0V_PGOOD")
	)
	(segment
		(start 42.164 39.624)
		(end 43.053 40.513)
		(width 0.12065)
		(layer "In7.Cu")
		(net "EXT_12.0V_PGOOD")
	)
	(segment
		(start 43.053 40.513)
		(end 43.053 43.434)
		(width 0.12065)
		(layer "In7.Cu")
		(net "EXT_12.0V_PGOOD")
	)
	(segment
		(start 42.164 39.613154)
		(end 42.164 39.624)
		(width 0.12065)
		(layer "In7.Cu")
		(net "EXT_12.0V_PGOOD")
	)
	(segment
		(start 41.91635 35.182759)
		(end 41.91635 35.789591)
		(width 0.12065)
		(layer "In7.Cu")
		(net "EXT_12.0V_PGOOD")
	)
	(segment
		(start 41.91635 35.789591)
		(end 42.164 36.037241)
		(width 0.12065)
		(layer "In7.Cu")
		(net "EXT_12.0V_PGOOD")
	)
	(segment
		(start 41.849675 38.933171)
		(end 41.849675 39.298829)
		(width 0.12065)
		(layer "In7.Cu")
		(net "EXT_12.0V_PGOOD")
	)
	(segment
		(start 42.164 36.037241)
		(end 42.164 38.618846)
		(width 0.12065)
		(layer "In7.Cu")
		(net "EXT_12.0V_PGOOD")
	)
	(segment
		(start 41.737001 28.575)
		(end 41.94175 28.779749)
		(width 0.12065)
		(layer "In7.Cu")
		(net "EXT_12.0V_PGOOD")
	)
	(segment
		(start 43.053 43.434)
		(end 45.593 45.974)
		(width 0.12065)
		(layer "In7.Cu")
		(net "EXT_12.0V_PGOOD")
	)
	(segment
		(start 41.849675 39.298829)
		(end 42.164 39.613154)
		(width 0.12065)
		(layer "In7.Cu")
		(net "EXT_12.0V_PGOOD")
	)
	(segment
		(start 22.733 45.847)
		(end 23.495 45.847)
		(width 0.508)
		(layer "F.Cu")
		(net "EXT_12.0V")
	)
	(segment
		(start 22.5679 44.069)
		(end 22.225 44.4119)
		(width 0.508)
		(layer "F.Cu")
		(net "EXT_12.0V")
	)
	(segment
		(start 22.225 44.4119)
		(end 22.225 45.339)
		(width 0.508)
		(layer "F.Cu")
		(net "EXT_12.0V")
	)
	(segment
		(start 22.225 45.339)
		(end 22.733 45.847)
		(width 0.508)
		(layer "F.Cu")
		(net "EXT_12.0V")
	)
	(segment
		(start 5.08 29.972)
		(end 3.937 29.972)
		(width 0.508)
		(layer "F.Cu")
		(net "EXT_12.0V")
	)
	(segment
		(start 3.937 28.702)
		(end 5.2959 28.702)
		(width 0.508)
		(layer "F.Cu")
		(net "EXT_12.0V")
	)
	(segment
		(start 5.334 28.0289)
		(end 5.334 29.718)
		(width 0.508)
		(layer "F.Cu")
		(net "EXT_12.0V")
	)
	(segment
		(start 5.334 29.718)
		(end 5.08 29.972)
		(width 0.508)
		(layer "F.Cu")
		(net "EXT_12.0V")
	)
	(segment
		(start 5.2959 28.702)
		(end 5.334 28.0289)
		(width 0.508)
		(layer "F.Cu")
		(net "EXT_12.0V")
	)
	(segment
		(start 40.9956 39.0144)
		(end 41.275 38.735)
		(width 0.508)
		(layer "F.Cu")
		(net "EXT_12.0V")
	)
	(segment
		(start 39.4716 39.0144)
		(end 40.9956 39.0144)
		(width 0.508)
		(layer "F.Cu")
		(net "EXT_12.0V")
	)
	(segment
		(start 63.250064 48.424084)
		(end 63.250064 47.737776)
		(width 0.2032)
		(layer "F.Cu")
		(net "EXT_12.0V")
	)
	(segment
		(start 43.8658 53.1368)
		(end 44.069 53.34)
		(width 0.254)
		(layer "F.Cu")
		(net "EXT_12.0V")
	)
	(segment
		(start 43.2689 53.1368)
		(end 43.8658 53.1368)
		(width 0.254)
		(layer "F.Cu")
		(net "EXT_12.0V")
	)
	(via
		(at 63.5 53.467)
		(size 0.508)
		(drill 0.254)
		(layers "F.Cu" "B.Cu")
		(net "EXT_12.0V")
	)
	(via
		(at 61.722 52.197)
		(size 0.508)
		(drill 0.254)
		(layers "F.Cu" "B.Cu")
		(net "EXT_12.0V")
	)
	(via
		(at 50.292 36.703)
		(size 0.508)
		(drill 0.254)
		(layers "F.Cu" "B.Cu")
		(net "EXT_12.0V")
	)
	(via
		(at 82.677 50.292)
		(size 0.508)
		(drill 0.254)
		(layers "F.Cu" "B.Cu")
		(net "EXT_12.0V")
	)
	(via
		(at 51.689 37.8206)
		(size 0.508)
		(drill 0.254)
		(layers "F.Cu" "B.Cu")
		(net "EXT_12.0V")
	)
	(via
		(at 50.1015 39.624)
		(size 0.6096)
		(drill 0.25654)
		(layers "F.Cu" "B.Cu")
		(net "EXT_12.0V")
	)
	(via
		(at 44.069 53.34)
		(size 0.508)
		(drill 0.2667)
		(layers "F.Cu" "B.Cu")
		(net "EXT_12.0V")
	)
	(via
		(at 3.937 28.702)
		(size 0.508)
		(drill 0.254)
		(layers "F.Cu" "B.Cu")
		(net "EXT_12.0V")
	)
	(via
		(at 71.882 37.719)
		(size 0.508)
		(drill 0.254)
		(layers "F.Cu" "B.Cu")
		(net "EXT_12.0V")
	)
	(via
		(at 62.992 52.197)
		(size 0.508)
		(drill 0.254)
		(layers "F.Cu" "B.Cu")
		(net "EXT_12.0V")
	)
	(via
		(at 54.3179 38.9636)
		(size 0.508)
		(drill 0.25654)
		(layers "F.Cu" "B.Cu")
		(net "EXT_12.0V")
	)
	(via
		(at 37.719 42.4561)
		(size 0.508)
		(drill 0.25654)
		(layers "F.Cu" "B.Cu")
		(net "EXT_12.0V")
	)
	(via
		(at 70.866 36.703)
		(size 0.508)
		(drill 0.254)
		(layers "F.Cu" "B.Cu")
		(net "EXT_12.0V")
	)
	(via
		(at 68.326 38.7604)
		(size 0.6096)
		(drill 0.25654)
		(layers "F.Cu" "B.Cu")
		(net "EXT_12.0V")
	)
	(via
		(at 41.275 38.735)
		(size 0.508)
		(drill 0.254)
		(layers "F.Cu" "B.Cu")
		(net "EXT_12.0V")
	)
	(via
		(at 3.937 29.972)
		(size 0.508)
		(drill 0.254)
		(layers "F.Cu" "B.Cu")
		(net "EXT_12.0V")
	)
	(via
		(at 53.43398 36.195)
		(size 0.508)
		(drill 0.254)
		(layers "F.Cu" "B.Cu")
		(net "EXT_12.0V")
	)
	(via
		(at 53.3019 38.9636)
		(size 0.508)
		(drill 0.25654)
		(layers "F.Cu" "B.Cu")
		(net "EXT_12.0V")
	)
	(via
		(at 54.6989 36.195)
		(size 0.508)
		(drill 0.254)
		(layers "F.Cu" "B.Cu")
		(net "EXT_12.0V")
	)
	(via
		(at 71.882 36.703)
		(size 0.508)
		(drill 0.254)
		(layers "F.Cu" "B.Cu")
		(net "EXT_12.0V")
	)
	(via
		(at 81.407 50.292)
		(size 0.508)
		(drill 0.254)
		(layers "F.Cu" "B.Cu")
		(net "EXT_12.0V")
	)
	(via
		(at 85.217 51.562)
		(size 0.508)
		(drill 0.254)
		(layers "F.Cu" "B.Cu")
		(net "EXT_12.0V")
	)
	(via
		(at 74.295 36.449)
		(size 0.508)
		(drill 0.254)
		(layers "F.Cu" "B.Cu")
		(net "EXT_12.0V")
	)
	(via
		(at 63.250064 47.737776)
		(size 0.508)
		(drill 0.254)
		(layers "F.Cu" "B.Cu")
		(net "EXT_12.0V")
	)
	(via
		(at 73.025 37.719)
		(size 0.508)
		(drill 0.254)
		(layers "F.Cu" "B.Cu")
		(net "EXT_12.0V")
	)
	(via
		(at 53.4289 37.719)
		(size 0.508)
		(drill 0.254)
		(layers "F.Cu" "B.Cu")
		(net "EXT_12.0V")
	)
	(via
		(at 54.6989 37.719)
		(size 0.508)
		(drill 0.254)
		(layers "F.Cu" "B.Cu")
		(net "EXT_12.0V")
	)
	(via
		(at 73.025 36.449)
		(size 0.508)
		(drill 0.254)
		(layers "F.Cu" "B.Cu")
		(net "EXT_12.0V")
	)
	(via
		(at 23.495 45.847)
		(size 0.508)
		(drill 0.254)
		(layers "F.Cu" "B.Cu")
		(net "EXT_12.0V")
	)
	(via
		(at 70.866 37.719)
		(size 0.508)
		(drill 0.254)
		(layers "F.Cu" "B.Cu")
		(net "EXT_12.0V")
	)
	(via
		(at 74.295 37.719)
		(size 0.508)
		(drill 0.254)
		(layers "F.Cu" "B.Cu")
		(net "EXT_12.0V")
	)
	(via
		(at 69.6976 39.624)
		(size 0.6096)
		(drill 0.25654)
		(layers "F.Cu" "B.Cu")
		(net "EXT_12.0V")
	)
	(via
		(at 16.6624 25.9969)
		(size 0.508)
		(drill 0.254)
		(layers "F.Cu" "B.Cu")
		(net "EXT_12.0V")
	)
	(via
		(at 86.487 51.562)
		(size 0.508)
		(drill 0.254)
		(layers "F.Cu" "B.Cu")
		(net "EXT_12.0V")
	)
	(via
		(at 63.5 54.737)
		(size 0.508)
		(drill 0.254)
		(layers "F.Cu" "B.Cu")
		(net "EXT_12.0V")
	)
	(via
		(at 16.6624 27.2669)
		(size 0.508)
		(drill 0.254)
		(layers "F.Cu" "B.Cu")
		(net "EXT_12.0V")
	)
	(via
		(at 48.7299 38.7604)
		(size 0.6096)
		(drill 0.25654)
		(layers "F.Cu" "B.Cu")
		(net "EXT_12.0V")
	)
	(via
		(at 81.407 51.562)
		(size 0.508)
		(drill 0.254)
		(layers "F.Cu" "B.Cu")
		(net "EXT_12.0V")
	)
	(segment
		(start 17.2974 26.6319)
		(end 16.6624 25.9969)
		(width 0.254)
		(layer "B.Cu")
		(net "EXT_12.0V")
	)
	(segment
		(start 17.2974 27.9019)
		(end 16.6624 27.2669)
		(width 0.254)
		(layer "B.Cu")
		(net "EXT_12.0V")
	)
	(segment
		(start 45.974 51.3969)
		(end 45.085 51.3969)
		(width 0.14732)
		(layer "F.Cu")
		(net "EXT_3.3V_THRESHOLD")
	)
	(segment
		(start 46.3931 51.3969)
		(end 46.609 51.181)
		(width 0.14732)
		(layer "F.Cu")
		(net "EXT_3.3V_THRESHOLD")
	)
	(segment
		(start 49.07026 49.99736)
		(end 48.006 49.99736)
		(width 0.14732)
		(layer "F.Cu")
		(net "EXT_3.3V_THRESHOLD")
	)
	(segment
		(start 48.006 49.99736)
		(end 48.006 50.673)
		(width 0.14732)
		(layer "F.Cu")
		(net "EXT_3.3V_THRESHOLD")
	)
	(segment
		(start 45.974 51.3969)
		(end 46.3931 51.3969)
		(width 0.14732)
		(layer "F.Cu")
		(net "EXT_3.3V_THRESHOLD")
	)
	(segment
		(start 49.53 50.4571)
		(end 49.07026 49.99736)
		(width 0.14732)
		(layer "F.Cu")
		(net "EXT_3.3V_THRESHOLD")
	)
	(segment
		(start 45.085 51.3969)
		(end 44.196 51.3969)
		(width 0.14732)
		(layer "F.Cu")
		(net "EXT_3.3V_THRESHOLD")
	)
	(segment
		(start 46.609 51.181)
		(end 47.498 51.181)
		(width 0.14732)
		(layer "F.Cu")
		(net "EXT_3.3V_THRESHOLD")
	)
	(segment
		(start 47.498 51.181)
		(end 48.006 50.673)
		(width 0.14732)
		(layer "F.Cu")
		(net "EXT_3.3V_THRESHOLD")
	)
	(via
		(at 48.006 50.673)
		(size 0.508)
		(drill 0.2667)
		(layers "F.Cu" "B.Cu")
		(net "EXT_3.3V_THRESHOLD")
	)
	(segment
		(start 33.03331 26.810538)
		(end 33.147 26.924229)
		(width 0.127)
		(layer "F.Cu")
		(net "EXT_3.3V_PGOOD")
	)
	(segment
		(start 33.147 26.9748)
		(end 33.439075 27.266875)
		(width 0.127)
		(layer "F.Cu")
		(net "EXT_3.3V_PGOOD")
	)
	(segment
		(start 49.53 48.6791)
		(end 49.51222 48.69688)
		(width 0.14732)
		(layer "F.Cu")
		(net "EXT_3.3V_PGOOD")
	)
	(segment
		(start 46.80712 48.69688)
		(end 48.006 48.69688)
		(width 0.14732)
		(layer "F.Cu")
		(net "EXT_3.3V_PGOOD")
	)
	(segment
		(start 33.464475 27.266875)
		(end 33.746008 27.548408)
		(width 0.127)
		(layer "F.Cu")
		(net "EXT_3.3V_PGOOD")
	)
	(segment
		(start 46.482 49.022)
		(end 46.80712 48.69688)
		(width 0.14732)
		(layer "F.Cu")
		(net "EXT_3.3V_PGOOD")
	)
	(segment
		(start 49.6189 48.6791)
		(end 50.038 48.26)
		(width 0.14732)
		(layer "F.Cu")
		(net "EXT_3.3V_PGOOD")
	)
	(segment
		(start 49.53 48.6791)
		(end 49.6189 48.6791)
		(width 0.14732)
		(layer "F.Cu")
		(net "EXT_3.3V_PGOOD")
	)
	(segment
		(start 33.147 26.924229)
		(end 33.147 26.9748)
		(width 0.127)
		(layer "F.Cu")
		(net "EXT_3.3V_PGOOD")
	)
	(segment
		(start 49.53 49.6189)
		(end 49.53 48.6791)
		(width 0.14732)
		(layer "F.Cu")
		(net "EXT_3.3V_PGOOD")
	)
	(segment
		(start 33.027518 26.810538)
		(end 33.03331 26.810538)
		(width 0.127)
		(layer "F.Cu")
		(net "EXT_3.3V_PGOOD")
	)
	(segment
		(start 50.038 47.244)
		(end 49.403 46.482)
		(width 0.14732)
		(layer "F.Cu")
		(net "EXT_3.3V_PGOOD")
	)
	(segment
		(start 49.51222 48.69688)
		(end 48.006 48.69688)
		(width 0.14732)
		(layer "F.Cu")
		(net "EXT_3.3V_PGOOD")
	)
	(segment
		(start 33.439075 27.266875)
		(end 33.464475 27.266875)
		(width 0.127)
		(layer "F.Cu")
		(net "EXT_3.3V_PGOOD")
	)
	(segment
		(start 50.038 48.26)
		(end 50.038 47.244)
		(width 0.14732)
		(layer "F.Cu")
		(net "EXT_3.3V_PGOOD")
	)
	(via
		(at 46.482 49.022)
		(size 0.508)
		(drill 0.2667)
		(layers "F.Cu" "B.Cu")
		(net "EXT_3.3V_PGOOD")
	)
	(via
		(at 33.027518 26.810538)
		(size 0.4572)
		(drill 0.20574)
		(layers "F.Cu" "B.Cu")
		(net "EXT_3.3V_PGOOD")
	)
	(via
		(at 41.737001 27.542007)
		(size 0.4826)
		(drill 0.20574)
		(layers "F.Cu" "B.Cu")
		(net "EXT_3.3V_PGOOD")
	)
	(segment
		(start 39.375232 27.945232)
		(end 39.116 27.686)
		(width 0.12065)
		(layer "In2.Cu")
		(net "EXT_3.3V_PGOOD")
	)
	(segment
		(start 41.333776 27.945232)
		(end 39.375232 27.945232)
		(width 0.12065)
		(layer "In2.Cu")
		(net "EXT_3.3V_PGOOD")
	)
	(segment
		(start 38.310185 26.245185)
		(end 38.310185 26.233171)
		(width 0.12065)
		(layer "In2.Cu")
		(net "EXT_3.3V_PGOOD")
	)
	(segment
		(start 39.116 27.051)
		(end 38.310185 26.245185)
		(width 0.12065)
		(layer "In2.Cu")
		(net "EXT_3.3V_PGOOD")
	)
	(segment
		(start 38.039675 25.974675)
		(end 37.338 25.273)
		(width 0.12065)
		(layer "In2.Cu")
		(net "EXT_3.3V_PGOOD")
	)
	(segment
		(start 39.116 27.686)
		(end 39.116 27.051)
		(width 0.12065)
		(layer "In2.Cu")
		(net "EXT_3.3V_PGOOD")
	)
	(segment
		(start 38.051689 25.974675)
		(end 38.039675 25.974675)
		(width 0.12065)
		(layer "In2.Cu")
		(net "EXT_3.3V_PGOOD")
	)
	(segment
		(start 34.565057 25.273)
		(end 33.027518 26.810538)
		(width 0.12065)
		(layer "In2.Cu")
		(net "EXT_3.3V_PGOOD")
	)
	(segment
		(start 37.338 25.273)
		(end 34.565057 25.273)
		(width 0.12065)
		(layer "In2.Cu")
		(net "EXT_3.3V_PGOOD")
	)
	(segment
		(start 41.737001 27.542007)
		(end 41.333776 27.945232)
		(width 0.12065)
		(layer "In2.Cu")
		(net "EXT_3.3V_PGOOD")
	)
	(segment
		(start 38.310185 26.233171)
		(end 38.051689 25.974675)
		(width 0.12065)
		(layer "In2.Cu")
		(net "EXT_3.3V_PGOOD")
	)
	(segment
		(start 43.434 39.624)
		(end 42.672 38.862)
		(width 0.12065)
		(layer "In7.Cu")
		(net "EXT_3.3V_PGOOD")
	)
	(segment
		(start 45.974 48.514)
		(end 45.974 45.72)
		(width 0.12065)
		(layer "In7.Cu")
		(net "EXT_3.3V_PGOOD")
	)
	(segment
		(start 42.672 36.195)
		(end 42.164 35.687)
		(width 0.12065)
		(layer "In7.Cu")
		(net "EXT_3.3V_PGOOD")
	)
	(segment
		(start 45.974 45.72)
		(end 43.434 43.18)
		(width 0.12065)
		(layer "In7.Cu")
		(net "EXT_3.3V_PGOOD")
	)
	(segment
		(start 43.434 43.18)
		(end 43.434 39.624)
		(width 0.12065)
		(layer "In7.Cu")
		(net "EXT_3.3V_PGOOD")
	)
	(segment
		(start 42.164 35.687)
		(end 42.164 27.94)
		(width 0.12065)
		(layer "In7.Cu")
		(net "EXT_3.3V_PGOOD")
	)
	(segment
		(start 46.482 49.022)
		(end 45.974 48.514)
		(width 0.12065)
		(layer "In7.Cu")
		(net "EXT_3.3V_PGOOD")
	)
	(segment
		(start 42.164 27.94)
		(end 41.737001 27.542007)
		(width 0.12065)
		(layer "In7.Cu")
		(net "EXT_3.3V_PGOOD")
	)
	(segment
		(start 42.672 38.862)
		(end 42.672 36.195)
		(width 0.12065)
		(layer "In7.Cu")
		(net "EXT_3.3V_PGOOD")
	)
	(segment
		(start 35.128911 5.599989)
		(end 34.2646 5.599989)
		(width 0.2032)
		(layer "F.Cu")
		(net "EXT_3.3V")
	)
	(segment
		(start 28.4988 6.763309)
		(end 28.4988 6.7691)
		(width 0.2032)
		(layer "F.Cu")
		(net "EXT_3.3V")
	)
	(segment
		(start 5.7912 2.4892)
		(end 5.7912 2.6416)
		(width 0.508)
		(layer "F.Cu")
		(net "EXT_3.3V")
	)
	(segment
		(start 35.2044 29.845)
		(end 35.2044 29.058794)
		(width 0.127)
		(layer "F.Cu")
		(net "EXT_3.3V")
	)
	(segment
		(start 35.8648 3.715309)
		(end 36.0045 3.575609)
		(width 0.2032)
		(layer "F.Cu")
		(net "EXT_3.3V")
	)
	(segment
		(start 33.428508 26.612774)
		(end 33.428508 26.679957)
		(width 0.127)
		(layer "F.Cu")
		(net "EXT_3.3V")
	)
	(segment
		(start 27.7876 21.1074)
		(end 27.7876 21.59)
		(width 0.127)
		(layer "F.Cu")
		(net "EXT_3.3V")
	)
	(segment
		(start 35.052025 21.716975)
		(end 35.4584 21.3106)
		(width 0.127)
		(layer "F.Cu")
		(net "EXT_3.3V")
	)
	(segment
		(start 36.0045 3.575609)
		(end 36.0045 2.2225)
		(width 0.2032)
		(layer "F.Cu")
		(net "EXT_3.3V")
	)
	(segment
		(start 18.034 1.27)
		(end 18.034 2.794)
		(width 0.2032)
		(layer "F.Cu")
		(net "EXT_3.3V")
	)
	(segment
		(start 23.413009 36.6141)
		(end 24.13 36.6141)
		(width 0.2032)
		(layer "F.Cu")
		(net "EXT_3.3V")
	)
	(segment
		(start 21.925991 36.1061)
		(end 21.379891 36.6522)
		(width 0.2032)
		(layer "F.Cu")
		(net "EXT_3.3V")
	)
	(segment
		(start 1.7526 2.9464)
		(end 3.175 1.524)
		(width 0.508)
		(layer "F.Cu")
		(net "EXT_3.3V")
	)
	(segment
		(start 17.399 0.9779)
		(end 17.7419 0.9779)
		(width 0.2032)
		(layer "F.Cu")
		(net "EXT_3.3V")
	)
	(segment
		(start 33.746008 26.997457)
		(end 33.746008 27.048409)
		(width 0.127)
		(layer "F.Cu")
		(net "EXT_3.3V")
	)
	(segment
		(start 35.6489 1.8669)
		(end 34.29 1.8669)
		(width 0.2032)
		(layer "F.Cu")
		(net "EXT_3.3V")
	)
	(segment
		(start 32.690511 27.548408)
		(end 32.74601 27.548408)
		(width 0.127)
		(layer "F.Cu")
		(net "EXT_3.3V")
	)
	(segment
		(start 26.924 27.5844)
		(end 27.485391 27.048409)
		(width 0.14732)
		(layer "F.Cu")
		(net "EXT_3.3V")
	)
	(segment
		(start 29.360978 6.477)
		(end 28.7909 6.477)
		(width 0.2032)
		(layer "F.Cu")
		(net "EXT_3.3V")
	)
	(segment
		(start 3.302 33.7439)
		(end 3.302 33.02)
		(width 0.2032)
		(layer "F.Cu")
		(net "EXT_3.3V")
	)
	(segment
		(start 24.3078 33.143012)
		(end 25.015012 33.143012)
		(width 0.2032)
		(layer "F.Cu")
		(net "EXT_3.3V")
	)
	(segment
		(start 24.13 36.6141)
		(end 24.638 36.1061)
		(width 0.2032)
		(layer "F.Cu")
		(net "EXT_3.3V")
	)
	(segment
		(start 45.0469 53.1368)
		(end 44.196 52.2351)
		(width 0.2032)
		(layer "F.Cu")
		(net "EXT_3.3V")
	)
	(segment
		(start 25.5397 35.941)
		(end 24.8031 35.941)
		(width 0.2032)
		(layer "F.Cu")
		(net "EXT_3.3V")
	)
	(segment
		(start 22.86 36.1061)
		(end 22.905009 36.1061)
		(width 0.2032)
		(layer "F.Cu")
		(net "EXT_3.3V")
	)
	(segment
		(start 25.5397 36.7792)
		(end 25.4889 36.83)
		(width 0.254)
		(layer "F.Cu")
		(net "EXT_3.3V")
	)
	(segment
		(start 32.926934 26.1112)
		(end 33.428508 26.612774)
		(width 0.127)
		(layer "F.Cu")
		(net "EXT_3.3V")
	)
	(segment
		(start 29.796791 23.548391)
		(end 29.245992 23.548391)
		(width 0.14732)
		(layer "F.Cu")
		(net "EXT_3.3V")
	)
	(segment
		(start 28.6385 6.6294)
		(end 28.632709 6.6294)
		(width 0.2032)
		(layer "F.Cu")
		(net "EXT_3.3V")
	)
	(segment
		(start 36.0045 2.2225)
		(end 35.6489 1.8669)
		(width 0.2032)
		(layer "F.Cu")
		(net "EXT_3.3V")
	)
	(segment
		(start 16.51 0.9779)
		(end 17.399 0.9779)
		(width 0.2032)
		(layer "F.Cu")
		(net "EXT_3.3V")
	)
	(segment
		(start 35.00374 28.858134)
		(end 34.746006 28.6004)
		(width 0.14732)
		(layer "F.Cu")
		(net "EXT_3.3V")
	)
	(segment
		(start 21.379891 36.6522)
		(end 20.7391 36.6522)
		(width 0.2032)
		(layer "F.Cu")
		(net "EXT_3.3V")
	)
	(segment
		(start 1.7526 3.9116)
		(end 1.7526 2.9464)
		(width 0.508)
		(layer "F.Cu")
		(net "EXT_3.3V")
	)
	(segment
		(start 17.78 24.8031)
		(end 17.7419 24.8031)
		(width 0.2032)
		(layer "F.Cu")
		(net "EXT_3.3V")
	)
	(segment
		(start 35.5219 4.064)
		(end 35.8648 3.7211)
		(width 0.2032)
		(layer "F.Cu")
		(net "EXT_3.3V")
	)
	(segment
		(start 29.983989 7.100011)
		(end 29.360978 6.477)
		(width 0.2032)
		(layer "F.Cu")
		(net "EXT_3.3V")
	)
	(segment
		(start 18.034 2.794)
		(end 18.542 3.302)
		(width 0.2032)
		(layer "F.Cu")
		(net "EXT_3.3V")
	)
	(segment
		(start 25.5397 35.941)
		(end 25.5397 36.7792)
		(width 0.254)
		(layer "F.Cu")
		(net "EXT_3.3V")
	)
	(segment
		(start 28.632709 6.6294)
		(end 28.4988 6.763309)
		(width 0.2032)
		(layer "F.Cu")
		(net "EXT_3.3V")
	)
	(segment
		(start 21.971 36.1061)
		(end 21.925991 36.1061)
		(width 0.2032)
		(layer "F.Cu")
		(net "EXT_3.3V")
	)
	(segment
		(start 34.746006 22.048394)
		(end 35.052025 21.742375)
		(width 0.127)
		(layer "F.Cu")
		(net "EXT_3.3V")
	)
	(segment
		(start 35.5219 5.207)
		(end 35.128911 5.599989)
		(width 0.2032)
		(layer "F.Cu")
		(net "EXT_3.3V")
	)
	(segment
		(start 19.777888 3.686988)
		(end 19.558 3.4163)
		(width 0.254)
		(layer "F.Cu")
		(net "EXT_3.3V")
	)
	(segment
		(start 32.639 26.1112)
		(end 32.926934 26.1112)
		(width 0.127)
		(layer "F.Cu")
		(net "EXT_3.3V")
	)
	(segment
		(start 20.6502 3.686988)
		(end 19.777888 3.686988)
		(width 0.254)
		(layer "F.Cu")
		(net "EXT_3.3V")
	)
	(segment
		(start 33.428508 26.679957)
		(end 33.746008 26.997457)
		(width 0.127)
		(layer "F.Cu")
		(net "EXT_3.3V")
	)
	(segment
		(start 36.2458 22.9362)
		(end 35.358197 22.9362)
		(width 0.127)
		(layer "F.Cu")
		(net "EXT_3.3V")
	)
	(segment
		(start 35.052025 21.742375)
		(end 35.052025 21.716975)
		(width 0.127)
		(layer "F.Cu")
		(net "EXT_3.3V")
	)
	(segment
		(start 1.524 33.7439)
		(end 1.524 33.02)
		(width 0.2032)
		(layer "F.Cu")
		(net "EXT_3.3V")
	)
	(segment
		(start 32.1564 27.00975)
		(end 32.563511 27.416862)
		(width 0.127)
		(layer "F.Cu")
		(net "EXT_3.3V")
	)
	(segment
		(start 22.86 36.1061)
		(end 21.971 36.1061)
		(width 0.2032)
		(layer "F.Cu")
		(net "EXT_3.3V")
	)
	(segment
		(start 32.563511 27.416862)
		(end 32.563511 27.421408)
		(width 0.127)
		(layer "F.Cu")
		(net "EXT_3.3V")
	)
	(segment
		(start 17.7419 0.9779)
		(end 18.034 1.27)
		(width 0.2032)
		(layer "F.Cu")
		(net "EXT_3.3V")
	)
	(segment
		(start 25.4635 33.5915)
		(end 25.4635 34.163)
		(width 0.2032)
		(layer "F.Cu")
		(net "EXT_3.3V")
	)
	(segment
		(start 2.413 33.7439)
		(end 2.413 33.02)
		(width 0.2032)
		(layer "F.Cu")
		(net "EXT_3.3V")
	)
	(segment
		(start 34.746006 28.6004)
		(end 34.746006 28.548406)
		(width 0.14732)
		(layer "F.Cu")
		(net "EXT_3.3V")
	)
	(segment
		(start 35.358197 22.9362)
		(end 34.746006 23.548391)
		(width 0.127)
		(layer "F.Cu")
		(net "EXT_3.3V")
	)
	(segment
		(start 27.7876 21.59)
		(end 28.245994 22.048394)
		(width 0.127)
		(layer "F.Cu")
		(net "EXT_3.3V")
	)
	(segment
		(start 17.145 25.4)
		(end 15.9893 25.4)
		(width 0.2032)
		(layer "F.Cu")
		(net "EXT_3.3V")
	)
	(segment
		(start 22.905009 36.1061)
		(end 23.413009 36.6141)
		(width 0.2032)
		(layer "F.Cu")
		(net "EXT_3.3V")
	)
	(segment
		(start 35.8648 3.7211)
		(end 35.8648 3.715309)
		(width 0.2032)
		(layer "F.Cu")
		(net "EXT_3.3V")
	)
	(segment
		(start 18.6563 3.4163)
		(end 18.542 3.302)
		(width 0.254)
		(layer "F.Cu")
		(net "EXT_3.3V")
	)
	(segment
		(start 31.0134 7.100011)
		(end 29.983989 7.100011)
		(width 0.2032)
		(layer "F.Cu")
		(net "EXT_3.3V")
	)
	(segment
		(start 20.7391 36.6522)
		(end 20.193 36.1061)
		(width 0.2032)
		(layer "F.Cu")
		(net "EXT_3.3V")
	)
	(segment
		(start 15.9893 25.4)
		(end 15.3924 25.9969)
		(width 0.2032)
		(layer "F.Cu")
		(net "EXT_3.3V")
	)
	(segment
		(start 25.015012 33.143012)
		(end 25.4635 33.5915)
		(width 0.2032)
		(layer "F.Cu")
		(net "EXT_3.3V")
	)
	(segment
		(start 46.77664 48.04664)
		(end 46.482 47.752)
		(width 0.2032)
		(layer "F.Cu")
		(net "EXT_3.3V")
	)
	(segment
		(start 24.8031 35.941)
		(end 24.638 36.1061)
		(width 0.2032)
		(layer "F.Cu")
		(net "EXT_3.3V")
	)
	(segment
		(start 27.485391 27.048409)
		(end 28.245994 27.048409)
		(width 0.14732)
		(layer "F.Cu")
		(net "EXT_3.3V")
	)
	(segment
		(start 35.2044 29.058794)
		(end 35.00374 28.858134)
		(width 0.127)
		(layer "F.Cu")
		(net "EXT_3.3V")
	)
	(segment
		(start 25.5397 35.052)
		(end 25.5397 34.2392)
		(width 0.254)
		(layer "F.Cu")
		(net "EXT_3.3V")
	)
	(segment
		(start 32.1564 26.8986)
		(end 32.1564 27.00975)
		(width 0.127)
		(layer "F.Cu")
		(net "EXT_3.3V")
	)
	(segment
		(start 4.826 1.524)
		(end 5.7912 2.4892)
		(width 0.508)
		(layer "F.Cu")
		(net "EXT_3.3V")
	)
	(segment
		(start 29.8704 23.6474)
		(end 29.796791 23.548391)
		(width 0.14732)
		(layer "F.Cu")
		(net "EXT_3.3V")
	)
	(segment
		(start 25.5397 35.941)
		(end 25.5397 35.052)
		(width 0.2032)
		(layer "F.Cu")
		(net "EXT_3.3V")
	)
	(segment
		(start 28.4988 6.7691)
		(end 28.1559 7.112)
		(width 0.2032)
		(layer "F.Cu")
		(net "EXT_3.3V")
	)
	(segment
		(start 25.5397 34.2392)
		(end 25.4635 34.163)
		(width 0.254)
		(layer "F.Cu")
		(net "EXT_3.3V")
	)
	(segment
		(start 35.5219 5.207)
		(end 35.5219 4.064)
		(width 0.508)
		(layer "F.Cu")
		(net "EXT_3.3V")
	)
	(segment
		(start 28.7909 6.477)
		(end 28.6385 6.6294)
		(width 0.2032)
		(layer "F.Cu")
		(net "EXT_3.3V")
	)
	(segment
		(start 32.563511 27.421408)
		(end 32.690511 27.548408)
		(width 0.127)
		(layer "F.Cu")
		(net "EXT_3.3V")
	)
	(segment
		(start 17.7419 24.8031)
		(end 17.145 25.4)
		(width 0.2032)
		(layer "F.Cu")
		(net "EXT_3.3V")
	)
	(segment
		(start 48.006 48.04664)
		(end 46.77664 48.04664)
		(width 0.2032)
		(layer "F.Cu")
		(net "EXT_3.3V")
	)
	(segment
		(start 3.175 1.524)
		(end 4.826 1.524)
		(width 0.508)
		(layer "F.Cu")
		(net "EXT_3.3V")
	)
	(segment
		(start 19.558 3.4163)
		(end 18.6563 3.4163)
		(width 0.254)
		(layer "F.Cu")
		(net "EXT_3.3V")
	)
	(via
		(at 18.5801 29.464)
		(size 0.508)
		(drill 0.25654)
		(layers "F.Cu" "B.Cu")
		(net "EXT_3.3V")
	)
	(via
		(at 36.2458 22.9362)
		(size 0.4572)
		(drill 0.20574)
		(layers "F.Cu" "B.Cu")
		(net "EXT_3.3V")
	)
	(via
		(at 32.1564 26.8986)
		(size 0.4572)
		(drill 0.20574)
		(layers "F.Cu" "B.Cu")
		(net "EXT_3.3V")
	)
	(via
		(at 35.5219 5.207)
		(size 0.508)
		(drill 0.25654)
		(layers "F.Cu" "B.Cu")
		(net "EXT_3.3V")
	)
	(via
		(at 2.667 19.05)
		(size 0.762)
		(drill 0.381)
		(layers "F.Cu" "B.Cu")
		(net "EXT_3.3V")
	)
	(via
		(at 1.7526 3.9116)
		(size 0.508)
		(drill 0.254)
		(layers "F.Cu" "B.Cu")
		(net "EXT_3.3V")
	)
	(via
		(at 28.6004 29.7434)
		(size 0.4572)
		(drill 0.20574)
		(layers "F.Cu" "B.Cu")
		(net "EXT_3.3V")
	)
	(via
		(at 35.4584 21.3106)
		(size 0.4572)
		(drill 0.20574)
		(layers "F.Cu" "B.Cu")
		(net "EXT_3.3V")
	)
	(via
		(at 26.924 27.5844)
		(size 0.4572)
		(drill 0.20574)
		(layers "F.Cu" "B.Cu")
		(net "EXT_3.3V")
	)
	(via
		(at 18.542 3.302)
		(size 0.508)
		(drill 0.254)
		(layers "F.Cu" "B.Cu")
		(net "EXT_3.3V")
	)
	(via
		(at 0.6604 9.4361)
		(size 0.508)
		(drill 0.25654)
		(layers "F.Cu" "B.Cu")
		(net "EXT_3.3V")
	)
	(via
		(at 0.635 19.05)
		(size 0.762)
		(drill 0.381)
		(layers "F.Cu" "B.Cu")
		(net "EXT_3.3V")
	)
	(via
		(at 3.302 33.02)
		(size 0.508)
		(drill 0.254)
		(layers "F.Cu" "B.Cu")
		(net "EXT_3.3V")
	)
	(via
		(at 25.4635 34.163)
		(size 0.508)
		(drill 0.25654)
		(layers "F.Cu" "B.Cu")
		(net "EXT_3.3V")
	)
	(via
		(at 1.524 33.02)
		(size 0.508)
		(drill 0.254)
		(layers "F.Cu" "B.Cu")
		(net "EXT_3.3V")
	)
	(via
		(at 10.16 45.9105)
		(size 0.508)
		(drill 0.25654)
		(layers "F.Cu" "B.Cu")
		(net "EXT_3.3V")
	)
	(via
		(at 29.983989 7.100011)
		(size 0.508)
		(drill 0.254)
		(layers "F.Cu" "B.Cu")
		(net "EXT_3.3V")
	)
	(via
		(at 15.3924 27.2669)
		(size 0.508)
		(drill 0.254)
		(layers "F.Cu" "B.Cu")
		(net "EXT_3.3V")
	)
	(via
		(at 46.482 47.752)
		(size 0.508)
		(drill 0.254)
		(layers "F.Cu" "B.Cu")
		(net "EXT_3.3V")
	)
	(via
		(at 27.7876 21.1074)
		(size 0.4572)
		(drill 0.20574)
		(layers "F.Cu" "B.Cu")
		(net "EXT_3.3V")
	)
	(via
		(at 29.8704 23.6474)
		(size 0.4572)
		(drill 0.20574)
		(layers "F.Cu" "B.Cu")
		(net "EXT_3.3V")
	)
	(via
		(at 0.6096 17.8689)
		(size 0.508)
		(drill 0.25654)
		(layers "F.Cu" "B.Cu")
		(net "EXT_3.3V")
	)
	(via
		(at 26.67 48.9585)
		(size 0.508)
		(drill 0.25654)
		(layers "F.Cu" "B.Cu")
		(net "EXT_3.3V")
	)
	(via
		(at 64.77 46.1137)
		(size 0.508)
		(drill 0.25654)
		(layers "F.Cu" "B.Cu")
		(net "EXT_3.3V")
	)
	(via
		(at 2.413 33.02)
		(size 0.508)
		(drill 0.2667)
		(layers "F.Cu" "B.Cu")
		(net "EXT_3.3V")
	)
	(via
		(at 20.955 28.8925)
		(size 0.508)
		(drill 0.25654)
		(layers "F.Cu" "B.Cu")
		(net "EXT_3.3V")
	)
	(via
		(at 44.196 52.2351)
		(size 0.508)
		(drill 0.25654)
		(layers "F.Cu" "B.Cu")
		(net "EXT_3.3V")
	)
	(via
		(at 35.2044 29.845)
		(size 0.4572)
		(drill 0.20574)
		(layers "F.Cu" "B.Cu")
		(net "EXT_3.3V")
	)
	(via
		(at 81.407 37.5031)
		(size 0.508)
		(drill 0.25654)
		(layers "F.Cu" "B.Cu")
		(net "EXT_3.3V")
	)
	(via
		(at 7.7724 13.2969)
		(size 0.508)
		(drill 0.254)
		(layers "F.Cu" "B.Cu")
		(net "EXT_3.3V")
	)
	(via
		(at 15.3924 25.9969)
		(size 0.508)
		(drill 0.254)
		(layers "F.Cu" "B.Cu")
		(net "EXT_3.3V")
	)
	(via
		(at 32.639 26.1112)
		(size 0.4572)
		(drill 0.20574)
		(layers "F.Cu" "B.Cu")
		(net "EXT_3.3V")
	)
	(segment
		(start 24.08428 34.8234)
		(end 24.784583 34.8234)
		(width 0.3048)
		(layer "B.Cu")
		(net "EXT_3.3V")
	)
	(segment
		(start 1.385748 17.8689)
		(end 1.398448 17.8816)
		(width 0.2032)
		(layer "B.Cu")
		(net "EXT_3.3V")
	)
	(segment
		(start 23.451109 4.699)
		(end 23.1521 4.699)
		(width 0.2032)
		(layer "B.Cu")
		(net "EXT_3.3V")
	)
	(segment
		(start 28.7401 30.48)
		(end 28.7401 29.8831)
		(width 0.254)
		(layer "B.Cu")
		(net "EXT_3.3V")
	)
	(segment
		(start 31.6103 27.686)
		(end 31.6611 27.686)
		(width 0.254)
		(layer "B.Cu")
		(net "EXT_3.3V")
	)
	(segment
		(start 29.845 23.5966)
		(end 29.8704 23.6474)
		(width 0.254)
		(layer "B.Cu")
		(net "EXT_3.3V")
	)
	(segment
		(start 35.4584 21.3106)
		(end 35.0774 21.3106)
		(width 0.254)
		(layer "B.Cu")
		(net "EXT_3.3V")
	)
	(segment
		(start 16.0274 26.6319)
		(end 15.3924 25.9969)
		(width 0.254)
		(layer "B.Cu")
		(net "EXT_3.3V")
	)
	(segment
		(start 35.0774 21.3106)
		(end 34.544 21.844)
		(width 0.254)
		(layer "B.Cu")
		(net "EXT_3.3V")
	)
	(segment
		(start 20.32 3.0861)
		(end 22.352 3.2131)
		(width 0.254)
		(layer "B.Cu")
		(net "EXT_3.3V")
	)
	(segment
		(start 1.916252 17.8689)
		(end 2.667 17.8689)
		(width 0.2032)
		(layer "B.Cu")
		(net "EXT_3.3V")
	)
	(segment
		(start 34.0741 21.844)
		(end 34.0741 22.733)
		(width 0.254)
		(layer "B.Cu")
		(net "EXT_3.3V")
	)
	(segment
		(start 30.988 7.0739)
		(end 30.0101 7.0739)
		(width 0.508)
		(layer "B.Cu")
		(net "EXT_3.3V")
	)
	(segment
		(start 1.398448 17.8816)
		(end 1.903552 17.8816)
		(width 0.2032)
		(layer "B.Cu")
		(net "EXT_3.3V")
	)
	(segment
		(start 28.829 22.7711)
		(end 28.956 22.6441)
		(width 0.2032)
		(layer "B.Cu")
		(net "EXT_3.3V")
	)
	(segment
		(start 24.638 33.0581)
		(end 24.8031 33.0581)
		(width 0.508)
		(layer "B.Cu")
		(net "EXT_3.3V")
	)
	(segment
		(start 36.3093 20.447)
		(end 36.3093 20.8407)
		(width 0.254)
		(layer "B.Cu")
		(net "EXT_3.3V")
	)
	(segment
		(start 22.352 4.365168)
		(end 22.5806 4.593768)
		(width 0.254)
		(layer "B.Cu")
		(net "EXT_3.3V")
	)
	(segment
		(start 23.1521 4.699)
		(end 22.8981 4.953)
		(width 0.2032)
		(layer "B.Cu")
		(net "EXT_3.3V")
	)
	(segment
		(start 7.7724 13.2969)
		(end 7.1628 13.2969)
		(width 0.254)
		(layer "B.Cu")
		(net "EXT_3.3V")
	)
	(segment
		(start 30.0101 6.3119)
		(end 30.0101 7.0739)
		(width 0.508)
		(layer "B.Cu")
		(net "EXT_3.3V")
	)
	(segment
		(start 25.4635 33.7185)
		(end 25.4635 34.163)
		(width 0.508)
		(layer "B.Cu")
		(net "EXT_3.3V")
	)
	(segment
		(start 32.1564 27.1907)
		(end 32.1564 26.8986)
		(width 0.254)
		(layer "B.Cu")
		(net "EXT_3.3V")
	)
	(segment
		(start 30.988 6.0071)
		(end 30.3149 6.0071)
		(width 0.508)
		(layer "B.Cu")
		(net "EXT_3.3V")
	)
	(segment
		(start 34.671 22.987)
		(end 34.417 22.733)
		(width 0.254)
		(layer "B.Cu")
		(net "EXT_3.3V")
	)
	(segment
		(start 1.903552 17.8816)
		(end 1.916252 17.8689)
		(width 0.2032)
		(layer "B.Cu")
		(net "EXT_3.3V")
	)
	(segment
		(start 24.936983 34.671)
		(end 24.9555 34.671)
		(width 0.3048)
		(layer "B.Cu")
		(net "EXT_3.3V")
	)
	(segment
		(start 36.3093 20.8407)
		(end 35.8394 21.3106)
		(width 0.254)
		(layer "B.Cu")
		(net "EXT_3.3V")
	)
	(segment
		(start 16.0274 27.9019)
		(end 15.3924 27.2669)
		(width 0.254)
		(layer "B.Cu")
		(net "EXT_3.3V")
	)
	(segment
		(start 34.544 21.844)
		(end 34.0741 21.844)
		(width 0.254)
		(layer "B.Cu")
		(net "EXT_3.3V")
	)
	(segment
		(start 27.7876 19.3675)
		(end 27.7876 21.1074)
		(width 0.254)
		(layer "B.Cu")
		(net "EXT_3.3V")
	)
	(segment
		(start 2.032 9.4361)
		(end 0.6604 9.4361)
		(width 0.2032)
		(layer "B.Cu")
		(net "EXT_3.3V")
	)
	(segment
		(start 22.352 3.2131)
		(end 24.13 3.2131)
		(width 0.254)
		(layer "B.Cu")
		(net "EXT_3.3V")
	)
	(segment
		(start 18.5801 29.464)
		(end 18.923 29.9339)
		(width 0.3048)
		(layer "B.Cu")
		(net "EXT_3.3V")
	)
	(segment
		(start 28.7401 29.8831)
		(end 28.6004 29.7434)
		(width 0.254)
		(layer "B.Cu")
		(net "EXT_3.3V")
	)
	(segment
		(start 30.3149 6.0071)
		(end 30.0101 6.3119)
		(width 0.508)
		(layer "B.Cu")
		(net "EXT_3.3V")
	)
	(segment
		(start 34.71672 23.622)
		(end 34.671 23.57628)
		(width 0.254)
		(layer "B.Cu")
		(net "EXT_3.3V")
	)
	(segment
		(start 23.876 4.2799)
		(end 23.5331 4.6228)
		(width 0.2032)
		(layer "B.Cu")
		(net "EXT_3.3V")
	)
	(segment
		(start 31.6611 27.686)
		(end 32.1564 27.1907)
		(width 0.254)
		(layer "B.Cu")
		(net "EXT_3.3V")
	)
	(segment
		(start 22.5806 4.593768)
		(end 22.5806 4.6355)
		(width 0.254)
		(layer "B.Cu")
		(net "EXT_3.3V")
	)
	(segment
		(start 30.0101 7.0739)
		(end 29.983989 7.100011)
		(width 0.508)
		(layer "B.Cu")
		(net "EXT_3.3V")
	)
	(segment
		(start 0.6604 19.0246)
		(end 0.635 19.05)
		(width 0.254)
		(layer "B.Cu")
		(net "EXT_3.3V")
	)
	(segment
		(start 27.7241 19.2024)
		(end 27.7876 19.3675)
		(width 0.254)
		(layer "B.Cu")
		(net "EXT_3.3V")
	)
	(segment
		(start 33.7439 26.162)
		(end 32.6898 26.162)
		(width 0.2032)
		(layer "B.Cu")
		(net "EXT_3.3V")
	)
	(segment
		(start 23.9141 34.7091)
		(end 23.96998 34.7091)
		(width 0.3048)
		(layer "B.Cu")
		(net "EXT_3.3V")
	)
	(segment
		(start 23.5331 4.6228)
		(end 23.527309 4.6228)
		(width 0.2032)
		(layer "B.Cu")
		(net "EXT_3.3V")
	)
	(segment
		(start 24.784583 34.8234)
		(end 24.936983 34.671)
		(width 0.3048)
		(layer "B.Cu")
		(net "EXT_3.3V")
	)
	(segment
		(start 7.1628 13.2969)
		(end 7.112 13.2461)
		(width 0.254)
		(layer "B.Cu")
		(net "EXT_3.3V")
	)
	(segment
		(start 22.352 3.2131)
		(end 22.352 4.365168)
		(width 0.254)
		(layer "B.Cu")
		(net "EXT_3.3V")
	)
	(segment
		(start 28.956 22.6441)
		(end 29.845 22.6441)
		(width 0.2032)
		(layer "B.Cu")
		(net "EXT_3.3V")
	)
	(segment
		(start 22.5806 4.6355)
		(end 22.8981 4.953)
		(width 0.254)
		(layer "B.Cu")
		(net "EXT_3.3V")
	)
	(segment
		(start 19.431 34.29)
		(end 23.495 34.29)
		(width 0.3048)
		(layer "B.Cu")
		(net "EXT_3.3V")
	)
	(segment
		(start 11.43 43.8785)
		(end 11.43 45.085)
		(width 0.254)
		(layer "B.Cu")
		(net "EXT_3.3V")
	)
	(segment
		(start 24.9555 34.671)
		(end 25.4635 34.163)
		(width 0.3048)
		(layer "B.Cu")
		(net "EXT_3.3V")
	)
	(segment
		(start 18.923 29.9339)
		(end 18.923 33.782)
		(width 0.3048)
		(layer "B.Cu")
		(net "EXT_3.3V")
	)
	(segment
		(start 10.668 45.847)
		(end 10.2235 45.847)
		(width 0.254)
		(layer "B.Cu")
		(net "EXT_3.3V")
	)
	(segment
		(start 35.8394 21.3106)
		(end 35.4584 21.3106)
		(width 0.254)
		(layer "B.Cu")
		(net "EXT_3.3V")
	)
	(segment
		(start 20.32 3.0861)
		(end 18.7579 3.0861)
		(width 0.254)
		(layer "B.Cu")
		(net "EXT_3.3V")
	)
	(segment
		(start 32.6898 26.162)
		(end 32.639 26.1112)
		(width 0.2032)
		(layer "B.Cu")
		(net "EXT_3.3V")
	)
	(segment
		(start 7.112 13.2461)
		(end 5.334 13.2461)
		(width 0.254)
		(layer "B.Cu")
		(net "EXT_3.3V")
	)
	(segment
		(start 23.495 34.29)
		(end 23.9141 34.7091)
		(width 0.3048)
		(layer "B.Cu")
		(net "EXT_3.3V")
	)
	(segment
		(start 24.8031 33.0581)
		(end 25.4635 33.7185)
		(width 0.508)
		(layer "B.Cu")
		(net "EXT_3.3V")
	)
	(segment
		(start 23.527309 4.6228)
		(end 23.451109 4.699)
		(width 0.2032)
		(layer "B.Cu")
		(net "EXT_3.3V")
	)
	(segment
		(start 34.417 22.733)
		(end 34.0741 22.733)
		(width 0.254)
		(layer "B.Cu")
		(net "EXT_3.3V")
	)
	(segment
		(start 34.8869 29.083)
		(end 34.8869 29.5275)
		(width 0.254)
		(layer "B.Cu")
		(net "EXT_3.3V")
	)
	(segment
		(start 34.8869 29.5275)
		(end 35.2044 29.845)
		(width 0.254)
		(layer "B.Cu")
		(net "EXT_3.3V")
	)
	(segment
		(start 0.6096 17.8689)
		(end 1.385748 17.8689)
		(width 0.2032)
		(layer "B.Cu")
		(net "EXT_3.3V")
	)
	(segment
		(start 18.923 33.782)
		(end 19.431 34.29)
		(width 0.3048)
		(layer "B.Cu")
		(net "EXT_3.3V")
	)
	(segment
		(start 4.2418 13.465988)
		(end 5.114112 13.465988)
		(width 0.254)
		(layer "B.Cu")
		(net "EXT_3.3V")
	)
	(segment
		(start 29.845 22.6441)
		(end 29.845 23.5966)
		(width 0.254)
		(layer "B.Cu")
		(net "EXT_3.3V")
	)
	(segment
		(start 0.6096 17.8689)
		(end 0.6604 19.0246)
		(width 0.254)
		(layer "B.Cu")
		(net "EXT_3.3V")
	)
	(segment
		(start 2.667 17.8689)
		(end 2.667 19.05)
		(width 0.254)
		(layer "B.Cu")
		(net "EXT_3.3V")
	)
	(segment
		(start 18.7579 3.0861)
		(end 18.542 3.302)
		(width 0.254)
		(layer "B.Cu")
		(net "EXT_3.3V")
	)
	(segment
		(start 23.96998 34.7091)
		(end 24.08428 34.8234)
		(width 0.3048)
		(layer "B.Cu")
		(net "EXT_3.3V")
	)
	(segment
		(start 5.114112 13.465988)
		(end 5.334 13.2461)
		(width 0.254)
		(layer "B.Cu")
		(net "EXT_3.3V")
	)
	(segment
		(start 11.43 45.085)
		(end 10.668 45.847)
		(width 0.254)
		(layer "B.Cu")
		(net "EXT_3.3V")
	)
	(segment
		(start 10.2235 45.847)
		(end 10.16 45.9105)
		(width 0.254)
		(layer "B.Cu")
		(net "EXT_3.3V")
	)
	(segment
		(start 34.671 23.57628)
		(end 34.671 22.987)
		(width 0.254)
		(layer "B.Cu")
		(net "EXT_3.3V")
	)
	(segment
		(start 29.8704 23.6474)
		(end 29.745991 23.497591)
		(width 0.127)
		(layer "In1.Cu")
		(net "EXT_3.3V")
	)
	(segment
		(start 30.24599 28.09781)
		(end 28.6004 29.7434)
		(width 0.12065)
		(layer "In1.Cu")
		(net "EXT_3.3V")
	)
	(segment
		(start 29.745991 23.497591)
		(end 29.745991 22.548393)
		(width 0.127)
		(layer "In1.Cu")
		(net "EXT_3.3V")
	)
	(segment
		(start 30.24599 28.048407)
		(end 30.24599 28.09781)
		(width 0.127)
		(layer "In1.Cu")
		(net "EXT_3.3V")
	)
	(segment
		(start 19.106896 38.410896)
		(end 17.653 38.410896)
		(width 0.508)
		(layer "F.Cu")
		(net "DDR_1.8V")
	)
	(segment
		(start 20.955 47.498)
		(end 20.955 42.926)
		(width 0.508)
		(layer "F.Cu")
		(net "DDR_1.8V")
	)
	(segment
		(start 20.955 42.926)
		(end 20.9042 42.9641)
		(width 0.508)
		(layer "F.Cu")
		(net "DDR_1.8V")
	)
	(segment
		(start 20.8153 42.926)
		(end 20.9042 42.9641)
		(width 0.508)
		(layer "F.Cu")
		(net "DDR_1.8V")
	)
	(segment
		(start 17.653 38.410896)
		(end 16.6497 38.410896)
		(width 0.2032)
		(layer "F.Cu")
		(net "DDR_1.8V")
	)
	(via
		(at 21.209 39.624)
		(size 0.508)
		(drill 0.254)
		(layers "F.Cu" "B.Cu")
		(net "DDR_1.8V")
	)
	(via
		(at 19.304 38.862)
		(size 0.508)
		(drill 0.254)
		(layers "F.Cu" "B.Cu")
		(net "DDR_1.8V")
	)
	(via
		(at 53.737002 22.541992)
		(size 0.4826)
		(drill 0.20574)
		(layers "F.Cu" "B.Cu")
		(net "DDR_1.8V")
	)
	(via
		(at 21.209 40.894)
		(size 0.508)
		(drill 0.25654)
		(layers "F.Cu" "B.Cu")
		(net "DDR_1.8V")
	)
	(segment
		(start 54.737 21.541994)
		(end 53.737002 22.541992)
		(width 0.508)
		(layer "B.Cu")
		(net "DDR_1.8V")
	)
	(segment
		(start 80.250995 26.390905)
		(end 80.250995 25.813004)
		(width 0.14732)
		(layer "F.Cu")
		(net "DDR0_32A_WE_L")
	)
	(segment
		(start 80.137 26.5049)
		(end 80.250995 26.390905)
		(width 0.14732)
		(layer "F.Cu")
		(net "DDR0_32A_WE_L")
	)
	(segment
		(start 65.737003 11.541989)
		(end 65.237004 12.041988)
		(width 0.233528)
		(layer "F.Cu")
		(net "DDR0_32A_WE_L")
	)
	(via
		(at 65.737003 11.541989)
		(size 0.4826)
		(drill 0.25654)
		(layers "F.Cu" "B.Cu")
		(net "DDR0_32A_WE_L")
	)
	(segment
		(start 79.850996 3.099003)
		(end 80.250995 2.699004)
		(width 0.14732)
		(layer "B.Cu")
		(net "DDR0_32A_WE_L")
	)
	(segment
		(start 79.850996 26.213003)
		(end 80.250995 25.813004)
		(width 0.14732)
		(layer "B.Cu")
		(net "DDR0_32A_WE_L")
	)
	(segment
		(start 79.850996 14.656003)
		(end 80.250995 14.256004)
		(width 0.14732)
		(layer "B.Cu")
		(net "DDR0_32A_WE_L")
	)
	(segment
		(start 80.250995 14.256004)
		(end 79.856711 13.86172)
		(width 0.12065)
		(layer "In3.Cu")
		(net "DDR0_32A_WE_L")
	)
	(segment
		(start 79.856711 3.093288)
		(end 80.250995 2.699004)
		(width 0.12065)
		(layer "In3.Cu")
		(net "DDR0_32A_WE_L")
	)
	(segment
		(start 80.250995 25.813004)
		(end 79.856711 25.41872)
		(width 0.12065)
		(layer "In3.Cu")
		(net "DDR0_32A_WE_L")
	)
	(segment
		(start 79.856711 14.650288)
		(end 80.250995 14.256004)
		(width 0.12065)
		(layer "In3.Cu")
		(net "DDR0_32A_WE_L")
	)
	(segment
		(start 79.856711 25.41872)
		(end 79.856711 14.650288)
		(width 0.12065)
		(layer "In3.Cu")
		(net "DDR0_32A_WE_L")
	)
	(segment
		(start 79.856711 13.86172)
		(end 79.856711 3.093288)
		(width 0.12065)
		(layer "In3.Cu")
		(net "DDR0_32A_WE_L")
	)
	(segment
		(start 80.645279 -0.211455)
		(end 80.645279 0.898982)
		(width 0.188697)
		(layer "In6.Cu")
		(net "DDR0_32A_WE_L")
	)
	(segment
		(start 80.645279 1.397)
		(end 80.645279 2.062353)
		(width 0.12065)
		(layer "In6.Cu")
		(net "DDR0_32A_WE_L")
	)
	(segment
		(start 80.060775 -0.2286)
		(end 80.238575 -0.4064)
		(width 0.188697)
		(layer "In6.Cu")
		(net "DDR0_32A_WE_L")
	)
	(segment
		(start 68.7832 0.3048)
		(end 68.6562 0.1778)
		(width 0.188697)
		(layer "In6.Cu")
		(net "DDR0_32A_WE_L")
	)
	(segment
		(start 65.737003 11.541989)
		(end 66.260015 12.065)
		(width 0.188697)
		(layer "In6.Cu")
		(net "DDR0_32A_WE_L")
	)
	(segment
		(start 79.933775 1.3716)
		(end 80.060775 1.2446)
		(width 0.188697)
		(layer "In6.Cu")
		(net "DDR0_32A_WE_L")
	)
	(segment
		(start 67.3608 1.524)
		(end 67.3608 1.0414)
		(width 0.188697)
		(layer "In6.Cu")
		(net "DDR0_32A_WE_L")
	)
	(segment
		(start 80.622673 0.921588)
		(end 80.622673 1.276426)
		(width 0.188697)
		(layer "In6.Cu")
		(net "DDR0_32A_WE_L")
	)
	(segment
		(start 68.0212 1.7018)
		(end 67.5386 1.7018)
		(width 0.188697)
		(layer "In6.Cu")
		(net "DDR0_32A_WE_L")
	)
	(segment
		(start 80.645279 1.299032)
		(end 80.645279 1.397)
		(width 0.188697)
		(layer "In6.Cu")
		(net "DDR0_32A_WE_L")
	)
	(segment
		(start 67.8942 12.065)
		(end 68.199 11.7602)
		(width 0.188697)
		(layer "In6.Cu")
		(net "DDR0_32A_WE_L")
	)
	(segment
		(start 80.250995 2.456637)
		(end 80.250995 2.699004)
		(width 0.12065)
		(layer "In6.Cu")
		(net "DDR0_32A_WE_L")
	)
	(segment
		(start 66.2178 -0.4064)
		(end 79.2734 -0.4064)
		(width 0.188697)
		(layer "In6.Cu")
		(net "DDR0_32A_WE_L")
	)
	(segment
		(start 80.450334 -0.4064)
		(end 80.645279 -0.211455)
		(width 0.188697)
		(layer "In6.Cu")
		(net "DDR0_32A_WE_L")
	)
	(segment
		(start 67.3608 1.0414)
		(end 67.4878 0.9144)
		(width 0.188697)
		(layer "In6.Cu")
		(net "DDR0_32A_WE_L")
	)
	(segment
		(start 66.260015 12.065)
		(end 67.8942 12.065)
		(width 0.188697)
		(layer "In6.Cu")
		(net "DDR0_32A_WE_L")
	)
	(segment
		(start 66.0654 -0.00254)
		(end 66.0654 -0.254)
		(width 0.188697)
		(layer "In6.Cu")
		(net "DDR0_32A_WE_L")
	)
	(segment
		(start 66.24574 0.1778)
		(end 66.0654 -0.00254)
		(width 0.188697)
		(layer "In6.Cu")
		(net "DDR0_32A_WE_L")
	)
	(segment
		(start 80.645279 0.898982)
		(end 80.622673 0.921588)
		(width 0.188697)
		(layer "In6.Cu")
		(net "DDR0_32A_WE_L")
	)
	(segment
		(start 79.2734 -0.4064)
		(end 79.4258 -0.254)
		(width 0.188697)
		(layer "In6.Cu")
		(net "DDR0_32A_WE_L")
	)
	(segment
		(start 68.199 11.7602)
		(end 68.199 1.8796)
		(width 0.188697)
		(layer "In6.Cu")
		(net "DDR0_32A_WE_L")
	)
	(segment
		(start 67.5386 1.7018)
		(end 67.3608 1.524)
		(width 0.188697)
		(layer "In6.Cu")
		(net "DDR0_32A_WE_L")
	)
	(segment
		(start 79.4258 -0.254)
		(end 79.4258 1.1684)
		(width 0.188697)
		(layer "In6.Cu")
		(net "DDR0_32A_WE_L")
	)
	(segment
		(start 68.58 0.9144)
		(end 68.7832 0.7112)
		(width 0.188697)
		(layer "In6.Cu")
		(net "DDR0_32A_WE_L")
	)
	(segment
		(start 80.622673 1.276426)
		(end 80.645279 1.299032)
		(width 0.188697)
		(layer "In6.Cu")
		(net "DDR0_32A_WE_L")
	)
	(segment
		(start 68.6562 0.1778)
		(end 66.24574 0.1778)
		(width 0.188697)
		(layer "In6.Cu")
		(net "DDR0_32A_WE_L")
	)
	(segment
		(start 80.238575 -0.4064)
		(end 80.450334 -0.4064)
		(width 0.188697)
		(layer "In6.Cu")
		(net "DDR0_32A_WE_L")
	)
	(segment
		(start 67.4878 0.9144)
		(end 68.58 0.9144)
		(width 0.188697)
		(layer "In6.Cu")
		(net "DDR0_32A_WE_L")
	)
	(segment
		(start 80.060775 1.2446)
		(end 80.060775 -0.2286)
		(width 0.188697)
		(layer "In6.Cu")
		(net "DDR0_32A_WE_L")
	)
	(segment
		(start 79.629 1.3716)
		(end 79.933775 1.3716)
		(width 0.188697)
		(layer "In6.Cu")
		(net "DDR0_32A_WE_L")
	)
	(segment
		(start 66.0654 -0.254)
		(end 66.2178 -0.4064)
		(width 0.188697)
		(layer "In6.Cu")
		(net "DDR0_32A_WE_L")
	)
	(segment
		(start 79.4258 1.1684)
		(end 79.629 1.3716)
		(width 0.188697)
		(layer "In6.Cu")
		(net "DDR0_32A_WE_L")
	)
	(segment
		(start 68.199 1.8796)
		(end 68.0212 1.7018)
		(width 0.188697)
		(layer "In6.Cu")
		(net "DDR0_32A_WE_L")
	)
	(segment
		(start 80.645279 2.062353)
		(end 80.250995 2.456637)
		(width 0.12065)
		(layer "In6.Cu")
		(net "DDR0_32A_WE_L")
	)
	(segment
		(start 68.7832 0.7112)
		(end 68.7832 0.3048)
		(width 0.188697)
		(layer "In6.Cu")
		(net "DDR0_32A_WE_L")
	)
	(segment
		(start 84.582 11.176)
		(end 78.613 11.176)
		(width 0.254)
		(layer "F.Cu")
		(net "DDR0_32A_VREF1B")
	)
	(segment
		(start 75.438 11.1379)
		(end 76.327 11.1379)
		(width 0.254)
		(layer "F.Cu")
		(net "DDR0_32A_VREF1B")
	)
	(segment
		(start 77.597 23.622)
		(end 77.597 21.082)
		(width 0.254)
		(layer "F.Cu")
		(net "DDR0_32A_VREF1B")
	)
	(segment
		(start 76.251003 22.593173)
		(end 75.8571 23.020096)
		(width 0.254)
		(layer "F.Cu")
		(net "DDR0_32A_VREF1B")
	)
	(segment
		(start 77.051002 24.213007)
		(end 76.708 23.870006)
		(width 0.254)
		(layer "F.Cu")
		(net "DDR0_32A_VREF1B")
	)
	(segment
		(start 76.581 23.495)
		(end 75.8571 23.495)
		(width 0.254)
		(layer "F.Cu")
		(net "DDR0_32A_VREF1B")
	)
	(segment
		(start 77.851 20.828)
		(end 77.851 17.78)
		(width 0.254)
		(layer "F.Cu")
		(net "DDR0_32A_VREF1B")
	)
	(segment
		(start 81.456987 17.145)
		(end 84.582 17.145)
		(width 0.254)
		(layer "F.Cu")
		(net "DDR0_32A_VREF1B")
	)
	(segment
		(start 80.645 17.145)
		(end 81.050994 17.550994)
		(width 0.254)
		(layer "F.Cu")
		(net "DDR0_32A_VREF1B")
	)
	(segment
		(start 76.708 11.1379)
		(end 76.327 11.1379)
		(width 0.254)
		(layer "F.Cu")
		(net "DDR0_32A_VREF1B")
	)
	(segment
		(start 78.613 11.176)
		(end 78.4479 11.3411)
		(width 0.254)
		(layer "F.Cu")
		(net "DDR0_32A_VREF1B")
	)
	(segment
		(start 78.4479 11.3411)
		(end 77.597 11.3411)
		(width 0.254)
		(layer "F.Cu")
		(net "DDR0_32A_VREF1B")
	)
	(segment
		(start 85.217 16.51)
		(end 85.217 11.811)
		(width 0.254)
		(layer "F.Cu")
		(net "DDR0_32A_VREF1B")
	)
	(segment
		(start 77.597 12.110009)
		(end 77.051002 12.656007)
		(width 0.254)
		(layer "F.Cu")
		(net "DDR0_32A_VREF1B")
	)
	(segment
		(start 77.597 21.082)
		(end 77.851 20.828)
		(width 0.254)
		(layer "F.Cu")
		(net "DDR0_32A_VREF1B")
	)
	(segment
		(start 77.718107 24.213007)
		(end 77.051002 24.213007)
		(width 0.254)
		(layer "F.Cu")
		(net "DDR0_32A_VREF1B")
	)
	(segment
		(start 77.597 11.3411)
		(end 76.9112 11.3411)
		(width 0.254)
		(layer "F.Cu")
		(net "DDR0_32A_VREF1B")
	)
	(segment
		(start 78.486 17.145)
		(end 79.375 17.145)
		(width 0.254)
		(layer "F.Cu")
		(net "DDR0_32A_VREF1B")
	)
	(segment
		(start 85.217 11.811)
		(end 84.582 11.176)
		(width 0.254)
		(layer "F.Cu")
		(net "DDR0_32A_VREF1B")
	)
	(segment
		(start 77.851 17.78)
		(end 78.486 17.145)
		(width 0.254)
		(layer "F.Cu")
		(net "DDR0_32A_VREF1B")
	)
	(segment
		(start 76.708 23.870006)
		(end 76.708 23.622)
		(width 0.254)
		(layer "F.Cu")
		(net "DDR0_32A_VREF1B")
	)
	(segment
		(start 76.708 23.622)
		(end 76.581 23.495)
		(width 0.254)
		(layer "F.Cu")
		(net "DDR0_32A_VREF1B")
	)
	(segment
		(start 79.375 17.145)
		(end 80.645 17.145)
		(width 0.254)
		(layer "F.Cu")
		(net "DDR0_32A_VREF1B")
	)
	(segment
		(start 77.851 23.876)
		(end 77.597 23.622)
		(width 0.254)
		(layer "F.Cu")
		(net "DDR0_32A_VREF1B")
	)
	(segment
		(start 84.582 17.145)
		(end 85.217 16.51)
		(width 0.254)
		(layer "F.Cu")
		(net "DDR0_32A_VREF1B")
	)
	(segment
		(start 77.851 24.3459)
		(end 77.851 23.876)
		(width 0.254)
		(layer "F.Cu")
		(net "DDR0_32A_VREF1B")
	)
	(segment
		(start 76.9112 11.3411)
		(end 76.708 11.1379)
		(width 0.254)
		(layer "F.Cu")
		(net "DDR0_32A_VREF1B")
	)
	(segment
		(start 75.8571 23.020096)
		(end 75.8571 23.495)
		(width 0.254)
		(layer "F.Cu")
		(net "DDR0_32A_VREF1B")
	)
	(segment
		(start 77.851 24.3459)
		(end 77.718107 24.213007)
		(width 0.254)
		(layer "F.Cu")
		(net "DDR0_32A_VREF1B")
	)
	(segment
		(start 77.597 11.3411)
		(end 77.597 12.110009)
		(width 0.254)
		(layer "F.Cu")
		(net "DDR0_32A_VREF1B")
	)
	(segment
		(start 81.050994 17.550994)
		(end 81.050994 19.055994)
		(width 0.254)
		(layer "F.Cu")
		(net "DDR0_32A_VREF1B")
	)
	(segment
		(start 81.050994 17.550994)
		(end 81.456987 17.145)
		(width 0.254)
		(layer "F.Cu")
		(net "DDR0_32A_VREF1B")
	)
	(via
		(at 81.050994 30.612994)
		(size 0.4572)
		(drill 0.20574)
		(layers "F.Cu" "B.Cu")
		(net "DDR0_32A_VREF1B")
	)
	(via
		(at 77.051002 24.213007)
		(size 0.4572)
		(drill 0.20574)
		(layers "F.Cu" "B.Cu")
		(net "DDR0_32A_VREF1B")
	)
	(via
		(at 81.050994 19.055994)
		(size 0.4572)
		(drill 0.20574)
		(layers "F.Cu" "B.Cu")
		(net "DDR0_32A_VREF1B")
	)
	(via
		(at 79.375 17.145)
		(size 0.762)
		(drill 0.381)
		(layers "F.Cu" "B.Cu")
		(net "DDR0_32A_VREF1B")
	)
	(via
		(at 77.051002 12.656007)
		(size 0.4572)
		(drill 0.20574)
		(layers "F.Cu" "B.Cu")
		(net "DDR0_32A_VREF1B")
	)
	(segment
		(start 77.451001 13.056006)
		(end 77.051002 12.656007)
		(width 0.254)
		(layer "B.Cu")
		(net "DDR0_32A_VREF1B")
	)
	(segment
		(start 80.650994 30.212995)
		(end 81.050994 30.612994)
		(width 0.254)
		(layer "B.Cu")
		(net "DDR0_32A_VREF1B")
	)
	(segment
		(start 80.650994 18.655995)
		(end 81.050994 19.055994)
		(width 0.254)
		(layer "B.Cu")
		(net "DDR0_32A_VREF1B")
	)
	(segment
		(start 77.451001 24.613006)
		(end 77.051002 24.213007)
		(width 0.254)
		(layer "B.Cu")
		(net "DDR0_32A_VREF1B")
	)
	(segment
		(start 80.391 27.305)
		(end 81.050994 27.964994)
		(width 0.2032)
		(layer "In7.Cu")
		(net "DDR0_32A_VREF1B")
	)
	(segment
		(start 77.851 26.543)
		(end 78.613 27.305)
		(width 0.2032)
		(layer "In7.Cu")
		(net "DDR0_32A_VREF1B")
	)
	(segment
		(start 77.851 25.013006)
		(end 77.851 26.543)
		(width 0.2032)
		(layer "In7.Cu")
		(net "DDR0_32A_VREF1B")
	)
	(segment
		(start 77.051002 24.213007)
		(end 77.851 25.013006)
		(width 0.2032)
		(layer "In7.Cu")
		(net "DDR0_32A_VREF1B")
	)
	(segment
		(start 78.613 27.305)
		(end 80.391 27.305)
		(width 0.2032)
		(layer "In7.Cu")
		(net "DDR0_32A_VREF1B")
	)
	(segment
		(start 81.050994 27.964994)
		(end 81.050994 30.612994)
		(width 0.2032)
		(layer "In7.Cu")
		(net "DDR0_32A_VREF1B")
	)
	(segment
		(start 79.4131 3.7211)
		(end 79.4131 4.191)
		(width 0.254)
		(layer "F.Cu")
		(net "DDR0_32A_VREF0B")
	)
	(segment
		(start 78.359 3.429)
		(end 79.121 3.429)
		(width 0.254)
		(layer "F.Cu")
		(net "DDR0_32A_VREF0B")
	)
	(segment
		(start 77.6351 4.1529)
		(end 78.359 3.429)
		(width 0.254)
		(layer "F.Cu")
		(net "DDR0_32A_VREF0B")
	)
	(segment
		(start 79.121 3.429)
		(end 79.4131 3.7211)
		(width 0.254)
		(layer "F.Cu")
		(net "DDR0_32A_VREF0B")
	)
	(segment
		(start 80.772 4.445)
		(end 80.518 4.191)
		(width 0.254)
		(layer "F.Cu")
		(net "DDR0_32A_VREF0B")
	)
	(segment
		(start 80.772 4.953)
		(end 80.772 4.445)
		(width 0.254)
		(layer "F.Cu")
		(net "DDR0_32A_VREF0B")
	)
	(segment
		(start 81.050994 5.231994)
		(end 80.772 4.953)
		(width 0.254)
		(layer "F.Cu")
		(net "DDR0_32A_VREF0B")
	)
	(segment
		(start 77.1779 4.191)
		(end 77.216 4.1529)
		(width 0.254)
		(layer "F.Cu")
		(net "DDR0_32A_VREF0B")
	)
	(segment
		(start 77.597 3.048)
		(end 77.216 3.429)
		(width 0.254)
		(layer "F.Cu")
		(net "DDR0_32A_VREF0B")
	)
	(segment
		(start 77.216 4.1529)
		(end 77.6351 4.1529)
		(width 0.254)
		(layer "F.Cu")
		(net "DDR0_32A_VREF0B")
	)
	(segment
		(start 81.050994 7.498994)
		(end 81.050994 5.231994)
		(width 0.254)
		(layer "F.Cu")
		(net "DDR0_32A_VREF0B")
	)
	(segment
		(start 77.051002 1.099007)
		(end 77.597 1.645006)
		(width 0.254)
		(layer "F.Cu")
		(net "DDR0_32A_VREF0B")
	)
	(segment
		(start 80.518 4.191)
		(end 79.4131 4.191)
		(width 0.254)
		(layer "F.Cu")
		(net "DDR0_32A_VREF0B")
	)
	(segment
		(start 76.2381 4.318)
		(end 77.1779 4.191)
		(width 0.254)
		(layer "F.Cu")
		(net "DDR0_32A_VREF0B")
	)
	(segment
		(start 77.216 3.429)
		(end 77.216 4.1529)
		(width 0.254)
		(layer "F.Cu")
		(net "DDR0_32A_VREF0B")
	)
	(segment
		(start 77.597 1.645006)
		(end 77.597 3.048)
		(width 0.254)
		(layer "F.Cu")
		(net "DDR0_32A_VREF0B")
	)
	(via
		(at 80.772 4.953)
		(size 0.762)
		(drill 0.381)
		(layers "F.Cu" "B.Cu")
		(net "DDR0_32A_VREF0B")
	)
	(via
		(at 81.050994 7.498994)
		(size 0.4572)
		(drill 0.20574)
		(layers "F.Cu" "B.Cu")
		(net "DDR0_32A_VREF0B")
	)
	(via
		(at 77.051002 1.099007)
		(size 0.4572)
		(drill 0.20574)
		(layers "F.Cu" "B.Cu")
		(net "DDR0_32A_VREF0B")
	)
	(segment
		(start 80.650994 7.098995)
		(end 81.050994 7.498994)
		(width 0.254)
		(layer "B.Cu")
		(net "DDR0_32A_VREF0B")
	)
	(segment
		(start 77.451001 1.499006)
		(end 77.051002 1.099007)
		(width 0.254)
		(layer "B.Cu")
		(net "DDR0_32A_VREF0B")
	)
	(segment
		(start 61.737011 16.542004)
		(end 61.237012 17.042003)
		(width 0.254)
		(layer "F.Cu")
		(net "DDR0_32A_VREF")
	)
	(segment
		(start 61.737011 15.542006)
		(end 61.237012 16.042005)
		(width 0.254)
		(layer "F.Cu")
		(net "DDR0_32A_VREF")
	)
	(via
		(at 61.737011 15.542006)
		(size 0.4826)
		(drill 0.20574)
		(layers "F.Cu" "B.Cu")
		(net "DDR0_32A_VREF")
	)
	(via
		(at 61.737011 16.542004)
		(size 0.4826)
		(drill 0.20574)
		(layers "F.Cu" "B.Cu")
		(net "DDR0_32A_VREF")
	)
	(via
		(at 64.516 15.542006)
		(size 0.762)
		(drill 0.381)
		(layers "F.Cu" "B.Cu")
		(net "DDR0_32A_VREF")
	)
	(segment
		(start 62.23701 16.042005)
		(end 61.737011 15.542006)
		(width 0.254)
		(layer "B.Cu")
		(net "DDR0_32A_VREF")
	)
	(segment
		(start 62.23701 15.042007)
		(end 62.237112 15.042007)
		(width 0.254)
		(layer "B.Cu")
		(net "DDR0_32A_VREF")
	)
	(segment
		(start 62.23701 16.042005)
		(end 61.737011 16.542004)
		(width 0.254)
		(layer "B.Cu")
		(net "DDR0_32A_VREF")
	)
	(segment
		(start 64.516 15.542006)
		(end 63.302134 15.042134)
		(width 0.254)
		(layer "B.Cu")
		(net "DDR0_32A_VREF")
	)
	(segment
		(start 61.737011 15.542006)
		(end 62.23701 15.042007)
		(width 0.254)
		(layer "B.Cu")
		(net "DDR0_32A_VREF")
	)
	(segment
		(start 63.236983 15.042134)
		(end 62.237239 15.042134)
		(width 0.254)
		(layer "B.Cu")
		(net "DDR0_32A_VREF")
	)
	(segment
		(start 62.237112 16.042005)
		(end 62.23701 16.042005)
		(width 0.254)
		(layer "B.Cu")
		(net "DDR0_32A_VREF")
	)
	(segment
		(start 63.302134 15.042134)
		(end 63.236983 15.042134)
		(width 0.254)
		(layer "B.Cu")
		(net "DDR0_32A_VREF")
	)
	(segment
		(start 62.237239 15.042134)
		(end 62.237112 15.042007)
		(width 0.254)
		(layer "B.Cu")
		(net "DDR0_32A_VREF")
	)
	(segment
		(start 78.650998 26.212902)
		(end 78.650998 25.813004)
		(width 0.14732)
		(layer "F.Cu")
		(net "DDR0_32A_RAS_L")
	)
	(segment
		(start 64.737005 12.542012)
		(end 64.237006 13.042011)
		(width 0.233528)
		(layer "F.Cu")
		(net "DDR0_32A_RAS_L")
	)
	(segment
		(start 78.359 26.5049)
		(end 78.650998 26.212902)
		(width 0.14732)
		(layer "F.Cu")
		(net "DDR0_32A_RAS_L")
	)
	(via
		(at 64.737005 12.542012)
		(size 0.4826)
		(drill 0.20574)
		(layers "F.Cu" "B.Cu")
		(net "DDR0_32A_RAS_L")
	)
	(segment
		(start 78.250999 3.099003)
		(end 78.650998 2.699004)
		(width 0.14732)
		(layer "B.Cu")
		(net "DDR0_32A_RAS_L")
	)
	(segment
		(start 78.250999 26.213003)
		(end 78.650998 25.813004)
		(width 0.14732)
		(layer "B.Cu")
		(net "DDR0_32A_RAS_L")
	)
	(segment
		(start 78.250999 14.656003)
		(end 78.650998 14.256004)
		(width 0.14732)
		(layer "B.Cu")
		(net "DDR0_32A_RAS_L")
	)
	(segment
		(start 75.321211 0.635)
		(end 75.085219 0.635)
		(width 0.188697)
		(layer "In6.Cu")
		(net "DDR0_32A_RAS_L")
	)
	(segment
		(start 73.53239 -0.014503)
		(end 72.048903 -0.014503)
		(width 0.188697)
		(layer "In6.Cu")
		(net "DDR0_32A_RAS_L")
	)
	(segment
		(start 73.699243 0.468147)
		(end 73.699243 0.152349)
		(width 0.188697)
		(layer "In6.Cu")
		(net "DDR0_32A_RAS_L")
	)
	(segment
		(start 71.172553 3.730168)
		(end 71.178014 3.724707)
		(width 0.188697)
		(layer "In6.Cu")
		(net "DDR0_32A_RAS_L")
	)
	(segment
		(start 73.699243 0.152349)
		(end 73.53239 -0.014503)
		(width 0.188697)
		(layer "In6.Cu")
		(net "DDR0_32A_RAS_L")
	)
	(segment
		(start 71.178014 3.724707)
		(end 71.178014 3.359302)
		(width 0.188697)
		(layer "In6.Cu")
		(net "DDR0_32A_RAS_L")
	)
	(segment
		(start 74.435792 -0.014503)
		(end 74.26894 0.152349)
		(width 0.188697)
		(layer "In6.Cu")
		(net "DDR0_32A_RAS_L")
	)
	(segment
		(start 78.256714 25.41872)
		(end 78.256714 14.650288)
		(width 0.12065)
		(layer "In6.Cu")
		(net "DDR0_32A_RAS_L")
	)
	(segment
		(start 74.26894 0.152349)
		(end 74.26894 0.468147)
		(width 0.188697)
		(layer "In6.Cu")
		(net "DDR0_32A_RAS_L")
	)
	(segment
		(start 76.220853 0.341147)
		(end 76.220853 0.152349)
		(width 0.188697)
		(layer "In6.Cu")
		(net "DDR0_32A_RAS_L")
	)
	(segment
		(start 70.978497 -0.014503)
		(end 69.381903 -0.014503)
		(width 0.188697)
		(layer "In6.Cu")
		(net "DDR0_32A_RAS_L")
	)
	(segment
		(start 75.654916 -0.014503)
		(end 75.488063 0.152349)
		(width 0.188697)
		(layer "In6.Cu")
		(net "DDR0_32A_RAS_L")
	)
	(segment
		(start 78.650998 14.256004)
		(end 78.256714 13.86172)
		(width 0.12065)
		(layer "In6.Cu")
		(net "DDR0_32A_RAS_L")
	)
	(segment
		(start 73.866096 0.635)
		(end 73.699243 0.468147)
		(width 0.188697)
		(layer "In6.Cu")
		(net "DDR0_32A_RAS_L")
	)
	(segment
		(start 78.256714 3.531286)
		(end 78.650998 3.137002)
		(width 0.12065)
		(layer "In6.Cu")
		(net "DDR0_32A_RAS_L")
	)
	(segment
		(start 76.054001 -0.014503)
		(end 75.654916 -0.014503)
		(width 0.188697)
		(layer "In6.Cu")
		(net "DDR0_32A_RAS_L")
	)
	(segment
		(start 76.623697 0.508)
		(end 76.387706 0.508)
		(width 0.188697)
		(layer "In6.Cu")
		(net "DDR0_32A_RAS_L")
	)
	(segment
		(start 74.751514 -0.014503)
		(end 74.435792 -0.014503)
		(width 0.188697)
		(layer "In6.Cu")
		(net "DDR0_32A_RAS_L")
	)
	(segment
		(start 77.597 2.521204)
		(end 77.597 0.224993)
		(width 0.188697)
		(layer "In6.Cu")
		(net "DDR0_32A_RAS_L")
	)
	(segment
		(start 74.918367 0.152349)
		(end 74.751514 -0.014503)
		(width 0.188697)
		(layer "In6.Cu")
		(net "DDR0_32A_RAS_L")
	)
	(segment
		(start 75.488063 0.468147)
		(end 75.321211 0.635)
		(width 0.188697)
		(layer "In6.Cu")
		(net "DDR0_32A_RAS_L")
	)
	(segment
		(start 71.822691 0.211709)
		(end 71.822691 4.320489)
		(width 0.188697)
		(layer "In6.Cu")
		(net "DDR0_32A_RAS_L")
	)
	(segment
		(start 75.085219 0.635)
		(end 74.918367 0.468147)
		(width 0.188697)
		(layer "In6.Cu")
		(net "DDR0_32A_RAS_L")
	)
	(segment
		(start 77.7748 2.699004)
		(end 77.597 2.521204)
		(width 0.188697)
		(layer "In6.Cu")
		(net "DDR0_32A_RAS_L")
	)
	(segment
		(start 71.633994 4.509186)
		(end 71.311897 4.509186)
		(width 0.188697)
		(layer "In6.Cu")
		(net "DDR0_32A_RAS_L")
	)
	(segment
		(start 69.381903 -0.014503)
		(end 69.215 0.1524)
		(width 0.188697)
		(layer "In6.Cu")
		(net "DDR0_32A_RAS_L")
	)
	(segment
		(start 71.172553 3.353841)
		(end 71.172553 0.179553)
		(width 0.188697)
		(layer "In6.Cu")
		(net "DDR0_32A_RAS_L")
	)
	(segment
		(start 78.256714 13.86172)
		(end 78.256714 3.531286)
		(width 0.12065)
		(layer "In6.Cu")
		(net "DDR0_32A_RAS_L")
	)
	(segment
		(start 69.215 0.1524)
		(end 69.215 12.7762)
		(width 0.188697)
		(layer "In6.Cu")
		(net "DDR0_32A_RAS_L")
	)
	(segment
		(start 76.220853 0.152349)
		(end 76.054001 -0.014503)
		(width 0.188697)
		(layer "In6.Cu")
		(net "DDR0_32A_RAS_L")
	)
	(segment
		(start 71.311897 4.509186)
		(end 71.172553 4.369841)
		(width 0.188697)
		(layer "In6.Cu")
		(net "DDR0_32A_RAS_L")
	)
	(segment
		(start 78.650998 3.137002)
		(end 78.650998 2.699004)
		(width 0.12065)
		(layer "In6.Cu")
		(net "DDR0_32A_RAS_L")
	)
	(segment
		(start 76.387706 0.508)
		(end 76.220853 0.341147)
		(width 0.188697)
		(layer "In6.Cu")
		(net "DDR0_32A_RAS_L")
	)
	(segment
		(start 76.79055 0.152349)
		(end 76.79055 0.341147)
		(width 0.188697)
		(layer "In6.Cu")
		(net "DDR0_32A_RAS_L")
	)
	(segment
		(start 68.9102 13.081)
		(end 65.275993 13.081)
		(width 0.188697)
		(layer "In6.Cu")
		(net "DDR0_32A_RAS_L")
	)
	(segment
		(start 72.048903 -0.014503)
		(end 71.822691 0.211709)
		(width 0.188697)
		(layer "In6.Cu")
		(net "DDR0_32A_RAS_L")
	)
	(segment
		(start 78.256714 14.650288)
		(end 78.650998 14.256004)
		(width 0.12065)
		(layer "In6.Cu")
		(net "DDR0_32A_RAS_L")
	)
	(segment
		(start 74.26894 0.468147)
		(end 74.102087 0.635)
		(width 0.188697)
		(layer "In6.Cu")
		(net "DDR0_32A_RAS_L")
	)
	(segment
		(start 74.102087 0.635)
		(end 73.866096 0.635)
		(width 0.188697)
		(layer "In6.Cu")
		(net "DDR0_32A_RAS_L")
	)
	(segment
		(start 74.918367 0.468147)
		(end 74.918367 0.152349)
		(width 0.188697)
		(layer "In6.Cu")
		(net "DDR0_32A_RAS_L")
	)
	(segment
		(start 71.178014 3.359302)
		(end 71.172553 3.353841)
		(width 0.188697)
		(layer "In6.Cu")
		(net "DDR0_32A_RAS_L")
	)
	(segment
		(start 71.172553 0.179553)
		(end 70.978497 -0.014503)
		(width 0.188697)
		(layer "In6.Cu")
		(net "DDR0_32A_RAS_L")
	)
	(segment
		(start 76.79055 0.341147)
		(end 76.623697 0.508)
		(width 0.188697)
		(layer "In6.Cu")
		(net "DDR0_32A_RAS_L")
	)
	(segment
		(start 69.215 12.7762)
		(end 68.9102 13.081)
		(width 0.188697)
		(layer "In6.Cu")
		(net "DDR0_32A_RAS_L")
	)
	(segment
		(start 75.488063 0.152349)
		(end 75.488063 0.468147)
		(width 0.188697)
		(layer "In6.Cu")
		(net "DDR0_32A_RAS_L")
	)
	(segment
		(start 71.822691 4.320489)
		(end 71.633994 4.509186)
		(width 0.188697)
		(layer "In6.Cu")
		(net "DDR0_32A_RAS_L")
	)
	(segment
		(start 77.357503 -0.014503)
		(end 76.957403 -0.014503)
		(width 0.188697)
		(layer "In6.Cu")
		(net "DDR0_32A_RAS_L")
	)
	(segment
		(start 76.957403 -0.014503)
		(end 76.79055 0.152349)
		(width 0.188697)
		(layer "In6.Cu")
		(net "DDR0_32A_RAS_L")
	)
	(segment
		(start 78.650998 2.699004)
		(end 77.7748 2.699004)
		(width 0.188697)
		(layer "In6.Cu")
		(net "DDR0_32A_RAS_L")
	)
	(segment
		(start 71.172553 4.369841)
		(end 71.172553 3.730168)
		(width 0.188697)
		(layer "In6.Cu")
		(net "DDR0_32A_RAS_L")
	)
	(segment
		(start 78.650998 25.813004)
		(end 78.256714 25.41872)
		(width 0.12065)
		(layer "In6.Cu")
		(net "DDR0_32A_RAS_L")
	)
	(segment
		(start 77.597 0.224993)
		(end 77.357503 -0.014503)
		(width 0.188697)
		(layer "In6.Cu")
		(net "DDR0_32A_RAS_L")
	)
	(segment
		(start 65.275993 13.081)
		(end 64.737005 12.542012)
		(width 0.188697)
		(layer "In6.Cu")
		(net "DDR0_32A_RAS_L")
	)
	(segment
		(start 78.3082 23.4061)
		(end 78.486 24.048009)
		(width 0.14732)
		(layer "F.Cu")
		(net "DDR0_32A_ODT0")
	)
	(segment
		(start 78.486 24.048009)
		(end 78.650998 24.213007)
		(width 0.14732)
		(layer "F.Cu")
		(net "DDR0_32A_ODT0")
	)
	(segment
		(start 64.737005 13.54201)
		(end 64.237006 14.042009)
		(width 0.233528)
		(layer "F.Cu")
		(net "DDR0_32A_ODT0")
	)
	(via
		(at 78.650998 1.099007)
		(size 0.4572)
		(drill 0.20574)
		(layers "F.Cu" "B.Cu")
		(net "DDR0_32A_ODT0")
	)
	(via
		(at 64.737005 13.54201)
		(size 0.4826)
		(drill 0.20574)
		(layers "F.Cu" "B.Cu")
		(net "DDR0_32A_ODT0")
	)
	(via
		(at 78.650998 24.213007)
		(size 0.4572)
		(drill 0.20574)
		(layers "F.Cu" "B.Cu")
		(net "DDR0_32A_ODT0")
	)
	(via
		(at 78.650998 12.656007)
		(size 0.762)
		(drill 0.20574)
		(layers "F.Cu" "B.Cu")
		(net "DDR0_32A_ODT0")
	)
	(segment
		(start 79.050998 13.056006)
		(end 78.650998 12.656007)
		(width 0.14732)
		(layer "B.Cu")
		(net "DDR0_32A_ODT0")
	)
	(segment
		(start 79.050998 1.499006)
		(end 78.650998 1.099007)
		(width 0.14732)
		(layer "B.Cu")
		(net "DDR0_32A_ODT0")
	)
	(segment
		(start 79.050998 24.613006)
		(end 78.650998 24.213007)
		(width 0.14732)
		(layer "B.Cu")
		(net "DDR0_32A_ODT0")
	)
	(segment
		(start 64.9478 1.697355)
		(end 64.9478 4.062197)
		(width 0.188697)
		(layer "In2.Cu")
		(net "DDR0_32A_ODT0")
	)
	(segment
		(start 74.803 0.090322)
		(end 74.803 -0.598322)
		(width 0.188697)
		(layer "In2.Cu")
		(net "DDR0_32A_ODT0")
	)
	(segment
		(start 72.947759 -0.750722)
		(end 72.947759 0.090322)
		(width 0.188697)
		(layer "In2.Cu")
		(net "DDR0_32A_ODT0")
	)
	(segment
		(start 74.966678 0.254)
		(end 74.803 0.090322)
		(width 0.188697)
		(layer "In2.Cu")
		(net "DDR0_32A_ODT0")
	)
	(segment
		(start 64.9478 4.062197)
		(end 65.299742 4.414139)
		(width 0.188697)
		(layer "In2.Cu")
		(net "DDR0_32A_ODT0")
	)
	(segment
		(start 76.133452 0.254)
		(end 74.966678 0.254)
		(width 0.188697)
		(layer "In2.Cu")
		(net "DDR0_32A_ODT0")
	)
	(segment
		(start 67.918559 -0.750722)
		(end 67.765778 -0.903503)
		(width 0.188697)
		(layer "In2.Cu")
		(net "DDR0_32A_ODT0")
	)
	(segment
		(start 70.712559 0.090322)
		(end 70.548881 0.254)
		(width 0.188697)
		(layer "In2.Cu")
		(net "DDR0_32A_ODT0")
	)
	(segment
		(start 70.153759 -0.750722)
		(end 70.000978 -0.903503)
		(width 0.188697)
		(layer "In2.Cu")
		(net "DDR0_32A_ODT0")
	)
	(segment
		(start 65.405 5.8674)
		(end 65.659 6.1214)
		(width 0.188697)
		(layer "In2.Cu")
		(net "DDR0_32A_ODT0")
	)
	(segment
		(start 71.271359 -0.750722)
		(end 71.118578 -0.903503)
		(width 0.188697)
		(layer "In2.Cu")
		(net "DDR0_32A_ODT0")
	)
	(segment
		(start 73.10054 -0.903503)
		(end 72.947759 -0.750722)
		(width 0.188697)
		(layer "In2.Cu")
		(net "DDR0_32A_ODT0")
	)
	(segment
		(start 71.666481 0.254)
		(end 71.435036 0.254)
		(width 0.188697)
		(layer "In2.Cu")
		(net "DDR0_32A_ODT0")
	)
	(segment
		(start 74.803 -0.598322)
		(end 74.639322 -0.762)
		(width 0.188697)
		(layer "In2.Cu")
		(net "DDR0_32A_ODT0")
	)
	(segment
		(start 65.237004 13.042011)
		(end 64.737005 13.54201)
		(width 0.188697)
		(layer "In2.Cu")
		(net "DDR0_32A_ODT0")
	)
	(segment
		(start 72.947759 0.090322)
		(end 72.784081 0.254)
		(width 0.188697)
		(layer "In2.Cu")
		(net "DDR0_32A_ODT0")
	)
	(segment
		(start 72.236178 -0.903503)
		(end 71.98294 -0.903503)
		(width 0.188697)
		(layer "In2.Cu")
		(net "DDR0_32A_ODT0")
	)
	(segment
		(start 70.153759 0.090322)
		(end 70.153759 -0.750722)
		(width 0.188697)
		(layer "In2.Cu")
		(net "DDR0_32A_ODT0")
	)
	(segment
		(start 68.082236 0.253949)
		(end 67.918559 0.090272)
		(width 0.188697)
		(layer "In2.Cu")
		(net "DDR0_32A_ODT0")
	)
	(segment
		(start 72.784081 0.254)
		(end 72.552636 0.254)
		(width 0.188697)
		(layer "In2.Cu")
		(net "DDR0_32A_ODT0")
	)
	(segment
		(start 74.065359 -0.598322)
		(end 74.065359 0.090322)
		(width 0.188697)
		(layer "In2.Cu")
		(net "DDR0_32A_ODT0")
	)
	(segment
		(start 69.199836 0.254)
		(end 69.036159 0.090322)
		(width 0.188697)
		(layer "In2.Cu")
		(net "DDR0_32A_ODT0")
	)
	(segment
		(start 73.506559 0.090322)
		(end 73.506559 -0.750722)
		(width 0.188697)
		(layer "In2.Cu")
		(net "DDR0_32A_ODT0")
	)
	(segment
		(start 73.353778 -0.903503)
		(end 73.10054 -0.903503)
		(width 0.188697)
		(layer "In2.Cu")
		(net "DDR0_32A_ODT0")
	)
	(segment
		(start 71.118578 -0.903503)
		(end 70.86534 -0.903503)
		(width 0.188697)
		(layer "In2.Cu")
		(net "DDR0_32A_ODT0")
	)
	(segment
		(start 72.388959 -0.750722)
		(end 72.236178 -0.903503)
		(width 0.188697)
		(layer "In2.Cu")
		(net "DDR0_32A_ODT0")
	)
	(segment
		(start 70.712559 -0.750722)
		(end 70.712559 0.090322)
		(width 0.188697)
		(layer "In2.Cu")
		(net "DDR0_32A_ODT0")
	)
	(segment
		(start 69.74774 -0.903503)
		(end 69.594959 -0.750722)
		(width 0.188697)
		(layer "In2.Cu")
		(net "DDR0_32A_ODT0")
	)
	(segment
		(start 65.659 7.974736)
		(end 65.237004 8.396732)
		(width 0.188697)
		(layer "In2.Cu")
		(net "DDR0_32A_ODT0")
	)
	(segment
		(start 70.000978 -0.903503)
		(end 69.74774 -0.903503)
		(width 0.188697)
		(layer "In2.Cu")
		(net "DDR0_32A_ODT0")
	)
	(segment
		(start 73.901681 0.254)
		(end 73.670236 0.254)
		(width 0.188697)
		(layer "In2.Cu")
		(net "DDR0_32A_ODT0")
	)
	(segment
		(start 78.650998 1.099007)
		(end 77.847139 0.295148)
		(width 0.188697)
		(layer "In2.Cu")
		(net "DDR0_32A_ODT0")
	)
	(segment
		(start 69.594959 -0.750722)
		(end 69.594959 0.090322)
		(width 0.188697)
		(layer "In2.Cu")
		(net "DDR0_32A_ODT0")
	)
	(segment
		(start 65.237004 8.396732)
		(end 65.237004 13.042011)
		(width 0.188697)
		(layer "In2.Cu")
		(net "DDR0_32A_ODT0")
	)
	(segment
		(start 67.918559 0.090272)
		(end 67.918559 -0.750722)
		(width 0.188697)
		(layer "In2.Cu")
		(net "DDR0_32A_ODT0")
	)
	(segment
		(start 68.477359 0.090272)
		(end 68.313681 0.253949)
		(width 0.188697)
		(layer "In2.Cu")
		(net "DDR0_32A_ODT0")
	)
	(segment
		(start 71.98294 -0.903503)
		(end 71.830159 -0.750722)
		(width 0.188697)
		(layer "In2.Cu")
		(net "DDR0_32A_ODT0")
	)
	(segment
		(start 74.639322 -0.762)
		(end 74.229036 -0.762)
		(width 0.188697)
		(layer "In2.Cu")
		(net "DDR0_32A_ODT0")
	)
	(segment
		(start 74.065359 0.090322)
		(end 73.901681 0.254)
		(width 0.188697)
		(layer "In2.Cu")
		(net "DDR0_32A_ODT0")
	)
	(segment
		(start 77.847139 0.295148)
		(end 76.1746 0.295148)
		(width 0.188697)
		(layer "In2.Cu")
		(net "DDR0_32A_ODT0")
	)
	(segment
		(start 68.883378 -0.903503)
		(end 68.63014 -0.903503)
		(width 0.188697)
		(layer "In2.Cu")
		(net "DDR0_32A_ODT0")
	)
	(segment
		(start 72.552636 0.254)
		(end 72.388959 0.090322)
		(width 0.188697)
		(layer "In2.Cu")
		(net "DDR0_32A_ODT0")
	)
	(segment
		(start 65.299742 4.414139)
		(end 65.299742 5.723128)
		(width 0.188697)
		(layer "In2.Cu")
		(net "DDR0_32A_ODT0")
	)
	(segment
		(start 67.324503 -0.903503)
		(end 64.958697 1.462303)
		(width 0.188697)
		(layer "In2.Cu")
		(net "DDR0_32A_ODT0")
	)
	(segment
		(start 70.317436 0.254)
		(end 70.153759 0.090322)
		(width 0.188697)
		(layer "In2.Cu")
		(net "DDR0_32A_ODT0")
	)
	(segment
		(start 71.830159 -0.750722)
		(end 71.830159 0.090322)
		(width 0.188697)
		(layer "In2.Cu")
		(net "DDR0_32A_ODT0")
	)
	(segment
		(start 71.271359 0.090322)
		(end 71.271359 -0.750722)
		(width 0.188697)
		(layer "In2.Cu")
		(net "DDR0_32A_ODT0")
	)
	(segment
		(start 76.1746 0.295148)
		(end 76.133452 0.254)
		(width 0.188697)
		(layer "In2.Cu")
		(net "DDR0_32A_ODT0")
	)
	(segment
		(start 69.036159 -0.750722)
		(end 68.883378 -0.903503)
		(width 0.188697)
		(layer "In2.Cu")
		(net "DDR0_32A_ODT0")
	)
	(segment
		(start 64.958697 1.462303)
		(end 64.958697 1.686458)
		(width 0.188697)
		(layer "In2.Cu")
		(net "DDR0_32A_ODT0")
	)
	(segment
		(start 71.435036 0.254)
		(end 71.271359 0.090322)
		(width 0.188697)
		(layer "In2.Cu")
		(net "DDR0_32A_ODT0")
	)
	(segment
		(start 65.299742 5.723128)
		(end 65.405 5.828386)
		(width 0.188697)
		(layer "In2.Cu")
		(net "DDR0_32A_ODT0")
	)
	(segment
		(start 70.86534 -0.903503)
		(end 70.712559 -0.750722)
		(width 0.188697)
		(layer "In2.Cu")
		(net "DDR0_32A_ODT0")
	)
	(segment
		(start 72.388959 0.090322)
		(end 72.388959 -0.750722)
		(width 0.188697)
		(layer "In2.Cu")
		(net "DDR0_32A_ODT0")
	)
	(segment
		(start 73.506559 -0.750722)
		(end 73.353778 -0.903503)
		(width 0.188697)
		(layer "In2.Cu")
		(net "DDR0_32A_ODT0")
	)
	(segment
		(start 74.229036 -0.762)
		(end 74.065359 -0.598322)
		(width 0.188697)
		(layer "In2.Cu")
		(net "DDR0_32A_ODT0")
	)
	(segment
		(start 68.477359 -0.750722)
		(end 68.477359 0.090272)
		(width 0.188697)
		(layer "In2.Cu")
		(net "DDR0_32A_ODT0")
	)
	(segment
		(start 65.405 5.828386)
		(end 65.405 5.8674)
		(width 0.188697)
		(layer "In2.Cu")
		(net "DDR0_32A_ODT0")
	)
	(segment
		(start 73.670236 0.254)
		(end 73.506559 0.090322)
		(width 0.188697)
		(layer "In2.Cu")
		(net "DDR0_32A_ODT0")
	)
	(segment
		(start 69.431281 0.254)
		(end 69.199836 0.254)
		(width 0.188697)
		(layer "In2.Cu")
		(net "DDR0_32A_ODT0")
	)
	(segment
		(start 65.659 6.1214)
		(end 65.659 7.974736)
		(width 0.188697)
		(layer "In2.Cu")
		(net "DDR0_32A_ODT0")
	)
	(segment
		(start 64.958697 1.686458)
		(end 64.9478 1.697355)
		(width 0.188697)
		(layer "In2.Cu")
		(net "DDR0_32A_ODT0")
	)
	(segment
		(start 67.765778 -0.903503)
		(end 67.324503 -0.903503)
		(width 0.188697)
		(layer "In2.Cu")
		(net "DDR0_32A_ODT0")
	)
	(segment
		(start 71.830159 0.090322)
		(end 71.666481 0.254)
		(width 0.188697)
		(layer "In2.Cu")
		(net "DDR0_32A_ODT0")
	)
	(segment
		(start 68.63014 -0.903503)
		(end 68.477359 -0.750722)
		(width 0.188697)
		(layer "In2.Cu")
		(net "DDR0_32A_ODT0")
	)
	(segment
		(start 69.036159 0.090322)
		(end 69.036159 -0.750722)
		(width 0.188697)
		(layer "In2.Cu")
		(net "DDR0_32A_ODT0")
	)
	(segment
		(start 69.594959 0.090322)
		(end 69.431281 0.254)
		(width 0.188697)
		(layer "In2.Cu")
		(net "DDR0_32A_ODT0")
	)
	(segment
		(start 68.313681 0.253949)
		(end 68.082236 0.253949)
		(width 0.188697)
		(layer "In2.Cu")
		(net "DDR0_32A_ODT0")
	)
	(segment
		(start 70.548881 0.254)
		(end 70.317436 0.254)
		(width 0.188697)
		(layer "In2.Cu")
		(net "DDR0_32A_ODT0")
	)
	(segment
		(start 78.650998 24.213007)
		(end 79.045283 23.818723)
		(width 0.12065)
		(layer "In6.Cu")
		(net "DDR0_32A_ODT0")
	)
	(segment
		(start 79.045283 12.261723)
		(end 79.045283 1.493291)
		(width 0.12065)
		(layer "In6.Cu")
		(net "DDR0_32A_ODT0")
	)
	(segment
		(start 79.045283 1.493291)
		(end 78.650998 1.099007)
		(width 0.12065)
		(layer "In6.Cu")
		(net "DDR0_32A_ODT0")
	)
	(segment
		(start 79.045283 23.818723)
		(end 79.045283 13.050291)
		(width 0.12065)
		(layer "In6.Cu")
		(net "DDR0_32A_ODT0")
	)
	(segment
		(start 79.045283 13.050291)
		(end 78.650998 12.656007)
		(width 0.12065)
		(layer "In6.Cu")
		(net "DDR0_32A_ODT0")
	)
	(segment
		(start 78.650998 12.656007)
		(end 79.045283 12.261723)
		(width 0.12065)
		(layer "In6.Cu")
		(net "DDR0_32A_ODT0")
	)
	(via
		(at 84.250987 13.456006)
		(size 0.4572)
		(drill 0.20574)
		(layers "F.Cu" "B.Cu")
		(net "DDR0_32A_DRAMRST_L")
	)
	(via
		(at 84.250987 1.899006)
		(size 0.4572)
		(drill 0.20574)
		(layers "F.Cu" "B.Cu")
		(net "DDR0_32A_DRAMRST_L")
	)
	(via
		(at 67.736999 21.541994)
		(size 0.4826)
		(drill 0.25654)
		(layers "F.Cu" "B.Cu")
		(net "DDR0_32A_DRAMRST_L")
	)
	(segment
		(start 83.850988 25.413005)
		(end 84.250987 25.013006)
		(width 0.14732)
		(layer "B.Cu")
		(net "DDR0_32A_DRAMRST_L")
	)
	(segment
		(start 84.250987 1.899006)
		(end 84.745779 2.393798)
		(width 0.139446)
		(layer "B.Cu")
		(net "DDR0_32A_DRAMRST_L")
	)
	(segment
		(start 84.844585 2.492604)
		(end 84.844585 12.862408)
		(width 0.1397)
		(layer "B.Cu")
		(net "DDR0_32A_DRAMRST_L")
	)
	(segment
		(start 67.429126 21.849867)
		(end 67.736999 21.541994)
		(width 0.233528)
		(layer "B.Cu")
		(net "DDR0_32A_DRAMRST_L")
	)
	(segment
		(start 84.745779 24.518214)
		(end 84.844585 24.419408)
		(width 0.1397)
		(layer "B.Cu")
		(net "DDR0_32A_DRAMRST_L")
	)
	(segment
		(start 84.745779 13.950798)
		(end 84.250987 13.456006)
		(width 0.139446)
		(layer "B.Cu")
		(net "DDR0_32A_DRAMRST_L")
	)
	(segment
		(start 84.745779 2.393798)
		(end 84.844585 2.492604)
		(width 0.1397)
		(layer "B.Cu")
		(net "DDR0_32A_DRAMRST_L")
	)
	(segment
		(start 84.250987 25.013006)
		(end 84.745779 24.518214)
		(width 0.139446)
		(layer "B.Cu")
		(net "DDR0_32A_DRAMRST_L")
	)
	(segment
		(start 84.745779 12.961214)
		(end 84.250987 13.456006)
		(width 0.139446)
		(layer "B.Cu")
		(net "DDR0_32A_DRAMRST_L")
	)
	(segment
		(start 84.844585 14.049604)
		(end 84.745779 13.950798)
		(width 0.1397)
		(layer "B.Cu")
		(net "DDR0_32A_DRAMRST_L")
	)
	(segment
		(start 83.850988 2.299005)
		(end 84.250987 1.899006)
		(width 0.14732)
		(layer "B.Cu")
		(net "DDR0_32A_DRAMRST_L")
	)
	(segment
		(start 84.844585 24.419408)
		(end 84.844585 14.049604)
		(width 0.1397)
		(layer "B.Cu")
		(net "DDR0_32A_DRAMRST_L")
	)
	(segment
		(start 84.844585 12.862408)
		(end 84.745779 12.961214)
		(width 0.1397)
		(layer "B.Cu")
		(net "DDR0_32A_DRAMRST_L")
	)
	(segment
		(start 83.850988 13.856005)
		(end 84.250987 13.456006)
		(width 0.14732)
		(layer "B.Cu")
		(net "DDR0_32A_DRAMRST_L")
	)
	(segment
		(start 67.429126 23.622)
		(end 67.429126 21.849867)
		(width 0.233528)
		(layer "B.Cu")
		(net "DDR0_32A_DRAMRST_L")
	)
	(segment
		(start 78.994 5.715)
		(end 81.84073 5.715)
		(width 0.188697)
		(layer "In2.Cu")
		(net "DDR0_32A_DRAMRST_L")
	)
	(segment
		(start 77.228421 20.284313)
		(end 77.479322 20.033412)
		(width 0.188697)
		(layer "In2.Cu")
		(net "DDR0_32A_DRAMRST_L")
	)
	(segment
		(start 67.736999 21.541994)
		(end 68.450993 20.828)
		(width 0.188697)
		(layer "In2.Cu")
		(net "DDR0_32A_DRAMRST_L")
	)
	(segment
		(start 77.479322 12.478588)
		(end 77.343 12.342266)
		(width 0.188697)
		(layer "In2.Cu")
		(net "DDR0_32A_DRAMRST_L")
	)
	(segment
		(start 77.479322 20.033412)
		(end 77.479322 12.478588)
		(width 0.188697)
		(layer "In2.Cu")
		(net "DDR0_32A_DRAMRST_L")
	)
	(segment
		(start 77.220699 20.284313)
		(end 77.228421 20.284313)
		(width 0.188697)
		(layer "In2.Cu")
		(net "DDR0_32A_DRAMRST_L")
	)
	(segment
		(start 76.677012 20.828)
		(end 77.220699 20.284313)
		(width 0.188697)
		(layer "In2.Cu")
		(net "DDR0_32A_DRAMRST_L")
	)
	(segment
		(start 77.343 8.639861)
		(end 77.724 8.258861)
		(width 0.188697)
		(layer "In2.Cu")
		(net "DDR0_32A_DRAMRST_L")
	)
	(segment
		(start 68.450993 20.828)
		(end 76.677012 20.828)
		(width 0.188697)
		(layer "In2.Cu")
		(net "DDR0_32A_DRAMRST_L")
	)
	(segment
		(start 77.724 6.985)
		(end 78.994 5.715)
		(width 0.188697)
		(layer "In2.Cu")
		(net "DDR0_32A_DRAMRST_L")
	)
	(segment
		(start 81.84073 5.715)
		(end 84.679307 2.876423)
		(width 0.188697)
		(layer "In2.Cu")
		(net "DDR0_32A_DRAMRST_L")
	)
	(segment
		(start 77.343 12.342266)
		(end 77.343 8.639861)
		(width 0.188697)
		(layer "In2.Cu")
		(net "DDR0_32A_DRAMRST_L")
	)
	(segment
		(start 84.679307 2.876423)
		(end 84.679307 2.327326)
		(width 0.188697)
		(layer "In2.Cu")
		(net "DDR0_32A_DRAMRST_L")
	)
	(segment
		(start 84.679307 2.327326)
		(end 84.250987 1.899006)
		(width 0.188697)
		(layer "In2.Cu")
		(net "DDR0_32A_DRAMRST_L")
	)
	(segment
		(start 77.724 8.258861)
		(end 77.724 6.985)
		(width 0.188697)
		(layer "In2.Cu")
		(net "DDR0_32A_DRAMRST_L")
	)
	(segment
		(start 69.736995 19.541998)
		(end 69.236996 19.041999)
		(width 0.099314)
		(layer "F.Cu")
		(net "DDR0_32A_DQS4_P")
	)
	(via
		(at 69.736995 19.541998)
		(size 0.4826)
		(drill 0.25654)
		(layers "F.Cu" "B.Cu")
		(net "DDR0_32A_DQS4_P")
	)
	(segment
		(start 75.851004 26.213003)
		(end 76.251003 26.613002)
		(width 0.099314)
		(layer "B.Cu")
		(net "DDR0_32A_DQS4_P")
	)
	(segment
		(start 71.626476 27.6098)
		(end 71.885658 27.350618)
		(width 0.096012)
		(layer "In3.Cu")
		(net "DDR0_32A_DQS4_P")
	)
	(segment
		(start 71.885658 27.350618)
		(end 71.885658 26.57983)
		(width 0.096012)
		(layer "In3.Cu")
		(net "DDR0_32A_DQS4_P")
	)
	(segment
		(start 74.28865 27.350618)
		(end 74.547832 27.6098)
		(width 0.096012)
		(layer "In3.Cu")
		(net "DDR0_32A_DQS4_P")
	)
	(segment
		(start 75.384863 27.350618)
		(end 75.384863 26.443737)
		(width 0.096012)
		(layer "In3.Cu")
		(net "DDR0_32A_DQS4_P")
	)
	(segment
		(start 73.81748 26.7208)
		(end 74.18197 26.7208)
		(width 0.096012)
		(layer "In3.Cu")
		(net "DDR0_32A_DQS4_P")
	)
	(segment
		(start 71.0184 27.6098)
		(end 71.626476 27.6098)
		(width 0.096012)
		(layer "In3.Cu")
		(net "DDR0_32A_DQS4_P")
	)
	(segment
		(start 74.547832 27.6098)
		(end 75.125682 27.6098)
		(width 0.096012)
		(layer "In3.Cu")
		(net "DDR0_32A_DQS4_P")
	)
	(segment
		(start 70.133235 26.724635)
		(end 71.0184 27.6098)
		(width 0.096012)
		(layer "In3.Cu")
		(net "DDR0_32A_DQS4_P")
	)
	(segment
		(start 72.632519 27.6098)
		(end 73.451618 27.6098)
		(width 0.096012)
		(layer "In3.Cu")
		(net "DDR0_32A_DQS4_P")
	)
	(segment
		(start 70.106819 21.351418)
		(end 70.133235 21.377834)
		(width 0.096012)
		(layer "In3.Cu")
		(net "DDR0_32A_DQS4_P")
	)
	(segment
		(start 70.106819 20.703794)
		(end 70.106819 21.351418)
		(width 0.096012)
		(layer "In3.Cu")
		(net "DDR0_32A_DQS4_P")
	)
	(segment
		(start 70.133235 21.377834)
		(end 70.133235 26.724635)
		(width 0.096012)
		(layer "In3.Cu")
		(net "DDR0_32A_DQS4_P")
	)
	(segment
		(start 71.885658 26.57983)
		(end 71.992338 26.47315)
		(width 0.096012)
		(layer "In3.Cu")
		(net "DDR0_32A_DQS4_P")
	)
	(segment
		(start 75.491543 26.337057)
		(end 75.975058 26.337057)
		(width 0.096012)
		(layer "In3.Cu")
		(net "DDR0_32A_DQS4_P")
	)
	(segment
		(start 74.28865 26.82748)
		(end 74.28865 27.350618)
		(width 0.096012)
		(layer "In3.Cu")
		(net "DDR0_32A_DQS4_P")
	)
	(segment
		(start 73.7108 26.82748)
		(end 73.81748 26.7208)
		(width 0.096012)
		(layer "In3.Cu")
		(net "DDR0_32A_DQS4_P")
	)
	(segment
		(start 74.18197 26.7208)
		(end 74.28865 26.82748)
		(width 0.096012)
		(layer "In3.Cu")
		(net "DDR0_32A_DQS4_P")
	)
	(segment
		(start 72.373338 26.57983)
		(end 72.373338 27.350618)
		(width 0.096012)
		(layer "In3.Cu")
		(net "DDR0_32A_DQS4_P")
	)
	(segment
		(start 72.373338 27.350618)
		(end 72.632519 27.6098)
		(width 0.096012)
		(layer "In3.Cu")
		(net "DDR0_32A_DQS4_P")
	)
	(segment
		(start 73.451618 27.6098)
		(end 73.7108 27.350618)
		(width 0.096012)
		(layer "In3.Cu")
		(net "DDR0_32A_DQS4_P")
	)
	(segment
		(start 75.975058 26.337057)
		(end 76.251003 26.613002)
		(width 0.096012)
		(layer "In3.Cu")
		(net "DDR0_32A_DQS4_P")
	)
	(segment
		(start 72.266658 26.47315)
		(end 72.373338 26.57983)
		(width 0.096012)
		(layer "In3.Cu")
		(net "DDR0_32A_DQS4_P")
	)
	(segment
		(start 69.736995 19.541998)
		(end 69.736995 20.33397)
		(width 0.096012)
		(layer "In3.Cu")
		(net "DDR0_32A_DQS4_P")
	)
	(segment
		(start 73.7108 27.350618)
		(end 73.7108 26.82748)
		(width 0.096012)
		(layer "In3.Cu")
		(net "DDR0_32A_DQS4_P")
	)
	(segment
		(start 75.384863 26.443737)
		(end 75.491543 26.337057)
		(width 0.096012)
		(layer "In3.Cu")
		(net "DDR0_32A_DQS4_P")
	)
	(segment
		(start 75.125682 27.6098)
		(end 75.384863 27.350618)
		(width 0.096012)
		(layer "In3.Cu")
		(net "DDR0_32A_DQS4_P")
	)
	(segment
		(start 69.736995 20.33397)
		(end 70.106819 20.703794)
		(width 0.096012)
		(layer "In3.Cu")
		(net "DDR0_32A_DQS4_P")
	)
	(segment
		(start 71.992338 26.47315)
		(end 72.266658 26.47315)
		(width 0.096012)
		(layer "In3.Cu")
		(net "DDR0_32A_DQS4_P")
	)
	(segment
		(start 70.736993 19.541998)
		(end 70.236994 19.041999)
		(width 0.099314)
		(layer "F.Cu")
		(net "DDR0_32A_DQS4_N")
	)
	(via
		(at 70.736993 19.541998)
		(size 0.4826)
		(drill 0.20574)
		(layers "F.Cu" "B.Cu")
		(net "DDR0_32A_DQS4_N")
	)
	(segment
		(start 76.651002 26.213003)
		(end 76.251003 25.813004)
		(width 0.099314)
		(layer "B.Cu")
		(net "DDR0_32A_DQS4_N")
	)
	(segment
		(start 75.383695 26.076707)
		(end 75.124513 26.335888)
		(width 0.096012)
		(layer "In3.Cu")
		(net "DDR0_32A_DQS4_N")
	)
	(segment
		(start 75.017833 27.34945)
		(end 74.65568 27.34945)
		(width 0.096012)
		(layer "In3.Cu")
		(net "DDR0_32A_DQS4_N")
	)
	(segment
		(start 75.124513 26.335888)
		(end 75.124513 27.24277)
		(width 0.096012)
		(layer "In3.Cu")
		(net "DDR0_32A_DQS4_N")
	)
	(segment
		(start 74.289818 26.46045)
		(end 73.709632 26.46045)
		(width 0.096012)
		(layer "In3.Cu")
		(net "DDR0_32A_DQS4_N")
	)
	(segment
		(start 71.126248 27.34945)
		(end 70.393585 26.616787)
		(width 0.096012)
		(layer "In3.Cu")
		(net "DDR0_32A_DQS4_N")
	)
	(segment
		(start 69.997345 19.918629)
		(end 70.373977 19.541998)
		(width 0.096012)
		(layer "In3.Cu")
		(net "DDR0_32A_DQS4_N")
	)
	(segment
		(start 72.633688 27.24277)
		(end 72.633688 26.471982)
		(width 0.096012)
		(layer "In3.Cu")
		(net "DDR0_32A_DQS4_N")
	)
	(segment
		(start 73.34377 27.34945)
		(end 72.740368 27.34945)
		(width 0.096012)
		(layer "In3.Cu")
		(net "DDR0_32A_DQS4_N")
	)
	(segment
		(start 73.45045 27.24277)
		(end 73.34377 27.34945)
		(width 0.096012)
		(layer "In3.Cu")
		(net "DDR0_32A_DQS4_N")
	)
	(segment
		(start 70.393585 26.616787)
		(end 70.393585 21.269985)
		(width 0.096012)
		(layer "In3.Cu")
		(net "DDR0_32A_DQS4_N")
	)
	(segment
		(start 73.709632 26.46045)
		(end 73.45045 26.719632)
		(width 0.096012)
		(layer "In3.Cu")
		(net "DDR0_32A_DQS4_N")
	)
	(segment
		(start 69.997345 20.226122)
		(end 69.997345 19.918629)
		(width 0.096012)
		(layer "In3.Cu")
		(net "DDR0_32A_DQS4_N")
	)
	(segment
		(start 74.65568 27.34945)
		(end 74.549 27.24277)
		(width 0.096012)
		(layer "In3.Cu")
		(net "DDR0_32A_DQS4_N")
	)
	(segment
		(start 71.625308 26.471982)
		(end 71.625308 27.24277)
		(width 0.096012)
		(layer "In3.Cu")
		(net "DDR0_32A_DQS4_N")
	)
	(segment
		(start 75.124513 27.24277)
		(end 75.017833 27.34945)
		(width 0.096012)
		(layer "In3.Cu")
		(net "DDR0_32A_DQS4_N")
	)
	(segment
		(start 70.393585 21.269985)
		(end 70.367169 21.243569)
		(width 0.096012)
		(layer "In3.Cu")
		(net "DDR0_32A_DQS4_N")
	)
	(segment
		(start 70.373977 19.541998)
		(end 70.736993 19.541998)
		(width 0.096012)
		(layer "In3.Cu")
		(net "DDR0_32A_DQS4_N")
	)
	(segment
		(start 74.549 27.24277)
		(end 74.549 26.719632)
		(width 0.096012)
		(layer "In3.Cu")
		(net "DDR0_32A_DQS4_N")
	)
	(segment
		(start 72.374506 26.2128)
		(end 71.884489 26.2128)
		(width 0.096012)
		(layer "In3.Cu")
		(net "DDR0_32A_DQS4_N")
	)
	(segment
		(start 72.633688 26.471982)
		(end 72.374506 26.2128)
		(width 0.096012)
		(layer "In3.Cu")
		(net "DDR0_32A_DQS4_N")
	)
	(segment
		(start 70.367169 20.595946)
		(end 69.997345 20.226122)
		(width 0.096012)
		(layer "In3.Cu")
		(net "DDR0_32A_DQS4_N")
	)
	(segment
		(start 71.625308 27.24277)
		(end 71.518628 27.34945)
		(width 0.096012)
		(layer "In3.Cu")
		(net "DDR0_32A_DQS4_N")
	)
	(segment
		(start 71.518628 27.34945)
		(end 71.126248 27.34945)
		(width 0.096012)
		(layer "In3.Cu")
		(net "DDR0_32A_DQS4_N")
	)
	(segment
		(start 72.740368 27.34945)
		(end 72.633688 27.24277)
		(width 0.096012)
		(layer "In3.Cu")
		(net "DDR0_32A_DQS4_N")
	)
	(segment
		(start 75.9873 26.076707)
		(end 75.383695 26.076707)
		(width 0.096012)
		(layer "In3.Cu")
		(net "DDR0_32A_DQS4_N")
	)
	(segment
		(start 76.251003 25.813004)
		(end 75.9873 26.076707)
		(width 0.096012)
		(layer "In3.Cu")
		(net "DDR0_32A_DQS4_N")
	)
	(segment
		(start 73.45045 26.719632)
		(end 73.45045 27.24277)
		(width 0.096012)
		(layer "In3.Cu")
		(net "DDR0_32A_DQS4_N")
	)
	(segment
		(start 74.549 26.719632)
		(end 74.289818 26.46045)
		(width 0.096012)
		(layer "In3.Cu")
		(net "DDR0_32A_DQS4_N")
	)
	(segment
		(start 71.884489 26.2128)
		(end 71.625308 26.471982)
		(width 0.096012)
		(layer "In3.Cu")
		(net "DDR0_32A_DQS4_N")
	)
	(segment
		(start 70.367169 21.243569)
		(end 70.367169 20.595946)
		(width 0.096012)
		(layer "In3.Cu")
		(net "DDR0_32A_DQS4_N")
	)
	(segment
		(start 70.736993 15.542006)
		(end 70.236994 16.042005)
		(width 0.099314)
		(layer "F.Cu")
		(net "DDR0_32A_DQS3_P")
	)
	(via
		(at 70.736993 15.542006)
		(size 0.4826)
		(drill 0.20574)
		(layers "F.Cu" "B.Cu")
		(net "DDR0_32A_DQS3_P")
	)
	(segment
		(start 73.451009 17.855997)
		(end 73.851008 17.455998)
		(width 0.099314)
		(layer "B.Cu")
		(net "DDR0_32A_DQS3_P")
	)
	(segment
		(start 74.041 15.621)
		(end 73.787 15.875)
		(width 0.096012)
		(layer "In2.Cu")
		(net "DDR0_32A_DQS3_P")
	)
	(segment
		(start 73.164802 15.875)
		(end 72.663152 16.37665)
		(width 0.096012)
		(layer "In2.Cu")
		(net "DDR0_32A_DQS3_P")
	)
	(segment
		(start 71.069987 15.875)
		(end 70.736993 15.542006)
		(width 0.096012)
		(layer "In2.Cu")
		(net "DDR0_32A_DQS3_P")
	)
	(segment
		(start 75.431218 15.880182)
		(end 75.172037 15.621)
		(width 0.096012)
		(layer "In2.Cu")
		(net "DDR0_32A_DQS3_P")
	)
	(segment
		(start 71.354848 15.875)
		(end 71.069987 15.875)
		(width 0.096012)
		(layer "In2.Cu")
		(net "DDR0_32A_DQS3_P")
	)
	(segment
		(start 73.787 15.875)
		(end 73.164802 15.875)
		(width 0.096012)
		(layer "In2.Cu")
		(net "DDR0_32A_DQS3_P")
	)
	(segment
		(start 71.856498 16.37665)
		(end 71.354848 15.875)
		(width 0.096012)
		(layer "In2.Cu")
		(net "DDR0_32A_DQS3_P")
	)
	(segment
		(start 73.443948 17.421174)
		(end 73.443948 16.894353)
		(width 0.096012)
		(layer "In2.Cu")
		(net "DDR0_32A_DQS3_P")
	)
	(segment
		(start 73.781006 17.526)
		(end 73.548773 17.526)
		(width 0.096012)
		(layer "In2.Cu")
		(net "DDR0_32A_DQS3_P")
	)
	(segment
		(start 73.851008 17.455998)
		(end 73.781006 17.526)
		(width 0.096012)
		(layer "In2.Cu")
		(net "DDR0_32A_DQS3_P")
	)
	(segment
		(start 73.443948 16.894353)
		(end 73.5743 16.764)
		(width 0.096012)
		(layer "In2.Cu")
		(net "DDR0_32A_DQS3_P")
	)
	(segment
		(start 75.172037 15.621)
		(end 74.041 15.621)
		(width 0.096012)
		(layer "In2.Cu")
		(net "DDR0_32A_DQS3_P")
	)
	(segment
		(start 75.065357 16.764)
		(end 75.431218 16.398138)
		(width 0.096012)
		(layer "In2.Cu")
		(net "DDR0_32A_DQS3_P")
	)
	(segment
		(start 73.5743 16.764)
		(end 75.065357 16.764)
		(width 0.096012)
		(layer "In2.Cu")
		(net "DDR0_32A_DQS3_P")
	)
	(segment
		(start 72.663152 16.37665)
		(end 71.856498 16.37665)
		(width 0.096012)
		(layer "In2.Cu")
		(net "DDR0_32A_DQS3_P")
	)
	(segment
		(start 73.548773 17.526)
		(end 73.443948 17.421174)
		(width 0.096012)
		(layer "In2.Cu")
		(net "DDR0_32A_DQS3_P")
	)
	(segment
		(start 75.431218 16.398138)
		(end 75.431218 15.880182)
		(width 0.096012)
		(layer "In2.Cu")
		(net "DDR0_32A_DQS3_P")
	)
	(segment
		(start 69.736995 15.542006)
		(end 69.236996 16.042005)
		(width 0.099314)
		(layer "F.Cu")
		(net "DDR0_32A_DQS3_N")
	)
	(via
		(at 69.736995 15.542006)
		(size 0.4826)
		(drill 0.25654)
		(layers "F.Cu" "B.Cu")
		(net "DDR0_32A_DQS3_N")
	)
	(segment
		(start 72.65101 17.855997)
		(end 73.05101 17.455998)
		(width 0.099314)
		(layer "B.Cu")
		(net "DDR0_32A_DQS3_N")
	)
	(segment
		(start 73.106305 17.400702)
		(end 73.05101 17.455998)
		(width 0.096012)
		(layer "In2.Cu")
		(net "DDR0_32A_DQS3_N")
	)
	(segment
		(start 73.27265 16.13535)
		(end 73.894848 16.13535)
		(width 0.096012)
		(layer "In2.Cu")
		(net "DDR0_32A_DQS3_N")
	)
	(segment
		(start 74.148848 15.88135)
		(end 75.064188 15.88135)
		(width 0.096012)
		(layer "In2.Cu")
		(net "DDR0_32A_DQS3_N")
	)
	(segment
		(start 75.064188 15.88135)
		(end 75.170868 15.98803)
		(width 0.096012)
		(layer "In2.Cu")
		(net "DDR0_32A_DQS3_N")
	)
	(segment
		(start 69.736995 15.542006)
		(end 70.993 16.13535)
		(width 0.096012)
		(layer "In2.Cu")
		(net "DDR0_32A_DQS3_N")
	)
	(segment
		(start 75.170868 16.29029)
		(end 74.957508 16.50365)
		(width 0.096012)
		(layer "In2.Cu")
		(net "DDR0_32A_DQS3_N")
	)
	(segment
		(start 75.170868 15.98803)
		(end 75.170868 16.29029)
		(width 0.096012)
		(layer "In2.Cu")
		(net "DDR0_32A_DQS3_N")
	)
	(segment
		(start 73.466452 16.50365)
		(end 73.106305 16.863797)
		(width 0.096012)
		(layer "In2.Cu")
		(net "DDR0_32A_DQS3_N")
	)
	(segment
		(start 72.771 16.637)
		(end 73.27265 16.13535)
		(width 0.096012)
		(layer "In2.Cu")
		(net "DDR0_32A_DQS3_N")
	)
	(segment
		(start 73.894848 16.13535)
		(end 74.148848 15.88135)
		(width 0.096012)
		(layer "In2.Cu")
		(net "DDR0_32A_DQS3_N")
	)
	(segment
		(start 70.993 16.13535)
		(end 71.247 16.13535)
		(width 0.096012)
		(layer "In2.Cu")
		(net "DDR0_32A_DQS3_N")
	)
	(segment
		(start 73.106305 16.863797)
		(end 73.106305 17.400702)
		(width 0.096012)
		(layer "In2.Cu")
		(net "DDR0_32A_DQS3_N")
	)
	(segment
		(start 71.74865 16.637)
		(end 72.771 16.637)
		(width 0.096012)
		(layer "In2.Cu")
		(net "DDR0_32A_DQS3_N")
	)
	(segment
		(start 71.247 16.13535)
		(end 71.74865 16.637)
		(width 0.096012)
		(layer "In2.Cu")
		(net "DDR0_32A_DQS3_N")
	)
	(segment
		(start 74.957508 16.50365)
		(end 73.466452 16.50365)
		(width 0.096012)
		(layer "In2.Cu")
		(net "DDR0_32A_DQS3_N")
	)
	(segment
		(start 68.736997 14.542008)
		(end 68.236998 15.042007)
		(width 0.099314)
		(layer "F.Cu")
		(net "DDR0_32A_DQS2_P")
	)
	(via
		(at 68.736997 14.542008)
		(size 0.4826)
		(drill 0.20574)
		(layers "F.Cu" "B.Cu")
		(net "DDR0_32A_DQS2_P")
	)
	(segment
		(start 75.851004 14.656003)
		(end 76.251003 15.056002)
		(width 0.099314)
		(layer "B.Cu")
		(net "DDR0_32A_DQS2_P")
	)
	(segment
		(start 75.615038 14.935962)
		(end 75.615038 15.086838)
		(width 0.096012)
		(layer "In3.Cu")
		(net "DDR0_32A_DQS2_P")
	)
	(segment
		(start 68.479314 14.146911)
		(end 68.4022 14.224025)
		(width 0.095758)
		(layer "In3.Cu")
		(net "DDR0_32A_DQS2_P")
	)
	(segment
		(start 76.00315 15.47495)
		(end 76.00315 15.89405)
		(width 0.096012)
		(layer "In3.Cu")
		(net "DDR0_32A_DQS2_P")
	)
	(segment
		(start 75.615038 15.086838)
		(end 76.00315 15.47495)
		(width 0.096012)
		(layer "In3.Cu")
		(net "DDR0_32A_DQS2_P")
	)
	(segment
		(start 71.5518 15.280716)
		(end 71.5518 14.3002)
		(width 0.096012)
		(layer "In3.Cu")
		(net "DDR0_32A_DQS2_P")
	)
	(segment
		(start 71.980374 15.70929)
		(end 71.5518 15.280716)
		(width 0.096012)
		(layer "In3.Cu")
		(net "DDR0_32A_DQS2_P")
	)
	(segment
		(start 68.4022 14.224025)
		(end 68.4022 14.427175)
		(width 0.095758)
		(layer "In3.Cu")
		(net "DDR0_32A_DQS2_P")
	)
	(segment
		(start 75.764822 14.786178)
		(end 75.615038 14.935962)
		(width 0.096012)
		(layer "In3.Cu")
		(net "DDR0_32A_DQS2_P")
	)
	(segment
		(start 71.070851 14.146911)
		(end 68.479314 14.146911)
		(width 0.095758)
		(layer "In3.Cu")
		(net "DDR0_32A_DQS2_P")
	)
	(segment
		(start 71.5518 14.3002)
		(end 71.421625 14.170025)
		(width 0.096012)
		(layer "In3.Cu")
		(net "DDR0_32A_DQS2_P")
	)
	(segment
		(start 74.380217 15.70929)
		(end 71.980374 15.70929)
		(width 0.096012)
		(layer "In3.Cu")
		(net "DDR0_32A_DQS2_P")
	)
	(segment
		(start 74.958677 16.28775)
		(end 74.380217 15.70929)
		(width 0.096012)
		(layer "In3.Cu")
		(net "DDR0_32A_DQS2_P")
	)
	(segment
		(start 76.00315 15.89405)
		(end 75.60945 16.28775)
		(width 0.096012)
		(layer "In3.Cu")
		(net "DDR0_32A_DQS2_P")
	)
	(segment
		(start 71.12 14.170025)
		(end 71.093965 14.170025)
		(width 0.095758)
		(layer "In3.Cu")
		(net "DDR0_32A_DQS2_P")
	)
	(segment
		(start 71.093965 14.170025)
		(end 71.070851 14.146911)
		(width 0.095758)
		(layer "In3.Cu")
		(net "DDR0_32A_DQS2_P")
	)
	(segment
		(start 71.421625 14.170025)
		(end 71.12 14.170025)
		(width 0.096012)
		(layer "In3.Cu")
		(net "DDR0_32A_DQS2_P")
	)
	(segment
		(start 75.981179 14.786178)
		(end 75.764822 14.786178)
		(width 0.096012)
		(layer "In3.Cu")
		(net "DDR0_32A_DQS2_P")
	)
	(segment
		(start 76.251003 15.056002)
		(end 75.981179 14.786178)
		(width 0.096012)
		(layer "In3.Cu")
		(net "DDR0_32A_DQS2_P")
	)
	(segment
		(start 75.60945 16.28775)
		(end 74.958677 16.28775)
		(width 0.096012)
		(layer "In3.Cu")
		(net "DDR0_32A_DQS2_P")
	)
	(segment
		(start 68.517033 14.542008)
		(end 68.736997 14.542008)
		(width 0.095758)
		(layer "In3.Cu")
		(net "DDR0_32A_DQS2_P")
	)
	(segment
		(start 68.4022 14.427175)
		(end 68.517033 14.542008)
		(width 0.095758)
		(layer "In3.Cu")
		(net "DDR0_32A_DQS2_P")
	)
	(segment
		(start 67.736999 14.542008)
		(end 67.237 15.042007)
		(width 0.099314)
		(layer "F.Cu")
		(net "DDR0_32A_DQS2_N")
	)
	(via
		(at 67.736999 14.542008)
		(size 0.4826)
		(drill 0.25654)
		(layers "F.Cu" "B.Cu")
		(net "DDR0_32A_DQS2_N")
	)
	(segment
		(start 76.651002 14.656003)
		(end 76.251003 14.256004)
		(width 0.099314)
		(layer "B.Cu")
		(net "DDR0_32A_DQS2_N")
	)
	(segment
		(start 75.501602 16.0274)
		(end 75.7428 15.786202)
		(width 0.096012)
		(layer "In3.Cu")
		(net "DDR0_32A_DQS2_N")
	)
	(segment
		(start 71.12 13.909675)
		(end 71.529473 13.909675)
		(width 0.096012)
		(layer "In3.Cu")
		(net "DDR0_32A_DQS2_N")
	)
	(segment
		(start 75.611126 14.571675)
		(end 76.251003 14.256004)
		(width 0.096012)
		(layer "In3.Cu")
		(net "DDR0_32A_DQS2_N")
	)
	(segment
		(start 71.529473 13.909675)
		(end 71.81215 14.192352)
		(width 0.096012)
		(layer "In3.Cu")
		(net "DDR0_32A_DQS2_N")
	)
	(segment
		(start 71.81215 15.172868)
		(end 72.088223 15.44894)
		(width 0.096012)
		(layer "In3.Cu")
		(net "DDR0_32A_DQS2_N")
	)
	(segment
		(start 71.070851 13.932789)
		(end 71.093965 13.909675)
		(width 0.095758)
		(layer "In3.Cu")
		(net "DDR0_32A_DQS2_N")
	)
	(segment
		(start 67.767429 14.542008)
		(end 68.376648 13.932789)
		(width 0.095758)
		(layer "In3.Cu")
		(net "DDR0_32A_DQS2_N")
	)
	(segment
		(start 68.376648 13.932789)
		(end 71.070851 13.932789)
		(width 0.095758)
		(layer "In3.Cu")
		(net "DDR0_32A_DQS2_N")
	)
	(segment
		(start 74.488065 15.44894)
		(end 75.066525 16.0274)
		(width 0.096012)
		(layer "In3.Cu")
		(net "DDR0_32A_DQS2_N")
	)
	(segment
		(start 71.81215 14.192352)
		(end 71.81215 15.172868)
		(width 0.096012)
		(layer "In3.Cu")
		(net "DDR0_32A_DQS2_N")
	)
	(segment
		(start 75.066525 16.0274)
		(end 75.501602 16.0274)
		(width 0.096012)
		(layer "In3.Cu")
		(net "DDR0_32A_DQS2_N")
	)
	(segment
		(start 71.093965 13.909675)
		(end 71.12 13.909675)
		(width 0.095758)
		(layer "In3.Cu")
		(net "DDR0_32A_DQS2_N")
	)
	(segment
		(start 75.354688 15.194686)
		(end 75.354688 14.828114)
		(width 0.096012)
		(layer "In3.Cu")
		(net "DDR0_32A_DQS2_N")
	)
	(segment
		(start 67.736999 14.542008)
		(end 67.767429 14.542008)
		(width 0.095758)
		(layer "In3.Cu")
		(net "DDR0_32A_DQS2_N")
	)
	(segment
		(start 75.354688 14.828114)
		(end 75.611126 14.571675)
		(width 0.096012)
		(layer "In3.Cu")
		(net "DDR0_32A_DQS2_N")
	)
	(segment
		(start 75.7428 15.582798)
		(end 75.354688 15.194686)
		(width 0.096012)
		(layer "In3.Cu")
		(net "DDR0_32A_DQS2_N")
	)
	(segment
		(start 72.088223 15.44894)
		(end 74.488065 15.44894)
		(width 0.096012)
		(layer "In3.Cu")
		(net "DDR0_32A_DQS2_N")
	)
	(segment
		(start 75.7428 15.786202)
		(end 75.7428 15.582798)
		(width 0.096012)
		(layer "In3.Cu")
		(net "DDR0_32A_DQS2_N")
	)
	(segment
		(start 68.736997 11.541989)
		(end 68.236998 12.041988)
		(width 0.099314)
		(layer "F.Cu")
		(net "DDR0_32A_DQS1_P")
	)
	(via
		(at 68.736997 11.541989)
		(size 0.4826)
		(drill 0.25654)
		(layers "F.Cu" "B.Cu")
		(net "DDR0_32A_DQS1_P")
	)
	(segment
		(start 73.451009 6.298997)
		(end 73.851008 5.898998)
		(width 0.099314)
		(layer "B.Cu")
		(net "DDR0_32A_DQS1_P")
	)
	(segment
		(start 71.075347 10.93277)
		(end 71.376692 10.631424)
		(width 0.095758)
		(layer "In2.Cu")
		(net "DDR0_32A_DQS1_P")
	)
	(segment
		(start 73.15901 5.207)
		(end 73.851008 5.898998)
		(width 0.096012)
		(layer "In2.Cu")
		(net "DDR0_32A_DQS1_P")
	)
	(segment
		(start 68.612664 11.417656)
		(end 68.612664 11.143336)
		(width 0.095758)
		(layer "In2.Cu")
		(net "DDR0_32A_DQS1_P")
	)
	(segment
		(start 72.35825 10.631424)
		(end 72.434069 10.555605)
		(width 0.095758)
		(layer "In2.Cu")
		(net "DDR0_32A_DQS1_P")
	)
	(segment
		(start 72.009 5.207)
		(end 73.15901 5.207)
		(width 0.096012)
		(layer "In2.Cu")
		(net "DDR0_32A_DQS1_P")
	)
	(segment
		(start 68.82323 10.93277)
		(end 71.075347 10.93277)
		(width 0.095758)
		(layer "In2.Cu")
		(net "DDR0_32A_DQS1_P")
	)
	(segment
		(start 71.783016 10.039731)
		(end 71.196352 9.453067)
		(width 0.095758)
		(layer "In2.Cu")
		(net "DDR0_32A_DQS1_P")
	)
	(segment
		(start 72.434069 10.323195)
		(end 72.150605 10.039731)
		(width 0.095758)
		(layer "In2.Cu")
		(net "DDR0_32A_DQS1_P")
	)
	(segment
		(start 71.258303 8.727262)
		(end 71.258303 5.957697)
		(width 0.096012)
		(layer "In2.Cu")
		(net "DDR0_32A_DQS1_P")
	)
	(segment
		(start 72.434069 10.555605)
		(end 72.434069 10.323195)
		(width 0.095758)
		(layer "In2.Cu")
		(net "DDR0_32A_DQS1_P")
	)
	(segment
		(start 71.258303 5.957697)
		(end 72.009 5.207)
		(width 0.096012)
		(layer "In2.Cu")
		(net "DDR0_32A_DQS1_P")
	)
	(segment
		(start 68.612664 11.143336)
		(end 68.82323 10.93277)
		(width 0.095758)
		(layer "In2.Cu")
		(net "DDR0_32A_DQS1_P")
	)
	(segment
		(start 72.150605 10.039731)
		(end 71.783016 10.039731)
		(width 0.095758)
		(layer "In2.Cu")
		(net "DDR0_32A_DQS1_P")
	)
	(segment
		(start 71.376692 10.631424)
		(end 72.35825 10.631424)
		(width 0.095758)
		(layer "In2.Cu")
		(net "DDR0_32A_DQS1_P")
	)
	(segment
		(start 68.736997 11.541989)
		(end 68.612664 11.417656)
		(width 0.095758)
		(layer "In2.Cu")
		(net "DDR0_32A_DQS1_P")
	)
	(segment
		(start 71.196352 8.789213)
		(end 71.258303 8.727262)
		(width 0.095758)
		(layer "In2.Cu")
		(net "DDR0_32A_DQS1_P")
	)
	(segment
		(start 71.196352 9.453067)
		(end 71.196352 8.789213)
		(width 0.095758)
		(layer "In2.Cu")
		(net "DDR0_32A_DQS1_P")
	)
	(segment
		(start 67.736999 11.541989)
		(end 67.237 12.041988)
		(width 0.099314)
		(layer "F.Cu")
		(net "DDR0_32A_DQS1_N")
	)
	(via
		(at 67.736999 11.541989)
		(size 0.4826)
		(drill 0.20574)
		(layers "F.Cu" "B.Cu")
		(net "DDR0_32A_DQS1_N")
	)
	(segment
		(start 72.65101 6.298997)
		(end 73.05101 5.898998)
		(width 0.099314)
		(layer "B.Cu")
		(net "DDR0_32A_DQS1_N")
	)
	(segment
		(start 72.116848 5.46735)
		(end 71.518653 6.065545)
		(width 0.096012)
		(layer "In2.Cu")
		(net "DDR0_32A_DQS1_N")
	)
	(segment
		(start 68.487417 11.939524)
		(end 68.486147 11.940794)
		(width 0.095758)
		(layer "In2.Cu")
		(net "DDR0_32A_DQS1_N")
	)
	(segment
		(start 71.518653 8.732291)
		(end 71.518653 8.769731)
		(width 0.095758)
		(layer "In2.Cu")
		(net "DDR0_32A_DQS1_N")
	)
	(segment
		(start 69.228995 11.146892)
		(end 69.131967 11.24392)
		(width 0.095758)
		(layer "In2.Cu")
		(net "DDR0_32A_DQS1_N")
	)
	(segment
		(start 71.410474 9.36437)
		(end 71.871713 9.825609)
		(width 0.095758)
		(layer "In2.Cu")
		(net "DDR0_32A_DQS1_N")
	)
	(segment
		(start 69.131967 11.705615)
		(end 68.900624 11.936959)
		(width 0.095758)
		(layer "In2.Cu")
		(net "DDR0_32A_DQS1_N")
	)
	(segment
		(start 73.05101 5.898998)
		(end 72.619362 5.46735)
		(width 0.096012)
		(layer "In2.Cu")
		(net "DDR0_32A_DQS1_N")
	)
	(segment
		(start 68.486147 11.940794)
		(end 68.135805 11.940794)
		(width 0.095758)
		(layer "In2.Cu")
		(net "DDR0_32A_DQS1_N")
	)
	(segment
		(start 72.648191 10.234447)
		(end 72.648191 10.644353)
		(width 0.095758)
		(layer "In2.Cu")
		(net "DDR0_32A_DQS1_N")
	)
	(segment
		(start 71.871713 9.825609)
		(end 72.239353 9.825609)
		(width 0.095758)
		(layer "In2.Cu")
		(net "DDR0_32A_DQS1_N")
	)
	(segment
		(start 68.85752 11.939524)
		(end 68.487417 11.939524)
		(width 0.095758)
		(layer "In2.Cu")
		(net "DDR0_32A_DQS1_N")
	)
	(segment
		(start 68.860086 11.936959)
		(end 68.85752 11.939524)
		(width 0.095758)
		(layer "In2.Cu")
		(net "DDR0_32A_DQS1_N")
	)
	(segment
		(start 71.46544 10.845546)
		(end 71.164094 11.146892)
		(width 0.095758)
		(layer "In2.Cu")
		(net "DDR0_32A_DQS1_N")
	)
	(segment
		(start 71.164094 11.146892)
		(end 69.228995 11.146892)
		(width 0.095758)
		(layer "In2.Cu")
		(net "DDR0_32A_DQS1_N")
	)
	(segment
		(start 71.518653 8.769731)
		(end 71.410474 8.87791)
		(width 0.095758)
		(layer "In2.Cu")
		(net "DDR0_32A_DQS1_N")
	)
	(segment
		(start 72.446998 10.845546)
		(end 71.46544 10.845546)
		(width 0.095758)
		(layer "In2.Cu")
		(net "DDR0_32A_DQS1_N")
	)
	(segment
		(start 68.900624 11.936959)
		(end 68.860086 11.936959)
		(width 0.095758)
		(layer "In2.Cu")
		(net "DDR0_32A_DQS1_N")
	)
	(segment
		(start 71.410474 8.87791)
		(end 71.410474 9.36437)
		(width 0.095758)
		(layer "In2.Cu")
		(net "DDR0_32A_DQS1_N")
	)
	(segment
		(start 71.518653 6.065545)
		(end 71.518653 8.732291)
		(width 0.096012)
		(layer "In2.Cu")
		(net "DDR0_32A_DQS1_N")
	)
	(segment
		(start 72.648191 10.644353)
		(end 72.446998 10.845546)
		(width 0.095758)
		(layer "In2.Cu")
		(net "DDR0_32A_DQS1_N")
	)
	(segment
		(start 68.135805 11.940794)
		(end 67.736999 11.541989)
		(width 0.095758)
		(layer "In2.Cu")
		(net "DDR0_32A_DQS1_N")
	)
	(segment
		(start 72.619362 5.46735)
		(end 72.116848 5.46735)
		(width 0.096012)
		(layer "In2.Cu")
		(net "DDR0_32A_DQS1_N")
	)
	(segment
		(start 69.131967 11.24392)
		(end 69.131967 11.705615)
		(width 0.095758)
		(layer "In2.Cu")
		(net "DDR0_32A_DQS1_N")
	)
	(segment
		(start 72.239353 9.825609)
		(end 72.648191 10.234447)
		(width 0.095758)
		(layer "In2.Cu")
		(net "DDR0_32A_DQS1_N")
	)
	(segment
		(start 70.736993 8.541995)
		(end 70.236994 9.041994)
		(width 0.099314)
		(layer "F.Cu")
		(net "DDR0_32A_DQS0_P")
	)
	(via
		(at 70.736993 8.541995)
		(size 0.4826)
		(drill 0.20574)
		(layers "F.Cu" "B.Cu")
		(net "DDR0_32A_DQS0_P")
	)
	(segment
		(start 75.851004 3.099003)
		(end 76.251003 3.499002)
		(width 0.099314)
		(layer "B.Cu")
		(net "DDR0_32A_DQS0_P")
	)
	(segment
		(start 71.036282 5.167249)
		(end 71.020254 5.151222)
		(width 0.095758)
		(layer "In3.Cu")
		(net "DDR0_32A_DQS0_P")
	)
	(segment
		(start 75.8444 4.4196)
		(end 75.8444 4.806848)
		(width 0.096012)
		(layer "In3.Cu")
		(net "DDR0_32A_DQS0_P")
	)
	(segment
		(start 76.251003 3.499002)
		(end 76.251003 3.360217)
		(width 0.096012)
		(layer "In3.Cu")
		(net "DDR0_32A_DQS0_P")
	)
	(segment
		(start 69.57507 5.151222)
		(end 69.346216 5.380076)
		(width 0.095758)
		(layer "In3.Cu")
		(net "DDR0_32A_DQS0_P")
	)
	(segment
		(start 71.101077 5.167249)
		(end 71.036282 5.167249)
		(width 0.095758)
		(layer "In3.Cu")
		(net "DDR0_32A_DQS0_P")
	)
	(segment
		(start 70.654926 9.017)
		(end 70.739 9.017)
		(width 0.095758)
		(layer "In3.Cu")
		(net "DDR0_32A_DQS0_P")
	)
	(segment
		(start 75.564898 5.08635)
		(end 74.54265 5.08635)
		(width 0.096012)
		(layer "In3.Cu")
		(net "DDR0_32A_DQS0_P")
	)
	(segment
		(start 74.54265 5.08635)
		(end 74.461624 5.167376)
		(width 0.096012)
		(layer "In3.Cu")
		(net "DDR0_32A_DQS0_P")
	)
	(segment
		(start 70.866 8.89)
		(end 70.866 8.671001)
		(width 0.095758)
		(layer "In3.Cu")
		(net "DDR0_32A_DQS0_P")
	)
	(segment
		(start 76.144323 3.253537)
		(end 75.854662 3.253537)
		(width 0.096012)
		(layer "In3.Cu")
		(net "DDR0_32A_DQS0_P")
	)
	(segment
		(start 75.854662 3.253537)
		(end 75.5396 3.568598)
		(width 0.096012)
		(layer "In3.Cu")
		(net "DDR0_32A_DQS0_P")
	)
	(segment
		(start 69.987617 7.937094)
		(end 70.341896 8.291373)
		(width 0.095758)
		(layer "In3.Cu")
		(net "DDR0_32A_DQS0_P")
	)
	(segment
		(start 71.125029 5.167376)
		(end 71.101204 5.167376)
		(width 0.095758)
		(layer "In3.Cu")
		(net "DDR0_32A_DQS0_P")
	)
	(segment
		(start 70.341896 8.291373)
		(end 70.341896 8.70397)
		(width 0.095758)
		(layer "In3.Cu")
		(net "DDR0_32A_DQS0_P")
	)
	(segment
		(start 71.020254 5.151222)
		(end 69.57507 5.151222)
		(width 0.095758)
		(layer "In3.Cu")
		(net "DDR0_32A_DQS0_P")
	)
	(segment
		(start 75.5396 4.1148)
		(end 75.8444 4.4196)
		(width 0.096012)
		(layer "In3.Cu")
		(net "DDR0_32A_DQS0_P")
	)
	(segment
		(start 75.5396 3.568598)
		(end 75.5396 4.1148)
		(width 0.096012)
		(layer "In3.Cu")
		(net "DDR0_32A_DQS0_P")
	)
	(segment
		(start 76.251003 3.360217)
		(end 76.144323 3.253537)
		(width 0.096012)
		(layer "In3.Cu")
		(net "DDR0_32A_DQS0_P")
	)
	(segment
		(start 70.739 9.017)
		(end 70.866 8.89)
		(width 0.095758)
		(layer "In3.Cu")
		(net "DDR0_32A_DQS0_P")
	)
	(segment
		(start 75.8444 4.806848)
		(end 75.564898 5.08635)
		(width 0.096012)
		(layer "In3.Cu")
		(net "DDR0_32A_DQS0_P")
	)
	(segment
		(start 69.579439 7.937094)
		(end 69.987617 7.937094)
		(width 0.095758)
		(layer "In3.Cu")
		(net "DDR0_32A_DQS0_P")
	)
	(segment
		(start 69.346216 5.380076)
		(end 69.346216 7.703871)
		(width 0.095758)
		(layer "In3.Cu")
		(net "DDR0_32A_DQS0_P")
	)
	(segment
		(start 74.461624 5.167376)
		(end 71.125029 5.167376)
		(width 0.096012)
		(layer "In3.Cu")
		(net "DDR0_32A_DQS0_P")
	)
	(segment
		(start 69.346216 7.703871)
		(end 69.579439 7.937094)
		(width 0.095758)
		(layer "In3.Cu")
		(net "DDR0_32A_DQS0_P")
	)
	(segment
		(start 71.101204 5.167376)
		(end 71.101077 5.167249)
		(width 0.095758)
		(layer "In3.Cu")
		(net "DDR0_32A_DQS0_P")
	)
	(segment
		(start 70.866 8.671001)
		(end 70.736993 8.541995)
		(width 0.095758)
		(layer "In3.Cu")
		(net "DDR0_32A_DQS0_P")
	)
	(segment
		(start 70.341896 8.70397)
		(end 70.654926 9.017)
		(width 0.095758)
		(layer "In3.Cu")
		(net "DDR0_32A_DQS0_P")
	)
	(segment
		(start 70.736993 9.541993)
		(end 70.236994 10.041992)
		(width 0.099314)
		(layer "F.Cu")
		(net "DDR0_32A_DQS0_N")
	)
	(via
		(at 70.736993 9.541993)
		(size 0.4826)
		(drill 0.20574)
		(layers "F.Cu" "B.Cu")
		(net "DDR0_32A_DQS0_N")
	)
	(segment
		(start 76.651002 3.099003)
		(end 76.251003 2.699004)
		(width 0.099314)
		(layer "B.Cu")
		(net "DDR0_32A_DQS0_N")
	)
	(segment
		(start 69.360999 5.062449)
		(end 69.360999 5.062474)
		(width 0.095758)
		(layer "In3.Cu")
		(net "DDR0_32A_DQS0_N")
	)
	(segment
		(start 69.132094 7.792618)
		(end 69.490692 8.151216)
		(width 0.095758)
		(layer "In3.Cu")
		(net "DDR0_32A_DQS0_N")
	)
	(segment
		(start 70.736993 9.401937)
		(end 70.736993 9.541993)
		(width 0.095758)
		(layer "In3.Cu")
		(net "DDR0_32A_DQS0_N")
	)
	(segment
		(start 75.45705 4.826)
		(end 74.434802 4.826)
		(width 0.096012)
		(layer "In3.Cu")
		(net "DDR0_32A_DQS0_N")
	)
	(segment
		(start 69.132094 5.291379)
		(end 69.132094 7.792618)
		(width 0.095758)
		(layer "In3.Cu")
		(net "DDR0_32A_DQS0_N")
	)
	(segment
		(start 74.307802 4.953)
		(end 71.125029 4.953)
		(width 0.096012)
		(layer "In3.Cu")
		(net "DDR0_32A_DQS0_N")
	)
	(segment
		(start 69.490692 8.151216)
		(end 69.89887 8.151216)
		(width 0.095758)
		(layer "In3.Cu")
		(net "DDR0_32A_DQS0_N")
	)
	(segment
		(start 69.89887 8.151216)
		(end 70.127774 8.38012)
		(width 0.095758)
		(layer "In3.Cu")
		(net "DDR0_32A_DQS0_N")
	)
	(segment
		(start 75.27925 3.46075)
		(end 75.27925 4.222648)
		(width 0.096012)
		(layer "In3.Cu")
		(net "DDR0_32A_DQS0_N")
	)
	(segment
		(start 75.746813 2.993187)
		(end 75.27925 3.46075)
		(width 0.096012)
		(layer "In3.Cu")
		(net "DDR0_32A_DQS0_N")
	)
	(segment
		(start 70.127774 8.38012)
		(end 70.127774 8.792718)
		(width 0.095758)
		(layer "In3.Cu")
		(net "DDR0_32A_DQS0_N")
	)
	(segment
		(start 69.486348 4.9371)
		(end 69.360999 5.062449)
		(width 0.095758)
		(layer "In3.Cu")
		(net "DDR0_32A_DQS0_N")
	)
	(segment
		(start 69.360999 5.062474)
		(end 69.132094 5.291379)
		(width 0.095758)
		(layer "In3.Cu")
		(net "DDR0_32A_DQS0_N")
	)
	(segment
		(start 71.109129 4.9371)
		(end 69.486348 4.9371)
		(width 0.095758)
		(layer "In3.Cu")
		(net "DDR0_32A_DQS0_N")
	)
	(segment
		(start 75.58405 4.527448)
		(end 75.58405 4.699)
		(width 0.096012)
		(layer "In3.Cu")
		(net "DDR0_32A_DQS0_N")
	)
	(segment
		(start 71.125029 4.953)
		(end 71.109129 4.9371)
		(width 0.095758)
		(layer "In3.Cu")
		(net "DDR0_32A_DQS0_N")
	)
	(segment
		(start 75.27925 4.222648)
		(end 75.58405 4.527448)
		(width 0.096012)
		(layer "In3.Cu")
		(net "DDR0_32A_DQS0_N")
	)
	(segment
		(start 74.434802 4.826)
		(end 74.307802 4.953)
		(width 0.096012)
		(layer "In3.Cu")
		(net "DDR0_32A_DQS0_N")
	)
	(segment
		(start 70.127774 8.792718)
		(end 70.736993 9.401937)
		(width 0.095758)
		(layer "In3.Cu")
		(net "DDR0_32A_DQS0_N")
	)
	(segment
		(start 75.58405 4.699)
		(end 75.45705 4.826)
		(width 0.096012)
		(layer "In3.Cu")
		(net "DDR0_32A_DQS0_N")
	)
	(segment
		(start 76.251003 2.699004)
		(end 75.746813 2.993187)
		(width 0.096012)
		(layer "In3.Cu")
		(net "DDR0_32A_DQS0_N")
	)
	(segment
		(start 65.737003 15.542006)
		(end 65.237004 16.042005)
		(width 0.13208)
		(layer "F.Cu")
		(net "DDR0_32A_DQ31")
	)
	(via
		(at 65.737003 15.542006)
		(size 0.4826)
		(drill 0.25654)
		(layers "F.Cu" "B.Cu")
		(net "DDR0_32A_DQ31")
	)
	(segment
		(start 73.451009 13.856005)
		(end 73.05101 13.456006)
		(width 0.254)
		(layer "B.Cu")
		(net "DDR0_32A_DQ31")
	)
	(segment
		(start 66.90073 14.937232)
		(end 67.341775 14.496186)
		(width 0.104648)
		(layer "In2.Cu")
		(net "DDR0_32A_DQ31")
	)
	(segment
		(start 67.341775 14.496186)
		(end 67.341775 14.37828)
		(width 0.104648)
		(layer "In2.Cu")
		(net "DDR0_32A_DQ31")
	)
	(segment
		(start 72.085327 13.056083)
		(end 72.631071 13.056083)
		(width 0.12065)
		(layer "In2.Cu")
		(net "DDR0_32A_DQ31")
	)
	(segment
		(start 68.326 13.716025)
		(end 68.326 13.462)
		(width 0.104648)
		(layer "In2.Cu")
		(net "DDR0_32A_DQ31")
	)
	(segment
		(start 68.341773 13.378282)
		(end 68.573269 13.146786)
		(width 0.104648)
		(layer "In2.Cu")
		(net "DDR0_32A_DQ31")
	)
	(segment
		(start 65.737003 15.542006)
		(end 66.341777 14.937232)
		(width 0.104648)
		(layer "In2.Cu")
		(net "DDR0_32A_DQ31")
	)
	(segment
		(start 67.341775 14.37828)
		(end 67.782821 13.937234)
		(width 0.104648)
		(layer "In2.Cu")
		(net "DDR0_32A_DQ31")
	)
	(segment
		(start 73.030994 13.456006)
		(end 73.05101 13.456006)
		(width 0.12065)
		(layer "In2.Cu")
		(net "DDR0_32A_DQ31")
	)
	(segment
		(start 66.341777 14.937232)
		(end 66.90073 14.937232)
		(width 0.104648)
		(layer "In2.Cu")
		(net "DDR0_32A_DQ31")
	)
	(segment
		(start 67.782821 13.937234)
		(end 67.900728 13.937234)
		(width 0.104648)
		(layer "In2.Cu")
		(net "DDR0_32A_DQ31")
	)
	(segment
		(start 72.631071 13.056083)
		(end 73.030994 13.456006)
		(width 0.12065)
		(layer "In2.Cu")
		(net "DDR0_32A_DQ31")
	)
	(segment
		(start 68.341773 13.446227)
		(end 68.341773 13.378282)
		(width 0.104648)
		(layer "In2.Cu")
		(net "DDR0_32A_DQ31")
	)
	(segment
		(start 68.326 13.462)
		(end 68.341773 13.446227)
		(width 0.104648)
		(layer "In2.Cu")
		(net "DDR0_32A_DQ31")
	)
	(segment
		(start 68.573269 13.146786)
		(end 70.931786 13.146786)
		(width 0.104648)
		(layer "In2.Cu")
		(net "DDR0_32A_DQ31")
	)
	(segment
		(start 68.148505 13.893521)
		(end 68.326 13.716025)
		(width 0.104648)
		(layer "In2.Cu")
		(net "DDR0_32A_DQ31")
	)
	(segment
		(start 70.931786 13.146786)
		(end 71.994624 13.146786)
		(width 0.12065)
		(layer "In2.Cu")
		(net "DDR0_32A_DQ31")
	)
	(segment
		(start 71.994624 13.146786)
		(end 72.085327 13.056083)
		(width 0.12065)
		(layer "In2.Cu")
		(net "DDR0_32A_DQ31")
	)
	(segment
		(start 67.900728 13.937234)
		(end 67.944441 13.893521)
		(width 0.104648)
		(layer "In2.Cu")
		(net "DDR0_32A_DQ31")
	)
	(segment
		(start 67.944441 13.893521)
		(end 68.148505 13.893521)
		(width 0.104648)
		(layer "In2.Cu")
		(net "DDR0_32A_DQ31")
	)
	(segment
		(start 67.736999 15.542006)
		(end 67.237 16.042005)
		(width 0.13208)
		(layer "F.Cu")
		(net "DDR0_32A_DQ30")
	)
	(via
		(at 67.736999 15.542006)
		(size 0.4826)
		(drill 0.20574)
		(layers "F.Cu" "B.Cu")
		(net "DDR0_32A_DQ30")
	)
	(segment
		(start 73.451009 14.656003)
		(end 73.05101 14.256004)
		(width 0.254)
		(layer "B.Cu")
		(net "DDR0_32A_DQ30")
	)
	(segment
		(start 71.684261 14.986)
		(end 71.119949 14.986)
		(width 0.12065)
		(layer "In2.Cu")
		(net "DDR0_32A_DQ30")
	)
	(segment
		(start 72.650934 15.221534)
		(end 72.650934 14.890318)
		(width 0.12065)
		(layer "In2.Cu")
		(net "DDR0_32A_DQ30")
	)
	(segment
		(start 71.119949 14.986)
		(end 71.074432 14.940534)
		(width 0.104648)
		(layer "In2.Cu")
		(net "DDR0_32A_DQ30")
	)
	(segment
		(start 73.571075 15.455925)
		(end 72.885325 15.455925)
		(width 0.12065)
		(layer "In2.Cu")
		(net "DDR0_32A_DQ30")
	)
	(segment
		(start 73.685324 14.655927)
		(end 73.771531 14.655927)
		(width 0.12065)
		(layer "In2.Cu")
		(net "DDR0_32A_DQ30")
	)
	(segment
		(start 72.885325 15.455925)
		(end 72.650934 15.221534)
		(width 0.12065)
		(layer "In2.Cu")
		(net "DDR0_32A_DQ30")
	)
	(segment
		(start 69.487821 14.940534)
		(end 69.281573 15.146782)
		(width 0.104648)
		(layer "In2.Cu")
		(net "DDR0_32A_DQ30")
	)
	(segment
		(start 72.014182 14.655927)
		(end 71.684261 14.986)
		(width 0.12065)
		(layer "In2.Cu")
		(net "DDR0_32A_DQ30")
	)
	(segment
		(start 68.546243 15.146782)
		(end 68.151019 15.542006)
		(width 0.104648)
		(layer "In2.Cu")
		(net "DDR0_32A_DQ30")
	)
	(segment
		(start 71.074432 14.940534)
		(end 69.487821 14.940534)
		(width 0.104648)
		(layer "In2.Cu")
		(net "DDR0_32A_DQ30")
	)
	(segment
		(start 73.05101 14.256004)
		(end 73.285401 14.256004)
		(width 0.12065)
		(layer "In2.Cu")
		(net "DDR0_32A_DQ30")
	)
	(segment
		(start 73.771531 14.655927)
		(end 73.985984 14.870379)
		(width 0.12065)
		(layer "In2.Cu")
		(net "DDR0_32A_DQ30")
	)
	(segment
		(start 72.650934 14.890318)
		(end 72.416543 14.655927)
		(width 0.12065)
		(layer "In2.Cu")
		(net "DDR0_32A_DQ30")
	)
	(segment
		(start 69.281573 15.146782)
		(end 68.546243 15.146782)
		(width 0.104648)
		(layer "In2.Cu")
		(net "DDR0_32A_DQ30")
	)
	(segment
		(start 73.985984 15.041016)
		(end 73.571075 15.455925)
		(width 0.12065)
		(layer "In2.Cu")
		(net "DDR0_32A_DQ30")
	)
	(segment
		(start 73.285401 14.256004)
		(end 73.685324 14.655927)
		(width 0.12065)
		(layer "In2.Cu")
		(net "DDR0_32A_DQ30")
	)
	(segment
		(start 68.151019 15.542006)
		(end 67.736999 15.542006)
		(width 0.104648)
		(layer "In2.Cu")
		(net "DDR0_32A_DQ30")
	)
	(segment
		(start 73.985984 14.870379)
		(end 73.985984 15.041016)
		(width 0.12065)
		(layer "In2.Cu")
		(net "DDR0_32A_DQ30")
	)
	(segment
		(start 72.416543 14.655927)
		(end 72.014182 14.655927)
		(width 0.12065)
		(layer "In2.Cu")
		(net "DDR0_32A_DQ30")
	)
	(segment
		(start 68.736997 15.542006)
		(end 68.236998 16.042005)
		(width 0.13208)
		(layer "F.Cu")
		(net "DDR0_32A_DQ29")
	)
	(via
		(at 68.736997 15.542006)
		(size 0.4826)
		(drill 0.25654)
		(layers "F.Cu" "B.Cu")
		(net "DDR0_32A_DQ29")
	)
	(segment
		(start 71.851012 14.656003)
		(end 72.251011 15.056002)
		(width 0.14732)
		(layer "B.Cu")
		(net "DDR0_32A_DQ29")
	)
	(segment
		(start 72.39 15.88135)
		(end 72.39 15.176652)
		(width 0.12065)
		(layer "In2.Cu")
		(net "DDR0_32A_DQ29")
	)
	(segment
		(start 68.900726 16.937228)
		(end 69.341771 16.496182)
		(width 0.104648)
		(layer "In2.Cu")
		(net "DDR0_32A_DQ29")
	)
	(segment
		(start 69.341771 15.378278)
		(end 69.573267 15.146782)
		(width 0.104648)
		(layer "In2.Cu")
		(net "DDR0_32A_DQ29")
	)
	(segment
		(start 68.267758 15.806217)
		(end 68.267758 16.83258)
		(width 0.104648)
		(layer "In2.Cu")
		(net "DDR0_32A_DQ29")
	)
	(segment
		(start 72.26935 15.056002)
		(end 72.251011 15.056002)
		(width 0.12065)
		(layer "In2.Cu")
		(net "DDR0_32A_DQ29")
	)
	(segment
		(start 69.596 16.124047)
		(end 69.596 15.959963)
		(width 0.104648)
		(layer "In2.Cu")
		(net "DDR0_32A_DQ29")
	)
	(segment
		(start 68.372406 16.937228)
		(end 68.900726 16.937228)
		(width 0.104648)
		(layer "In2.Cu")
		(net "DDR0_32A_DQ29")
	)
	(segment
		(start 68.736997 15.542006)
		(end 68.531969 15.542006)
		(width 0.104648)
		(layer "In2.Cu")
		(net "DDR0_32A_DQ29")
	)
	(segment
		(start 69.341771 16.378276)
		(end 69.596 16.124047)
		(width 0.104648)
		(layer "In2.Cu")
		(net "DDR0_32A_DQ29")
	)
	(segment
		(start 71.240701 15.233701)
		(end 72.009 16.002)
		(width 0.12065)
		(layer "In2.Cu")
		(net "DDR0_32A_DQ29")
	)
	(segment
		(start 69.341771 15.705734)
		(end 69.341771 15.378278)
		(width 0.104648)
		(layer "In2.Cu")
		(net "DDR0_32A_DQ29")
	)
	(segment
		(start 69.596 15.959963)
		(end 69.341771 15.705734)
		(width 0.104648)
		(layer "In2.Cu")
		(net "DDR0_32A_DQ29")
	)
	(segment
		(start 70.900722 15.146782)
		(end 70.987641 15.233701)
		(width 0.104648)
		(layer "In2.Cu")
		(net "DDR0_32A_DQ29")
	)
	(segment
		(start 72.39 15.176652)
		(end 72.26935 15.056002)
		(width 0.12065)
		(layer "In2.Cu")
		(net "DDR0_32A_DQ29")
	)
	(segment
		(start 69.573267 15.146782)
		(end 70.900722 15.146782)
		(width 0.104648)
		(layer "In2.Cu")
		(net "DDR0_32A_DQ29")
	)
	(segment
		(start 68.531969 15.542006)
		(end 68.267758 15.806217)
		(width 0.104648)
		(layer "In2.Cu")
		(net "DDR0_32A_DQ29")
	)
	(segment
		(start 70.987641 15.233701)
		(end 71.12 15.233701)
		(width 0.104648)
		(layer "In2.Cu")
		(net "DDR0_32A_DQ29")
	)
	(segment
		(start 69.341771 16.496182)
		(end 69.341771 16.378276)
		(width 0.104648)
		(layer "In2.Cu")
		(net "DDR0_32A_DQ29")
	)
	(segment
		(start 71.12 15.233701)
		(end 71.240701 15.233701)
		(width 0.12065)
		(layer "In2.Cu")
		(net "DDR0_32A_DQ29")
	)
	(segment
		(start 72.009 16.002)
		(end 72.26935 16.002)
		(width 0.12065)
		(layer "In2.Cu")
		(net "DDR0_32A_DQ29")
	)
	(segment
		(start 68.267758 16.83258)
		(end 68.372406 16.937228)
		(width 0.104648)
		(layer "In2.Cu")
		(net "DDR0_32A_DQ29")
	)
	(segment
		(start 72.26935 16.002)
		(end 72.39 15.88135)
		(width 0.12065)
		(layer "In2.Cu")
		(net "DDR0_32A_DQ29")
	)
	(segment
		(start 67.736999 16.542004)
		(end 67.237 17.042003)
		(width 0.13208)
		(layer "F.Cu")
		(net "DDR0_32A_DQ28")
	)
	(via
		(at 67.736999 16.542004)
		(size 0.4826)
		(drill 0.20574)
		(layers "F.Cu" "B.Cu")
		(net "DDR0_32A_DQ28")
	)
	(segment
		(start 72.65101 18.655995)
		(end 72.251011 18.255996)
		(width 0.14732)
		(layer "B.Cu")
		(net "DDR0_32A_DQ28")
	)
	(segment
		(start 68.140224 17.709058)
		(end 67.818 18.031282)
		(width 0.12065)
		(layer "In2.Cu")
		(net "DDR0_32A_DQ28")
	)
	(segment
		(start 69.260872 19.954621)
		(end 71.231379 19.954621)
		(width 0.12065)
		(layer "In2.Cu")
		(net "DDR0_32A_DQ28")
	)
	(segment
		(start 72.130361 18.656071)
		(end 72.251011 18.535421)
		(width 0.12065)
		(layer "In2.Cu")
		(net "DDR0_32A_DQ28")
	)
	(segment
		(start 71.231379 19.954621)
		(end 71.851088 19.334912)
		(width 0.12065)
		(layer "In2.Cu")
		(net "DDR0_32A_DQ28")
	)
	(segment
		(start 69.140222 19.374942)
		(end 69.140222 19.833971)
		(width 0.12065)
		(layer "In2.Cu")
		(net "DDR0_32A_DQ28")
	)
	(segment
		(start 69.140222 19.833971)
		(end 69.260872 19.954621)
		(width 0.12065)
		(layer "In2.Cu")
		(net "DDR0_32A_DQ28")
	)
	(segment
		(start 67.736999 16.971721)
		(end 68.140224 17.374946)
		(width 0.12065)
		(layer "In2.Cu")
		(net "DDR0_32A_DQ28")
	)
	(segment
		(start 72.251011 18.535421)
		(end 72.251011 18.255996)
		(width 0.12065)
		(layer "In2.Cu")
		(net "DDR0_32A_DQ28")
	)
	(segment
		(start 67.736999 16.542004)
		(end 67.736999 16.971721)
		(width 0.12065)
		(layer "In2.Cu")
		(net "DDR0_32A_DQ28")
	)
	(segment
		(start 71.851088 19.334912)
		(end 71.851088 18.89031)
		(width 0.12065)
		(layer "In2.Cu")
		(net "DDR0_32A_DQ28")
	)
	(segment
		(start 68.287773 19.138773)
		(end 68.904053 19.138773)
		(width 0.12065)
		(layer "In2.Cu")
		(net "DDR0_32A_DQ28")
	)
	(segment
		(start 72.085327 18.656071)
		(end 72.130361 18.656071)
		(width 0.12065)
		(layer "In2.Cu")
		(net "DDR0_32A_DQ28")
	)
	(segment
		(start 68.140224 17.374946)
		(end 68.140224 17.709058)
		(width 0.12065)
		(layer "In2.Cu")
		(net "DDR0_32A_DQ28")
	)
	(segment
		(start 68.904053 19.138773)
		(end 69.140222 19.374942)
		(width 0.12065)
		(layer "In2.Cu")
		(net "DDR0_32A_DQ28")
	)
	(segment
		(start 71.851088 18.89031)
		(end 72.085327 18.656071)
		(width 0.12065)
		(layer "In2.Cu")
		(net "DDR0_32A_DQ28")
	)
	(segment
		(start 67.818 18.669)
		(end 68.287773 19.138773)
		(width 0.12065)
		(layer "In2.Cu")
		(net "DDR0_32A_DQ28")
	)
	(segment
		(start 67.818 18.031282)
		(end 67.818 18.669)
		(width 0.12065)
		(layer "In2.Cu")
		(net "DDR0_32A_DQ28")
	)
	(segment
		(start 70.736993 16.542004)
		(end 70.236994 17.042003)
		(width 0.13208)
		(layer "F.Cu")
		(net "DDR0_32A_DQ27")
	)
	(via
		(at 70.736993 16.542004)
		(size 0.4826)
		(drill 0.20574)
		(layers "F.Cu" "B.Cu")
		(net "DDR0_32A_DQ27")
	)
	(segment
		(start 74.251007 17.855997)
		(end 73.851008 18.255996)
		(width 0.254)
		(layer "B.Cu")
		(net "DDR0_32A_DQ27")
	)
	(segment
		(start 73.851008 18.255996)
		(end 74.251083 18.656071)
		(width 0.12065)
		(layer "In2.Cu")
		(net "DDR0_32A_DQ27")
	)
	(segment
		(start 75.051082 19.335267)
		(end 74.930432 19.455917)
		(width 0.12065)
		(layer "In2.Cu")
		(net "DDR0_32A_DQ27")
	)
	(segment
		(start 70.857643 17.018)
		(end 70.736993 16.89735)
		(width 0.12065)
		(layer "In2.Cu")
		(net "DDR0_32A_DQ27")
	)
	(segment
		(start 75.051082 18.776721)
		(end 75.051082 19.335267)
		(width 0.12065)
		(layer "In2.Cu")
		(net "DDR0_32A_DQ27")
	)
	(segment
		(start 74.930432 18.656071)
		(end 75.051082 18.776721)
		(width 0.12065)
		(layer "In2.Cu")
		(net "DDR0_32A_DQ27")
	)
	(segment
		(start 72.651087 18.549087)
		(end 72.651087 17.13865)
		(width 0.12065)
		(layer "In2.Cu")
		(net "DDR0_32A_DQ27")
	)
	(segment
		(start 73.685324 19.455917)
		(end 73.450933 19.221526)
		(width 0.12065)
		(layer "In2.Cu")
		(net "DDR0_32A_DQ27")
	)
	(segment
		(start 72.758071 18.656071)
		(end 72.651087 18.549087)
		(width 0.12065)
		(layer "In2.Cu")
		(net "DDR0_32A_DQ27")
	)
	(segment
		(start 74.251083 18.656071)
		(end 74.930432 18.656071)
		(width 0.12065)
		(layer "In2.Cu")
		(net "DDR0_32A_DQ27")
	)
	(segment
		(start 72.651087 17.13865)
		(end 72.530437 17.018)
		(width 0.12065)
		(layer "In2.Cu")
		(net "DDR0_32A_DQ27")
	)
	(segment
		(start 73.216694 18.656071)
		(end 72.758071 18.656071)
		(width 0.12065)
		(layer "In2.Cu")
		(net "DDR0_32A_DQ27")
	)
	(segment
		(start 74.930432 19.455917)
		(end 73.685324 19.455917)
		(width 0.12065)
		(layer "In2.Cu")
		(net "DDR0_32A_DQ27")
	)
	(segment
		(start 73.450933 18.89031)
		(end 73.216694 18.656071)
		(width 0.12065)
		(layer "In2.Cu")
		(net "DDR0_32A_DQ27")
	)
	(segment
		(start 70.736993 16.89735)
		(end 70.736993 16.542004)
		(width 0.12065)
		(layer "In2.Cu")
		(net "DDR0_32A_DQ27")
	)
	(segment
		(start 72.530437 17.018)
		(end 70.857643 17.018)
		(width 0.12065)
		(layer "In2.Cu")
		(net "DDR0_32A_DQ27")
	)
	(segment
		(start 73.450933 19.221526)
		(end 73.450933 18.89031)
		(width 0.12065)
		(layer "In2.Cu")
		(net "DDR0_32A_DQ27")
	)
	(segment
		(start 69.736995 16.542004)
		(end 69.236996 17.042003)
		(width 0.13208)
		(layer "F.Cu")
		(net "DDR0_32A_DQ26")
	)
	(via
		(at 69.736995 16.542004)
		(size 0.4826)
		(drill 0.25654)
		(layers "F.Cu" "B.Cu")
		(net "DDR0_32A_DQ26")
	)
	(segment
		(start 71.851012 17.855997)
		(end 72.251011 17.455998)
		(width 0.14732)
		(layer "B.Cu")
		(net "DDR0_32A_DQ26")
	)
	(segment
		(start 69.639637 19.05)
		(end 69.760287 18.92935)
		(width 0.12065)
		(layer "In2.Cu")
		(net "DDR0_32A_DQ26")
	)
	(segment
		(start 69.760287 18.28165)
		(end 69.880937 18.161)
		(width 0.12065)
		(layer "In2.Cu")
		(net "DDR0_32A_DQ26")
	)
	(segment
		(start 71.627975 18.669025)
		(end 71.851088 18.445912)
		(width 0.12065)
		(layer "In2.Cu")
		(net "DDR0_32A_DQ26")
	)
	(segment
		(start 70.141287 18.161)
		(end 70.261937 18.28165)
		(width 0.12065)
		(layer "In2.Cu")
		(net "DDR0_32A_DQ26")
	)
	(segment
		(start 69.736995 16.542004)
		(end 69.215 17.063999)
		(width 0.12065)
		(layer "In2.Cu")
		(net "DDR0_32A_DQ26")
	)
	(segment
		(start 70.739 18.288)
		(end 70.866 18.161)
		(width 0.12065)
		(layer "In2.Cu")
		(net "DDR0_32A_DQ26")
	)
	(segment
		(start 72.206129 17.455998)
		(end 72.251011 17.455998)
		(width 0.12065)
		(layer "In2.Cu")
		(net "DDR0_32A_DQ26")
	)
	(segment
		(start 70.739 18.923)
		(end 70.739 18.288)
		(width 0.12065)
		(layer "In2.Cu")
		(net "DDR0_32A_DQ26")
	)
	(segment
		(start 69.215 17.063999)
		(end 69.215 18.796)
		(width 0.12065)
		(layer "In2.Cu")
		(net "DDR0_32A_DQ26")
	)
	(segment
		(start 70.261937 18.28165)
		(end 70.261937 18.92935)
		(width 0.12065)
		(layer "In2.Cu")
		(net "DDR0_32A_DQ26")
	)
	(segment
		(start 69.215 18.796)
		(end 69.469 19.05)
		(width 0.12065)
		(layer "In2.Cu")
		(net "DDR0_32A_DQ26")
	)
	(segment
		(start 72.205977 17.455845)
		(end 72.206129 17.455998)
		(width 0.12065)
		(layer "In2.Cu")
		(net "DDR0_32A_DQ26")
	)
	(segment
		(start 71.851088 17.810734)
		(end 72.205977 17.455845)
		(width 0.12065)
		(layer "In2.Cu")
		(net "DDR0_32A_DQ26")
	)
	(segment
		(start 71.374 18.669)
		(end 71.627949 18.669)
		(width 0.12065)
		(layer "In2.Cu")
		(net "DDR0_32A_DQ26")
	)
	(segment
		(start 70.382587 19.05)
		(end 70.612 19.05)
		(width 0.12065)
		(layer "In2.Cu")
		(net "DDR0_32A_DQ26")
	)
	(segment
		(start 71.12 18.161)
		(end 71.247 18.288)
		(width 0.12065)
		(layer "In2.Cu")
		(net "DDR0_32A_DQ26")
	)
	(segment
		(start 69.880937 18.161)
		(end 70.141287 18.161)
		(width 0.12065)
		(layer "In2.Cu")
		(net "DDR0_32A_DQ26")
	)
	(segment
		(start 69.469 19.05)
		(end 69.639637 19.05)
		(width 0.12065)
		(layer "In2.Cu")
		(net "DDR0_32A_DQ26")
	)
	(segment
		(start 70.261937 18.92935)
		(end 70.382587 19.05)
		(width 0.12065)
		(layer "In2.Cu")
		(net "DDR0_32A_DQ26")
	)
	(segment
		(start 70.866 18.161)
		(end 71.12 18.161)
		(width 0.12065)
		(layer "In2.Cu")
		(net "DDR0_32A_DQ26")
	)
	(segment
		(start 71.627949 18.669)
		(end 71.627975 18.669025)
		(width 0.12065)
		(layer "In2.Cu")
		(net "DDR0_32A_DQ26")
	)
	(segment
		(start 71.247 18.542)
		(end 71.374 18.669)
		(width 0.12065)
		(layer "In2.Cu")
		(net "DDR0_32A_DQ26")
	)
	(segment
		(start 71.247 18.288)
		(end 71.247 18.542)
		(width 0.12065)
		(layer "In2.Cu")
		(net "DDR0_32A_DQ26")
	)
	(segment
		(start 70.612 19.05)
		(end 70.739 18.923)
		(width 0.12065)
		(layer "In2.Cu")
		(net "DDR0_32A_DQ26")
	)
	(segment
		(start 71.851088 18.445912)
		(end 71.851088 17.810734)
		(width 0.12065)
		(layer "In2.Cu")
		(net "DDR0_32A_DQ26")
	)
	(segment
		(start 69.760287 18.92935)
		(end 69.760287 18.28165)
		(width 0.12065)
		(layer "In2.Cu")
		(net "DDR0_32A_DQ26")
	)
	(segment
		(start 66.737001 17.542002)
		(end 66.237002 18.042001)
		(width 0.13208)
		(layer "F.Cu")
		(net "DDR0_32A_DQ25")
	)
	(via
		(at 66.737001 17.542002)
		(size 0.4826)
		(drill 0.20574)
		(layers "F.Cu" "B.Cu")
		(net "DDR0_32A_DQ25")
	)
	(segment
		(start 73.451009 18.655995)
		(end 73.05101 19.055994)
		(width 0.254)
		(layer "B.Cu")
		(net "DDR0_32A_DQ25")
	)
	(segment
		(start 68.140224 19.374942)
		(end 67.904055 19.138773)
		(width 0.12065)
		(layer "In2.Cu")
		(net "DDR0_32A_DQ25")
	)
	(segment
		(start 68.769916 20.255916)
		(end 68.140224 19.626224)
		(width 0.12065)
		(layer "In2.Cu")
		(net "DDR0_32A_DQ25")
	)
	(segment
		(start 72.416848 20.255916)
		(end 68.769916 20.255916)
		(width 0.12065)
		(layer "In2.Cu")
		(net "DDR0_32A_DQ25")
	)
	(segment
		(start 72.651087 19.690309)
		(end 72.651087 20.021677)
		(width 0.12065)
		(layer "In2.Cu")
		(net "DDR0_32A_DQ25")
	)
	(segment
		(start 72.898 19.443395)
		(end 72.651087 19.690309)
		(width 0.12065)
		(layer "In2.Cu")
		(net "DDR0_32A_DQ25")
	)
	(segment
		(start 68.140224 19.626224)
		(end 68.140224 19.374942)
		(width 0.12065)
		(layer "In2.Cu")
		(net "DDR0_32A_DQ25")
	)
	(segment
		(start 72.898 19.209004)
		(end 72.898 19.443395)
		(width 0.12065)
		(layer "In2.Cu")
		(net "DDR0_32A_DQ25")
	)
	(segment
		(start 67.652773 19.138773)
		(end 67.437025 18.923025)
		(width 0.12065)
		(layer "In2.Cu")
		(net "DDR0_32A_DQ25")
	)
	(segment
		(start 67.904055 19.138773)
		(end 67.652773 19.138773)
		(width 0.12065)
		(layer "In2.Cu")
		(net "DDR0_32A_DQ25")
	)
	(segment
		(start 67.183 18.923025)
		(end 66.737001 18.477027)
		(width 0.12065)
		(layer "In2.Cu")
		(net "DDR0_32A_DQ25")
	)
	(segment
		(start 72.651087 20.021677)
		(end 72.416848 20.255916)
		(width 0.12065)
		(layer "In2.Cu")
		(net "DDR0_32A_DQ25")
	)
	(segment
		(start 73.05101 19.055994)
		(end 72.898 19.209004)
		(width 0.12065)
		(layer "In2.Cu")
		(net "DDR0_32A_DQ25")
	)
	(segment
		(start 67.437025 18.923025)
		(end 67.183 18.923025)
		(width 0.12065)
		(layer "In2.Cu")
		(net "DDR0_32A_DQ25")
	)
	(segment
		(start 66.737001 18.477027)
		(end 66.737001 17.542002)
		(width 0.12065)
		(layer "In2.Cu")
		(net "DDR0_32A_DQ25")
	)
	(segment
		(start 66.737001 15.542006)
		(end 66.237002 16.042005)
		(width 0.13208)
		(layer "F.Cu")
		(net "DDR0_32A_DQ24")
	)
	(via
		(at 66.737001 15.542006)
		(size 0.4826)
		(drill 0.25654)
		(layers "F.Cu" "B.Cu")
		(net "DDR0_32A_DQ24")
	)
	(segment
		(start 71.851012 13.856005)
		(end 72.251011 14.256004)
		(width 0.14732)
		(layer "B.Cu")
		(net "DDR0_32A_DQ24")
	)
	(segment
		(start 72.098738 14.408277)
		(end 72.251011 14.256004)
		(width 0.12065)
		(layer "In2.Cu")
		(net "DDR0_32A_DQ24")
	)
	(segment
		(start 66.737001 15.542006)
		(end 66.737001 15.810001)
		(width 0.12065)
		(layer "In2.Cu")
		(net "DDR0_32A_DQ24")
	)
	(segment
		(start 69.897422 14.143482)
		(end 70.162979 14.409039)
		(width 0.104648)
		(layer "In2.Cu")
		(net "DDR0_32A_DQ24")
	)
	(segment
		(start 67.341775 15.378278)
		(end 67.573271 15.146782)
		(width 0.104648)
		(layer "In2.Cu")
		(net "DDR0_32A_DQ24")
	)
	(segment
		(start 68.573269 14.146784)
		(end 68.900726 14.146784)
		(width 0.104648)
		(layer "In2.Cu")
		(net "DDR0_32A_DQ24")
	)
	(segment
		(start 66.802 16.002025)
		(end 67.030041 16.230067)
		(width 0.104648)
		(layer "In2.Cu")
		(net "DDR0_32A_DQ24")
	)
	(segment
		(start 70.162979 14.409039)
		(end 70.31101 14.409039)
		(width 0.104648)
		(layer "In2.Cu")
		(net "DDR0_32A_DQ24")
	)
	(segment
		(start 70.31101 14.409039)
		(end 70.573265 14.146784)
		(width 0.104648)
		(layer "In2.Cu")
		(net "DDR0_32A_DQ24")
	)
	(segment
		(start 66.737001 15.810001)
		(end 66.802 15.875)
		(width 0.12065)
		(layer "In2.Cu")
		(net "DDR0_32A_DQ24")
	)
	(segment
		(start 71.911566 14.408277)
		(end 72.098738 14.408277)
		(width 0.12065)
		(layer "In2.Cu")
		(net "DDR0_32A_DQ24")
	)
	(segment
		(start 69.311012 14.409039)
		(end 69.576569 14.143482)
		(width 0.104648)
		(layer "In2.Cu")
		(net "DDR0_32A_DQ24")
	)
	(segment
		(start 67.982871 15.146782)
		(end 68.341773 14.78788)
		(width 0.104648)
		(layer "In2.Cu")
		(net "DDR0_32A_DQ24")
	)
	(segment
		(start 68.341773 14.37828)
		(end 68.573269 14.146784)
		(width 0.104648)
		(layer "In2.Cu")
		(net "DDR0_32A_DQ24")
	)
	(segment
		(start 71.104938 14.351)
		(end 71.12 14.351)
		(width 0.104648)
		(layer "In2.Cu")
		(net "DDR0_32A_DQ24")
	)
	(segment
		(start 71.714893 14.605)
		(end 71.911566 14.408277)
		(width 0.12065)
		(layer "In2.Cu")
		(net "DDR0_32A_DQ24")
	)
	(segment
		(start 69.162981 14.409039)
		(end 69.311012 14.409039)
		(width 0.104648)
		(layer "In2.Cu")
		(net "DDR0_32A_DQ24")
	)
	(segment
		(start 67.573271 15.146782)
		(end 67.982871 15.146782)
		(width 0.104648)
		(layer "In2.Cu")
		(net "DDR0_32A_DQ24")
	)
	(segment
		(start 71.214996 14.351)
		(end 71.468996 14.605)
		(width 0.12065)
		(layer "In2.Cu")
		(net "DDR0_32A_DQ24")
	)
	(segment
		(start 67.564 16.156051)
		(end 67.564 15.927984)
		(width 0.104648)
		(layer "In2.Cu")
		(net "DDR0_32A_DQ24")
	)
	(segment
		(start 67.489984 16.230067)
		(end 67.564 16.156051)
		(width 0.104648)
		(layer "In2.Cu")
		(net "DDR0_32A_DQ24")
	)
	(segment
		(start 67.030041 16.230067)
		(end 67.489984 16.230067)
		(width 0.104648)
		(layer "In2.Cu")
		(net "DDR0_32A_DQ24")
	)
	(segment
		(start 71.12 14.351)
		(end 71.214996 14.351)
		(width 0.12065)
		(layer "In2.Cu")
		(net "DDR0_32A_DQ24")
	)
	(segment
		(start 68.900726 14.146784)
		(end 69.162981 14.409039)
		(width 0.104648)
		(layer "In2.Cu")
		(net "DDR0_32A_DQ24")
	)
	(segment
		(start 68.341773 14.78788)
		(end 68.341773 14.37828)
		(width 0.104648)
		(layer "In2.Cu")
		(net "DDR0_32A_DQ24")
	)
	(segment
		(start 70.900722 14.146784)
		(end 71.104938 14.351)
		(width 0.104648)
		(layer "In2.Cu")
		(net "DDR0_32A_DQ24")
	)
	(segment
		(start 70.573265 14.146784)
		(end 70.900722 14.146784)
		(width 0.104648)
		(layer "In2.Cu")
		(net "DDR0_32A_DQ24")
	)
	(segment
		(start 67.341775 15.705734)
		(end 67.341775 15.378278)
		(width 0.104648)
		(layer "In2.Cu")
		(net "DDR0_32A_DQ24")
	)
	(segment
		(start 67.564 15.927984)
		(end 67.341775 15.705734)
		(width 0.104648)
		(layer "In2.Cu")
		(net "DDR0_32A_DQ24")
	)
	(segment
		(start 66.802 15.875)
		(end 66.802 16.002025)
		(width 0.104648)
		(layer "In2.Cu")
		(net "DDR0_32A_DQ24")
	)
	(segment
		(start 71.468996 14.605)
		(end 71.714893 14.605)
		(width 0.12065)
		(layer "In2.Cu")
		(net "DDR0_32A_DQ24")
	)
	(segment
		(start 69.576569 14.143482)
		(end 69.897422 14.143482)
		(width 0.104648)
		(layer "In2.Cu")
		(net "DDR0_32A_DQ24")
	)
	(segment
		(start 70.736993 14.542008)
		(end 70.236994 15.042007)
		(width 0.13208)
		(layer "F.Cu")
		(net "DDR0_32A_DQ23")
	)
	(via
		(at 70.736993 14.542008)
		(size 0.4826)
		(drill 0.20574)
		(layers "F.Cu" "B.Cu")
		(net "DDR0_32A_DQ23")
	)
	(segment
		(start 77.451001 17.855997)
		(end 77.051002 18.255996)
		(width 0.254)
		(layer "B.Cu")
		(net "DDR0_32A_DQ23")
	)
	(segment
		(start 70.736993 14.542008)
		(end 70.930008 14.542008)
		(width 0.12065)
		(layer "In3.Cu")
		(net "DDR0_32A_DQ23")
	)
	(segment
		(start 78.2701 18.097246)
		(end 78.11135 18.255996)
		(width 0.12065)
		(layer "In3.Cu")
		(net "DDR0_32A_DQ23")
	)
	(segment
		(start 78.0923 16.7513)
		(end 78.2701 16.9291)
		(width 0.12065)
		(layer "In3.Cu")
		(net "DDR0_32A_DQ23")
	)
	(segment
		(start 78.11135 18.255996)
		(end 77.051002 18.255996)
		(width 0.12065)
		(layer "In3.Cu")
		(net "DDR0_32A_DQ23")
	)
	(segment
		(start 78.2701 16.9291)
		(end 78.2701 18.097246)
		(width 0.12065)
		(layer "In3.Cu")
		(net "DDR0_32A_DQ23")
	)
	(segment
		(start 74.886541 16.7513)
		(end 78.0923 16.7513)
		(width 0.12065)
		(layer "In3.Cu")
		(net "DDR0_32A_DQ23")
	)
	(segment
		(start 70.930008 14.542008)
		(end 71.247 14.859)
		(width 0.12065)
		(layer "In3.Cu")
		(net "DDR0_32A_DQ23")
	)
	(segment
		(start 71.247 15.482697)
		(end 71.885302 16.120999)
		(width 0.12065)
		(layer "In3.Cu")
		(net "DDR0_32A_DQ23")
	)
	(segment
		(start 71.247 14.859)
		(end 71.247 15.482697)
		(width 0.12065)
		(layer "In3.Cu")
		(net "DDR0_32A_DQ23")
	)
	(segment
		(start 71.885302 16.120999)
		(end 74.25624 16.120999)
		(width 0.12065)
		(layer "In3.Cu")
		(net "DDR0_32A_DQ23")
	)
	(segment
		(start 74.25624 16.120999)
		(end 74.886541 16.7513)
		(width 0.12065)
		(layer "In3.Cu")
		(net "DDR0_32A_DQ23")
	)
	(segment
		(start 69.736995 14.542008)
		(end 69.236996 15.042007)
		(width 0.13208)
		(layer "F.Cu")
		(net "DDR0_32A_DQ22")
	)
	(via
		(at 69.736995 14.542008)
		(size 0.4826)
		(drill 0.20574)
		(layers "F.Cu" "B.Cu")
		(net "DDR0_32A_DQ22")
	)
	(segment
		(start 77.451001 18.655995)
		(end 77.051002 19.055994)
		(width 0.254)
		(layer "B.Cu")
		(net "DDR0_32A_DQ22")
	)
	(segment
		(start 77.6224 17.5768)
		(end 77.6224 17.1958)
		(width 0.12065)
		(layer "In3.Cu")
		(net "DDR0_32A_DQ22")
	)
	(segment
		(start 74.153649 16.368649)
		(end 71.782711 16.368649)
		(width 0.12065)
		(layer "In3.Cu")
		(net "DDR0_32A_DQ22")
	)
	(segment
		(start 70.041008 14.542008)
		(end 69.736995 14.542008)
		(width 0.104648)
		(layer "In3.Cu")
		(net "DDR0_32A_DQ22")
	)
	(segment
		(start 76.650926 18.655919)
		(end 76.650926 18.0594)
		(width 0.12065)
		(layer "In3.Cu")
		(net "DDR0_32A_DQ22")
	)
	(segment
		(start 74.841151 17.056151)
		(end 74.153649 16.368649)
		(width 0.12065)
		(layer "In3.Cu")
		(net "DDR0_32A_DQ22")
	)
	(segment
		(start 70.341769 15.705734)
		(end 70.341769 14.842769)
		(width 0.104648)
		(layer "In3.Cu")
		(net "DDR0_32A_DQ22")
	)
	(segment
		(start 77.6224 17.1958)
		(end 77.482751 17.056151)
		(width 0.12065)
		(layer "In3.Cu")
		(net "DDR0_32A_DQ22")
	)
	(segment
		(start 71.351292 15.93723)
		(end 71.12 15.93723)
		(width 0.12065)
		(layer "In3.Cu")
		(net "DDR0_32A_DQ22")
	)
	(segment
		(start 76.650926 18.0594)
		(end 76.930326 17.78)
		(width 0.12065)
		(layer "In3.Cu")
		(net "DDR0_32A_DQ22")
	)
	(segment
		(start 71.12 15.93723)
		(end 70.573265 15.93723)
		(width 0.104648)
		(layer "In3.Cu")
		(net "DDR0_32A_DQ22")
	)
	(segment
		(start 71.782711 16.368649)
		(end 71.351292 15.93723)
		(width 0.12065)
		(layer "In3.Cu")
		(net "DDR0_32A_DQ22")
	)
	(segment
		(start 70.573265 15.93723)
		(end 70.341769 15.705734)
		(width 0.104648)
		(layer "In3.Cu")
		(net "DDR0_32A_DQ22")
	)
	(segment
		(start 76.930326 17.78)
		(end 77.4192 17.78)
		(width 0.12065)
		(layer "In3.Cu")
		(net "DDR0_32A_DQ22")
	)
	(segment
		(start 70.341769 14.842769)
		(end 70.041008 14.542008)
		(width 0.104648)
		(layer "In3.Cu")
		(net "DDR0_32A_DQ22")
	)
	(segment
		(start 77.051002 19.055994)
		(end 76.650926 18.655919)
		(width 0.12065)
		(layer "In3.Cu")
		(net "DDR0_32A_DQ22")
	)
	(segment
		(start 77.4192 17.78)
		(end 77.6224 17.5768)
		(width 0.12065)
		(layer "In3.Cu")
		(net "DDR0_32A_DQ22")
	)
	(segment
		(start 77.482751 17.056151)
		(end 74.841151 17.056151)
		(width 0.12065)
		(layer "In3.Cu")
		(net "DDR0_32A_DQ22")
	)
	(segment
		(start 67.736999 13.54201)
		(end 67.237 14.042009)
		(width 0.13208)
		(layer "F.Cu")
		(net "DDR0_32A_DQ21")
	)
	(via
		(at 67.736999 13.54201)
		(size 0.4826)
		(drill 0.20574)
		(layers "F.Cu" "B.Cu")
		(net "DDR0_32A_DQ21")
	)
	(segment
		(start 75.851004 13.856005)
		(end 75.451005 13.456006)
		(width 0.254)
		(layer "B.Cu")
		(net "DDR0_32A_DQ21")
	)
	(segment
		(start 70.922032 12.940538)
		(end 69.487821 12.940538)
		(width 0.104648)
		(layer "In3.Cu")
		(net "DDR0_32A_DQ21")
	)
	(segment
		(start 76.650926 12.058726)
		(end 76.3778 11.7856)
		(width 0.12065)
		(layer "In3.Cu")
		(net "DDR0_32A_DQ21")
	)
	(segment
		(start 68.178045 13.54201)
		(end 67.736999 13.54201)
		(width 0.104648)
		(layer "In3.Cu")
		(net "DDR0_32A_DQ21")
	)
	(segment
		(start 76.650926 12.821691)
		(end 76.650926 12.058726)
		(width 0.12065)
		(layer "In3.Cu")
		(net "DDR0_32A_DQ21")
	)
	(segment
		(start 69.281573 13.146786)
		(end 68.573269 13.146786)
		(width 0.104648)
		(layer "In3.Cu")
		(net "DDR0_32A_DQ21")
	)
	(segment
		(start 76.3778 11.7856)
		(end 71.780425 11.7856)
		(width 0.12065)
		(layer "In3.Cu")
		(net "DDR0_32A_DQ21")
	)
	(segment
		(start 76.416687 13.05593)
		(end 76.650926 12.821691)
		(width 0.12065)
		(layer "In3.Cu")
		(net "DDR0_32A_DQ21")
	)
	(segment
		(start 71.780425 11.7856)
		(end 71.149616 12.416409)
		(width 0.12065)
		(layer "In3.Cu")
		(net "DDR0_32A_DQ21")
	)
	(segment
		(start 71.149616 12.712954)
		(end 70.957999 12.904572)
		(width 0.12065)
		(layer "In3.Cu")
		(net "DDR0_32A_DQ21")
	)
	(segment
		(start 71.149616 12.416409)
		(end 71.149616 12.712954)
		(width 0.12065)
		(layer "In3.Cu")
		(net "DDR0_32A_DQ21")
	)
	(segment
		(start 69.487821 12.940538)
		(end 69.281573 13.146786)
		(width 0.104648)
		(layer "In3.Cu")
		(net "DDR0_32A_DQ21")
	)
	(segment
		(start 68.573269 13.146786)
		(end 68.178045 13.54201)
		(width 0.104648)
		(layer "In3.Cu")
		(net "DDR0_32A_DQ21")
	)
	(segment
		(start 70.957999 12.904572)
		(end 70.922032 12.940538)
		(width 0.104648)
		(layer "In3.Cu")
		(net "DDR0_32A_DQ21")
	)
	(segment
		(start 75.451005 13.456006)
		(end 75.85108 13.05593)
		(width 0.12065)
		(layer "In3.Cu")
		(net "DDR0_32A_DQ21")
	)
	(segment
		(start 75.85108 13.05593)
		(end 76.416687 13.05593)
		(width 0.12065)
		(layer "In3.Cu")
		(net "DDR0_32A_DQ21")
	)
	(segment
		(start 65.737003 14.542008)
		(end 65.237004 15.042007)
		(width 0.13208)
		(layer "F.Cu")
		(net "DDR0_32A_DQ20")
	)
	(via
		(at 65.737003 14.542008)
		(size 0.4826)
		(drill 0.25654)
		(layers "F.Cu" "B.Cu")
		(net "DDR0_32A_DQ20")
	)
	(segment
		(start 75.851004 18.655995)
		(end 75.451005 19.055994)
		(width 0.254)
		(layer "B.Cu")
		(net "DDR0_32A_DQ20")
	)
	(segment
		(start 71.286878 17.184878)
		(end 71.957921 17.855921)
		(width 0.12065)
		(layer "In3.Cu")
		(net "DDR0_32A_DQ20")
	)
	(segment
		(start 69.132221 16.496182)
		(end 69.781039 17.145)
		(width 0.104648)
		(layer "In3.Cu")
		(net "DDR0_32A_DQ20")
	)
	(segment
		(start 69.132221 16.378276)
		(end 69.132221 16.496182)
		(width 0.104648)
		(layer "In3.Cu")
		(net "DDR0_32A_DQ20")
	)
	(segment
		(start 71.017333 17.184878)
		(end 71.12 17.184878)
		(width 0.104648)
		(layer "In3.Cu")
		(net "DDR0_32A_DQ20")
	)
	(segment
		(start 67.132225 15.496184)
		(end 67.782821 16.14678)
		(width 0.104648)
		(layer "In3.Cu")
		(net "DDR0_32A_DQ20")
	)
	(segment
		(start 65.737003 14.542008)
		(end 66.90073 15.146782)
		(width 0.104648)
		(layer "In3.Cu")
		(net "DDR0_32A_DQ20")
	)
	(segment
		(start 66.90073 15.146782)
		(end 67.132225 15.378278)
		(width 0.104648)
		(layer "In3.Cu")
		(net "DDR0_32A_DQ20")
	)
	(segment
		(start 71.12 17.184878)
		(end 71.286878 17.184878)
		(width 0.12065)
		(layer "In3.Cu")
		(net "DDR0_32A_DQ20")
	)
	(segment
		(start 67.782821 16.14678)
		(end 68.900726 16.14678)
		(width 0.104648)
		(layer "In3.Cu")
		(net "DDR0_32A_DQ20")
	)
	(segment
		(start 71.957921 17.855921)
		(end 72.416695 17.855921)
		(width 0.12065)
		(layer "In3.Cu")
		(net "DDR0_32A_DQ20")
	)
	(segment
		(start 72.650934 18.090159)
		(end 72.650934 18.09176)
		(width 0.12065)
		(layer "In3.Cu")
		(net "DDR0_32A_DQ20")
	)
	(segment
		(start 75.051082 18.656071)
		(end 75.451005 19.055994)
		(width 0.12065)
		(layer "In3.Cu")
		(net "DDR0_32A_DQ20")
	)
	(segment
		(start 72.650934 18.09176)
		(end 73.215246 18.656071)
		(width 0.12065)
		(layer "In3.Cu")
		(net "DDR0_32A_DQ20")
	)
	(segment
		(start 73.215246 18.656071)
		(end 75.051082 18.656071)
		(width 0.12065)
		(layer "In3.Cu")
		(net "DDR0_32A_DQ20")
	)
	(segment
		(start 67.132225 15.378278)
		(end 67.132225 15.496184)
		(width 0.104648)
		(layer "In3.Cu")
		(net "DDR0_32A_DQ20")
	)
	(segment
		(start 69.781039 17.145)
		(end 70.977455 17.145)
		(width 0.104648)
		(layer "In3.Cu")
		(net "DDR0_32A_DQ20")
	)
	(segment
		(start 72.416695 17.855921)
		(end 72.650934 18.090159)
		(width 0.12065)
		(layer "In3.Cu")
		(net "DDR0_32A_DQ20")
	)
	(segment
		(start 70.977455 17.145)
		(end 71.017333 17.184878)
		(width 0.104648)
		(layer "In3.Cu")
		(net "DDR0_32A_DQ20")
	)
	(segment
		(start 68.900726 16.14678)
		(end 69.132221 16.378276)
		(width 0.104648)
		(layer "In3.Cu")
		(net "DDR0_32A_DQ20")
	)
	(segment
		(start 70.736993 13.54201)
		(end 70.236994 14.042009)
		(width 0.13208)
		(layer "F.Cu")
		(net "DDR0_32A_DQ19")
	)
	(via
		(at 70.736993 13.54201)
		(size 0.4826)
		(drill 0.20574)
		(layers "F.Cu" "B.Cu")
		(net "DDR0_32A_DQ19")
	)
	(segment
		(start 77.451001 14.656003)
		(end 77.051002 14.256004)
		(width 0.254)
		(layer "B.Cu")
		(net "DDR0_32A_DQ19")
	)
	(segment
		(start 75.057 14.0208)
		(end 75.057 14.5288)
		(width 0.12065)
		(layer "In3.Cu")
		(net "DDR0_32A_DQ19")
	)
	(segment
		(start 73.685324 13.056083)
		(end 73.450933 13.290474)
		(width 0.12065)
		(layer "In3.Cu")
		(net "DDR0_32A_DQ19")
	)
	(segment
		(start 74.7776 14.8082)
		(end 74.3712 14.8082)
		(width 0.12065)
		(layer "In3.Cu")
		(net "DDR0_32A_DQ19")
	)
	(segment
		(start 74.3712 14.8082)
		(end 74.2442 14.6812)
		(width 0.12065)
		(layer "In3.Cu")
		(net "DDR0_32A_DQ19")
	)
	(segment
		(start 73.450933 13.290474)
		(end 73.450933 14.509267)
		(width 0.12065)
		(layer "In3.Cu")
		(net "DDR0_32A_DQ19")
	)
	(segment
		(start 72.650934 14.535277)
		(end 72.650934 13.290321)
		(width 0.12065)
		(layer "In3.Cu")
		(net "DDR0_32A_DQ19")
	)
	(segment
		(start 74.2442 14.6812)
		(end 74.2442 14.428572)
		(width 0.12065)
		(layer "In3.Cu")
		(net "DDR0_32A_DQ19")
	)
	(segment
		(start 72.771584 14.655927)
		(end 72.650934 14.535277)
		(width 0.12065)
		(layer "In3.Cu")
		(net "DDR0_32A_DQ19")
	)
	(segment
		(start 75.057 14.5288)
		(end 74.7776 14.8082)
		(width 0.12065)
		(layer "In3.Cu")
		(net "DDR0_32A_DQ19")
	)
	(segment
		(start 73.450933 14.509267)
		(end 73.304273 14.655927)
		(width 0.12065)
		(layer "In3.Cu")
		(net "DDR0_32A_DQ19")
	)
	(segment
		(start 74.2442 14.428572)
		(end 74.251083 14.421688)
		(width 0.12065)
		(layer "In3.Cu")
		(net "DDR0_32A_DQ19")
	)
	(segment
		(start 72.416695 13.056083)
		(end 71.906917 13.056083)
		(width 0.12065)
		(layer "In3.Cu")
		(net "DDR0_32A_DQ19")
	)
	(segment
		(start 75.221871 13.855929)
		(end 75.057 14.0208)
		(width 0.12065)
		(layer "In3.Cu")
		(net "DDR0_32A_DQ19")
	)
	(segment
		(start 74.016845 13.056083)
		(end 73.685324 13.056083)
		(width 0.12065)
		(layer "In3.Cu")
		(net "DDR0_32A_DQ19")
	)
	(segment
		(start 72.650934 13.290321)
		(end 72.416695 13.056083)
		(width 0.12065)
		(layer "In3.Cu")
		(net "DDR0_32A_DQ19")
	)
	(segment
		(start 76.2254 13.856081)
		(end 76.225248 13.855929)
		(width 0.12065)
		(layer "In3.Cu")
		(net "DDR0_32A_DQ19")
	)
	(segment
		(start 76.225248 13.855929)
		(end 75.221871 13.855929)
		(width 0.12065)
		(layer "In3.Cu")
		(net "DDR0_32A_DQ19")
	)
	(segment
		(start 76.651079 13.856081)
		(end 76.2254 13.856081)
		(width 0.12065)
		(layer "In3.Cu")
		(net "DDR0_32A_DQ19")
	)
	(segment
		(start 71.42099 13.54201)
		(end 70.736993 13.54201)
		(width 0.12065)
		(layer "In3.Cu")
		(net "DDR0_32A_DQ19")
	)
	(segment
		(start 74.251083 14.421688)
		(end 74.251083 13.290321)
		(width 0.12065)
		(layer "In3.Cu")
		(net "DDR0_32A_DQ19")
	)
	(segment
		(start 77.051002 14.256004)
		(end 76.651079 13.856081)
		(width 0.12065)
		(layer "In3.Cu")
		(net "DDR0_32A_DQ19")
	)
	(segment
		(start 74.251083 13.290321)
		(end 74.016845 13.056083)
		(width 0.12065)
		(layer "In3.Cu")
		(net "DDR0_32A_DQ19")
	)
	(segment
		(start 71.906917 13.056083)
		(end 71.42099 13.54201)
		(width 0.12065)
		(layer "In3.Cu")
		(net "DDR0_32A_DQ19")
	)
	(segment
		(start 73.304273 14.655927)
		(end 72.771584 14.655927)
		(width 0.12065)
		(layer "In3.Cu")
		(net "DDR0_32A_DQ19")
	)
	(segment
		(start 65.737003 13.54201)
		(end 65.237004 14.042009)
		(width 0.13208)
		(layer "F.Cu")
		(net "DDR0_32A_DQ18")
	)
	(via
		(at 65.737003 13.54201)
		(size 0.4826)
		(drill 0.25654)
		(layers "F.Cu" "B.Cu")
		(net "DDR0_32A_DQ18")
	)
	(segment
		(start 75.851004 17.855997)
		(end 75.451005 18.255996)
		(width 0.254)
		(layer "B.Cu")
		(net "DDR0_32A_DQ18")
	)
	(segment
		(start 70.135521 15.79118)
		(end 70.487819 16.143478)
		(width 0.104648)
		(layer "In3.Cu")
		(net "DDR0_32A_DQ18")
	)
	(segment
		(start 66.796844 14.042898)
		(end 67.341775 14.58783)
		(width 0.104648)
		(layer "In3.Cu")
		(net "DDR0_32A_DQ18")
	)
	(segment
		(start 69.691174 14.937232)
		(end 70.132219 15.378278)
		(width 0.104648)
		(layer "In3.Cu")
		(net "DDR0_32A_DQ18")
	)
	(segment
		(start 71.017333 16.18488)
		(end 71.12 16.18488)
		(width 0.104648)
		(layer "In3.Cu")
		(net "DDR0_32A_DQ18")
	)
	(segment
		(start 67.573271 14.937232)
		(end 69.691174 14.937232)
		(width 0.104648)
		(layer "In3.Cu")
		(net "DDR0_32A_DQ18")
	)
	(segment
		(start 70.132219 15.395194)
		(end 70.135521 15.398496)
		(width 0.104648)
		(layer "In3.Cu")
		(net "DDR0_32A_DQ18")
	)
	(segment
		(start 70.132219 15.378278)
		(end 70.132219 15.395194)
		(width 0.104648)
		(layer "In3.Cu")
		(net "DDR0_32A_DQ18")
	)
	(segment
		(start 75.451005 17.640605)
		(end 75.451005 18.255996)
		(width 0.12065)
		(layer "In3.Cu")
		(net "DDR0_32A_DQ18")
	)
	(segment
		(start 70.487819 16.143478)
		(end 70.975931 16.143478)
		(width 0.104648)
		(layer "In3.Cu")
		(net "DDR0_32A_DQ18")
	)
	(segment
		(start 75.1332 17.3228)
		(end 75.451005 17.640605)
		(width 0.12065)
		(layer "In3.Cu")
		(net "DDR0_32A_DQ18")
	)
	(segment
		(start 67.341775 14.58783)
		(end 67.341775 14.705736)
		(width 0.104648)
		(layer "In3.Cu")
		(net "DDR0_32A_DQ18")
	)
	(segment
		(start 71.12 16.18488)
		(end 71.17588 16.18488)
		(width 0.12065)
		(layer "In3.Cu")
		(net "DDR0_32A_DQ18")
	)
	(segment
		(start 71.628 16.637)
		(end 73.9902 16.637)
		(width 0.12065)
		(layer "In3.Cu")
		(net "DDR0_32A_DQ18")
	)
	(segment
		(start 70.975931 16.143478)
		(end 71.017333 16.18488)
		(width 0.104648)
		(layer "In3.Cu")
		(net "DDR0_32A_DQ18")
	)
	(segment
		(start 70.135521 15.398496)
		(end 70.135521 15.79118)
		(width 0.104648)
		(layer "In3.Cu")
		(net "DDR0_32A_DQ18")
	)
	(segment
		(start 65.737003 13.54201)
		(end 66.796844 14.042898)
		(width 0.104648)
		(layer "In3.Cu")
		(net "DDR0_32A_DQ18")
	)
	(segment
		(start 73.9902 16.637)
		(end 74.676 17.3228)
		(width 0.12065)
		(layer "In3.Cu")
		(net "DDR0_32A_DQ18")
	)
	(segment
		(start 74.676 17.3228)
		(end 75.1332 17.3228)
		(width 0.12065)
		(layer "In3.Cu")
		(net "DDR0_32A_DQ18")
	)
	(segment
		(start 71.17588 16.18488)
		(end 71.628 16.637)
		(width 0.12065)
		(layer "In3.Cu")
		(net "DDR0_32A_DQ18")
	)
	(segment
		(start 67.341775 14.705736)
		(end 67.573271 14.937232)
		(width 0.104648)
		(layer "In3.Cu")
		(net "DDR0_32A_DQ18")
	)
	(segment
		(start 70.736993 12.542012)
		(end 70.236994 13.042011)
		(width 0.13208)
		(layer "F.Cu")
		(net "DDR0_32A_DQ17")
	)
	(via
		(at 70.736993 12.542012)
		(size 0.4826)
		(drill 0.20574)
		(layers "F.Cu" "B.Cu")
		(net "DDR0_32A_DQ17")
	)
	(segment
		(start 76.651002 13.856005)
		(end 76.251003 13.456006)
		(width 0.254)
		(layer "B.Cu")
		(net "DDR0_32A_DQ17")
	)
	(segment
		(start 76.251003 13.456006)
		(end 76.485394 13.456006)
		(width 0.12065)
		(layer "In3.Cu")
		(net "DDR0_32A_DQ17")
	)
	(segment
		(start 76.885317 13.056083)
		(end 76.910717 13.056083)
		(width 0.12065)
		(layer "In3.Cu")
		(net "DDR0_32A_DQ17")
	)
	(segment
		(start 76.910717 13.056083)
		(end 76.91087 13.05593)
		(width 0.12065)
		(layer "In3.Cu")
		(net "DDR0_32A_DQ17")
	)
	(segment
		(start 78.1304 12.9032)
		(end 78.1304 11.7094)
		(width 0.12065)
		(layer "In3.Cu")
		(net "DDR0_32A_DQ17")
	)
	(segment
		(start 71.32955 11.52525)
		(end 70.736993 12.117807)
		(width 0.12065)
		(layer "In3.Cu")
		(net "DDR0_32A_DQ17")
	)
	(segment
		(start 77.94625 11.52525)
		(end 71.32955 11.52525)
		(width 0.12065)
		(layer "In3.Cu")
		(net "DDR0_32A_DQ17")
	)
	(segment
		(start 78.1304 11.7094)
		(end 77.94625 11.52525)
		(width 0.12065)
		(layer "In3.Cu")
		(net "DDR0_32A_DQ17")
	)
	(segment
		(start 76.485394 13.456006)
		(end 76.885317 13.056083)
		(width 0.12065)
		(layer "In3.Cu")
		(net "DDR0_32A_DQ17")
	)
	(segment
		(start 70.736993 12.117807)
		(end 70.736993 12.542012)
		(width 0.12065)
		(layer "In3.Cu")
		(net "DDR0_32A_DQ17")
	)
	(segment
		(start 77.97767 13.05593)
		(end 78.1304 12.9032)
		(width 0.12065)
		(layer "In3.Cu")
		(net "DDR0_32A_DQ17")
	)
	(segment
		(start 76.91087 13.05593)
		(end 77.97767 13.05593)
		(width 0.12065)
		(layer "In3.Cu")
		(net "DDR0_32A_DQ17")
	)
	(segment
		(start 68.736997 13.54201)
		(end 68.236998 14.042009)
		(width 0.13208)
		(layer "F.Cu")
		(net "DDR0_32A_DQ16")
	)
	(via
		(at 68.736997 13.54201)
		(size 0.4826)
		(drill 0.20574)
		(layers "F.Cu" "B.Cu")
		(net "DDR0_32A_DQ16")
	)
	(segment
		(start 75.051006 14.656003)
		(end 74.651006 14.256004)
		(width 0.254)
		(layer "B.Cu")
		(net "DDR0_32A_DQ16")
	)
	(segment
		(start 69.178043 13.54201)
		(end 68.736997 13.54201)
		(width 0.104648)
		(layer "In3.Cu")
		(net "DDR0_32A_DQ16")
	)
	(segment
		(start 74.651006 14.045819)
		(end 75.051082 13.645744)
		(width 0.12065)
		(layer "In3.Cu")
		(net "DDR0_32A_DQ16")
	)
	(segment
		(start 75.051082 12.160682)
		(end 74.92365 12.03325)
		(width 0.12065)
		(layer "In3.Cu")
		(net "DDR0_32A_DQ16")
	)
	(segment
		(start 71.4502 12.554814)
		(end 71.4502 13.0048)
		(width 0.12065)
		(layer "In3.Cu")
		(net "DDR0_32A_DQ16")
	)
	(segment
		(start 71.971764 12.03325)
		(end 71.4502 12.554814)
		(width 0.12065)
		(layer "In3.Cu")
		(net "DDR0_32A_DQ16")
	)
	(segment
		(start 74.92365 12.03325)
		(end 74.549 12.03325)
		(width 0.12065)
		(layer "In3.Cu")
		(net "DDR0_32A_DQ16")
	)
	(segment
		(start 74.39025 12.192)
		(end 74.041 12.192)
		(width 0.12065)
		(layer "In3.Cu")
		(net "DDR0_32A_DQ16")
	)
	(segment
		(start 74.549 12.03325)
		(end 74.39025 12.192)
		(width 0.12065)
		(layer "In3.Cu")
		(net "DDR0_32A_DQ16")
	)
	(segment
		(start 73.88225 12.03325)
		(end 73.571608 12.03325)
		(width 0.12065)
		(layer "In3.Cu")
		(net "DDR0_32A_DQ16")
	)
	(segment
		(start 73.330283 13.05593)
		(end 72.82213 13.05593)
		(width 0.12065)
		(layer "In3.Cu")
		(net "DDR0_32A_DQ16")
	)
	(segment
		(start 74.651006 14.256004)
		(end 74.651006 14.045819)
		(width 0.12065)
		(layer "In3.Cu")
		(net "DDR0_32A_DQ16")
	)
	(segment
		(start 72.651087 12.153925)
		(end 72.530411 12.03325)
		(width 0.12065)
		(layer "In3.Cu")
		(net "DDR0_32A_DQ16")
	)
	(segment
		(start 75.051082 13.645744)
		(end 75.051082 12.160682)
		(width 0.12065)
		(layer "In3.Cu")
		(net "DDR0_32A_DQ16")
	)
	(segment
		(start 74.041 12.192)
		(end 73.88225 12.03325)
		(width 0.12065)
		(layer "In3.Cu")
		(net "DDR0_32A_DQ16")
	)
	(segment
		(start 72.82213 13.05593)
		(end 72.651087 12.884887)
		(width 0.12065)
		(layer "In3.Cu")
		(net "DDR0_32A_DQ16")
	)
	(segment
		(start 73.450933 12.153925)
		(end 73.450933 12.93528)
		(width 0.12065)
		(layer "In3.Cu")
		(net "DDR0_32A_DQ16")
	)
	(segment
		(start 72.651087 12.884887)
		(end 72.651087 12.153925)
		(width 0.12065)
		(layer "In3.Cu")
		(net "DDR0_32A_DQ16")
	)
	(segment
		(start 73.450933 12.93528)
		(end 73.330283 13.05593)
		(width 0.12065)
		(layer "In3.Cu")
		(net "DDR0_32A_DQ16")
	)
	(segment
		(start 72.530411 12.03325)
		(end 71.971764 12.03325)
		(width 0.12065)
		(layer "In3.Cu")
		(net "DDR0_32A_DQ16")
	)
	(segment
		(start 71.4502 13.0048)
		(end 71.308214 13.146786)
		(width 0.12065)
		(layer "In3.Cu")
		(net "DDR0_32A_DQ16")
	)
	(segment
		(start 71.12 13.146786)
		(end 69.573267 13.146786)
		(width 0.104648)
		(layer "In3.Cu")
		(net "DDR0_32A_DQ16")
	)
	(segment
		(start 71.308214 13.146786)
		(end 71.12 13.146786)
		(width 0.12065)
		(layer "In3.Cu")
		(net "DDR0_32A_DQ16")
	)
	(segment
		(start 69.573267 13.146786)
		(end 69.178043 13.54201)
		(width 0.104648)
		(layer "In3.Cu")
		(net "DDR0_32A_DQ16")
	)
	(segment
		(start 73.571608 12.03325)
		(end 73.450933 12.153925)
		(width 0.12065)
		(layer "In3.Cu")
		(net "DDR0_32A_DQ16")
	)
	(segment
		(start 66.737001 10.541991)
		(end 66.237002 11.04199)
		(width 0.13208)
		(layer "F.Cu")
		(net "DDR0_32A_DQ15")
	)
	(via
		(at 66.737001 10.541991)
		(size 0.4826)
		(drill 0.25654)
		(layers "F.Cu" "B.Cu")
		(net "DDR0_32A_DQ15")
	)
	(segment
		(start 73.451009 2.299005)
		(end 73.05101 1.899006)
		(width 0.14732)
		(layer "B.Cu")
		(net "DDR0_32A_DQ15")
	)
	(segment
		(start 72.416695 2.298929)
		(end 73.030994 1.899006)
		(width 0.12065)
		(layer "In2.Cu")
		(net "DDR0_32A_DQ15")
	)
	(segment
		(start 66.737001 10.541991)
		(end 67.333774 9.221826)
		(width 0.12065)
		(layer "In2.Cu")
		(net "DDR0_32A_DQ15")
	)
	(segment
		(start 68.140224 3.741776)
		(end 68.140224 3.568497)
		(width 0.12065)
		(layer "In2.Cu")
		(net "DDR0_32A_DQ15")
	)
	(segment
		(start 67.333774 9.221826)
		(end 67.333774 4.374947)
		(width 0.12065)
		(layer "In2.Cu")
		(net "DDR0_32A_DQ15")
	)
	(segment
		(start 68.660721 3.048)
		(end 69.7992 3.048)
		(width 0.12065)
		(layer "In2.Cu")
		(net "DDR0_32A_DQ15")
	)
	(segment
		(start 73.030994 1.899006)
		(end 73.05101 1.899006)
		(width 0.12065)
		(layer "In2.Cu")
		(net "DDR0_32A_DQ15")
	)
	(segment
		(start 69.7992 3.048)
		(end 69.901968 2.945232)
		(width 0.12065)
		(layer "In2.Cu")
		(net "DDR0_32A_DQ15")
	)
	(segment
		(start 67.569944 4.138778)
		(end 67.743222 4.138778)
		(width 0.12065)
		(layer "In2.Cu")
		(net "DDR0_32A_DQ15")
	)
	(segment
		(start 70.14022 2.709062)
		(end 70.14022 2.70698)
		(width 0.12065)
		(layer "In2.Cu")
		(net "DDR0_32A_DQ15")
	)
	(segment
		(start 69.904051 2.945232)
		(end 70.14022 2.709062)
		(width 0.12065)
		(layer "In2.Cu")
		(net "DDR0_32A_DQ15")
	)
	(segment
		(start 67.333774 4.374947)
		(end 67.569944 4.138778)
		(width 0.12065)
		(layer "In2.Cu")
		(net "DDR0_32A_DQ15")
	)
	(segment
		(start 68.140224 3.568497)
		(end 68.660721 3.048)
		(width 0.12065)
		(layer "In2.Cu")
		(net "DDR0_32A_DQ15")
	)
	(segment
		(start 69.901968 2.945232)
		(end 69.904051 2.945232)
		(width 0.12065)
		(layer "In2.Cu")
		(net "DDR0_32A_DQ15")
	)
	(segment
		(start 70.548271 2.298929)
		(end 72.416695 2.298929)
		(width 0.12065)
		(layer "In2.Cu")
		(net "DDR0_32A_DQ15")
	)
	(segment
		(start 70.14022 2.70698)
		(end 70.548271 2.298929)
		(width 0.12065)
		(layer "In2.Cu")
		(net "DDR0_32A_DQ15")
	)
	(segment
		(start 67.743222 4.138778)
		(end 68.140224 3.741776)
		(width 0.12065)
		(layer "In2.Cu")
		(net "DDR0_32A_DQ15")
	)
	(segment
		(start 67.736999 10.541991)
		(end 67.237 11.04199)
		(width 0.13208)
		(layer "F.Cu")
		(net "DDR0_32A_DQ14")
	)
	(via
		(at 67.736999 10.541991)
		(size 0.4826)
		(drill 0.25654)
		(layers "F.Cu" "B.Cu")
		(net "DDR0_32A_DQ14")
	)
	(segment
		(start 71.851012 3.099003)
		(end 72.251011 3.499002)
		(width 0.14732)
		(layer "B.Cu")
		(net "DDR0_32A_DQ14")
	)
	(segment
		(start 71.270266 2.9972)
		(end 71.9836 2.9972)
		(width 0.12065)
		(layer "In2.Cu")
		(net "DDR0_32A_DQ14")
	)
	(segment
		(start 68.341773 10.437343)
		(end 68.341773 4.429227)
		(width 0.104648)
		(layer "In2.Cu")
		(net "DDR0_32A_DQ14")
	)
	(segment
		(start 71.9836 2.9972)
		(end 72.251011 3.264611)
		(width 0.12065)
		(layer "In2.Cu")
		(net "DDR0_32A_DQ14")
	)
	(segment
		(start 68.111116 10.668)
		(end 68.341773 10.437343)
		(width 0.104648)
		(layer "In2.Cu")
		(net "DDR0_32A_DQ14")
	)
	(segment
		(start 70.569938 4.138778)
		(end 70.994448 4.138778)
		(width 0.12065)
		(layer "In2.Cu")
		(net "DDR0_32A_DQ14")
	)
	(segment
		(start 68.602352 4.168648)
		(end 68.995646 4.168648)
		(width 0.104648)
		(layer "In2.Cu")
		(net "DDR0_32A_DQ14")
	)
	(segment
		(start 72.251011 3.264611)
		(end 72.251011 3.499002)
		(width 0.12065)
		(layer "In2.Cu")
		(net "DDR0_32A_DQ14")
	)
	(segment
		(start 70.994448 4.138778)
		(end 71.149616 3.983609)
		(width 0.12065)
		(layer "In2.Cu")
		(net "DDR0_32A_DQ14")
	)
	(segment
		(start 68.995646 4.168648)
		(end 69.656046 3.508248)
		(width 0.104648)
		(layer "In2.Cu")
		(net "DDR0_32A_DQ14")
	)
	(segment
		(start 70.561937 4.146779)
		(end 70.569938 4.138778)
		(width 0.12065)
		(layer "In2.Cu")
		(net "DDR0_32A_DQ14")
	)
	(segment
		(start 69.656046 3.508248)
		(end 69.923406 3.508248)
		(width 0.104648)
		(layer "In2.Cu")
		(net "DDR0_32A_DQ14")
	)
	(segment
		(start 71.149616 3.983609)
		(end 71.149616 3.11785)
		(width 0.12065)
		(layer "In2.Cu")
		(net "DDR0_32A_DQ14")
	)
	(segment
		(start 67.863009 10.668)
		(end 68.111116 10.668)
		(width 0.104648)
		(layer "In2.Cu")
		(net "DDR0_32A_DQ14")
	)
	(segment
		(start 69.923406 3.508248)
		(end 70.561937 4.146779)
		(width 0.104648)
		(layer "In2.Cu")
		(net "DDR0_32A_DQ14")
	)
	(segment
		(start 71.149616 3.11785)
		(end 71.270266 2.9972)
		(width 0.12065)
		(layer "In2.Cu")
		(net "DDR0_32A_DQ14")
	)
	(segment
		(start 68.341773 4.429227)
		(end 68.602352 4.168648)
		(width 0.104648)
		(layer "In2.Cu")
		(net "DDR0_32A_DQ14")
	)
	(segment
		(start 67.736999 10.541991)
		(end 67.863009 10.668)
		(width 0.104648)
		(layer "In2.Cu")
		(net "DDR0_32A_DQ14")
	)
	(segment
		(start 69.736995 11.541989)
		(end 69.236996 12.041988)
		(width 0.13208)
		(layer "F.Cu")
		(net "DDR0_32A_DQ13")
	)
	(via
		(at 69.736995 11.541989)
		(size 0.4826)
		(drill 0.25654)
		(layers "F.Cu" "B.Cu")
		(net "DDR0_32A_DQ13")
	)
	(segment
		(start 71.851012 6.298997)
		(end 72.251011 5.898998)
		(width 0.14732)
		(layer "B.Cu")
		(net "DDR0_32A_DQ13")
	)
	(segment
		(start 73.152 9.271)
		(end 73.152 8.8392)
		(width 0.12065)
		(layer "In2.Cu")
		(net "DDR0_32A_DQ13")
	)
	(segment
		(start 70.48754 11.94054)
		(end 71.041971 11.94054)
		(width 0.104648)
		(layer "In2.Cu")
		(net "DDR0_32A_DQ13")
	)
	(segment
		(start 73.1774 6.8326)
		(end 73.1774 6.477)
		(width 0.12065)
		(layer "In2.Cu")
		(net "DDR0_32A_DQ13")
	)
	(segment
		(start 72.650934 8.642934)
		(end 72.650934 7.112)
		(width 0.12065)
		(layer "In2.Cu")
		(net "DDR0_32A_DQ13")
	)
	(segment
		(start 74.3966 9.4742)
		(end 74.295 9.3726)
		(width 0.12065)
		(layer "In2.Cu")
		(net "DDR0_32A_DQ13")
	)
	(segment
		(start 73.2536 9.3726)
		(end 73.152 9.271)
		(width 0.12065)
		(layer "In2.Cu")
		(net "DDR0_32A_DQ13")
	)
	(segment
		(start 71.857413 11.6586)
		(end 74.2188 11.6586)
		(width 0.12065)
		(layer "In2.Cu")
		(net "DDR0_32A_DQ13")
	)
	(segment
		(start 71.041971 11.94054)
		(end 71.061377 11.959946)
		(width 0.104648)
		(layer "In2.Cu")
		(net "DDR0_32A_DQ13")
	)
	(segment
		(start 72.777934 6.985)
		(end 73.025 6.985)
		(width 0.12065)
		(layer "In2.Cu")
		(net "DDR0_32A_DQ13")
	)
	(segment
		(start 71.061377 11.959946)
		(end 71.12 11.959946)
		(width 0.104648)
		(layer "In2.Cu")
		(net "DDR0_32A_DQ13")
	)
	(segment
		(start 71.12 11.959946)
		(end 71.556067 11.959946)
		(width 0.12065)
		(layer "In2.Cu")
		(net "DDR0_32A_DQ13")
	)
	(segment
		(start 74.3966 11.4808)
		(end 74.3966 9.4742)
		(width 0.12065)
		(layer "In2.Cu")
		(net "DDR0_32A_DQ13")
	)
	(segment
		(start 71.556067 11.959946)
		(end 71.857413 11.6586)
		(width 0.12065)
		(layer "In2.Cu")
		(net "DDR0_32A_DQ13")
	)
	(segment
		(start 73.1774 6.477)
		(end 73.036913 6.336513)
		(width 0.12065)
		(layer "In2.Cu")
		(net "DDR0_32A_DQ13")
	)
	(segment
		(start 70.088989 11.541989)
		(end 70.48754 11.94054)
		(width 0.104648)
		(layer "In2.Cu")
		(net "DDR0_32A_DQ13")
	)
	(segment
		(start 72.650934 7.112)
		(end 72.777934 6.985)
		(width 0.12065)
		(layer "In2.Cu")
		(net "DDR0_32A_DQ13")
	)
	(segment
		(start 73.0504 8.7376)
		(end 72.7456 8.7376)
		(width 0.12065)
		(layer "In2.Cu")
		(net "DDR0_32A_DQ13")
	)
	(segment
		(start 73.025 6.985)
		(end 73.1774 6.8326)
		(width 0.12065)
		(layer "In2.Cu")
		(net "DDR0_32A_DQ13")
	)
	(segment
		(start 74.2188 11.6586)
		(end 74.3966 11.4808)
		(width 0.12065)
		(layer "In2.Cu")
		(net "DDR0_32A_DQ13")
	)
	(segment
		(start 73.036913 6.336513)
		(end 72.688679 6.336513)
		(width 0.12065)
		(layer "In2.Cu")
		(net "DDR0_32A_DQ13")
	)
	(segment
		(start 72.251011 5.898845)
		(end 72.251011 5.898998)
		(width 0.12065)
		(layer "In2.Cu")
		(net "DDR0_32A_DQ13")
	)
	(segment
		(start 74.295 9.3726)
		(end 73.2536 9.3726)
		(width 0.12065)
		(layer "In2.Cu")
		(net "DDR0_32A_DQ13")
	)
	(segment
		(start 73.152 8.8392)
		(end 73.0504 8.7376)
		(width 0.12065)
		(layer "In2.Cu")
		(net "DDR0_32A_DQ13")
	)
	(segment
		(start 72.688679 6.336513)
		(end 72.251011 5.898845)
		(width 0.12065)
		(layer "In2.Cu")
		(net "DDR0_32A_DQ13")
	)
	(segment
		(start 72.7456 8.7376)
		(end 72.650934 8.642934)
		(width 0.12065)
		(layer "In2.Cu")
		(net "DDR0_32A_DQ13")
	)
	(segment
		(start 69.736995 11.541989)
		(end 70.088989 11.541989)
		(width 0.104648)
		(layer "In2.Cu")
		(net "DDR0_32A_DQ13")
	)
	(segment
		(start 66.737001 11.541989)
		(end 66.237002 12.041988)
		(width 0.13208)
		(layer "F.Cu")
		(net "DDR0_32A_DQ12")
	)
	(via
		(at 66.737001 11.541989)
		(size 0.4826)
		(drill 0.20574)
		(layers "F.Cu" "B.Cu")
		(net "DDR0_32A_DQ12")
	)
	(segment
		(start 71.851012 2.299005)
		(end 72.251011 2.699004)
		(width 0.14732)
		(layer "B.Cu")
		(net "DDR0_32A_DQ12")
	)
	(segment
		(start 72.244407 2.6924)
		(end 72.251011 2.699004)
		(width 0.12065)
		(layer "In2.Cu")
		(net "DDR0_32A_DQ12")
	)
	(segment
		(start 67.900728 9.937217)
		(end 68.135525 9.702419)
		(width 0.104648)
		(layer "In2.Cu")
		(net "DDR0_32A_DQ12")
	)
	(segment
		(start 68.9102 3.9624)
		(end 69.5706 3.302)
		(width 0.104648)
		(layer "In2.Cu")
		(net "DDR0_32A_DQ12")
	)
	(segment
		(start 68.5038 3.9624)
		(end 68.9102 3.9624)
		(width 0.104648)
		(layer "In2.Cu")
		(net "DDR0_32A_DQ12")
	)
	(segment
		(start 66.737001 11.541989)
		(end 66.737001 11.100943)
		(width 0.104648)
		(layer "In2.Cu")
		(net "DDR0_32A_DQ12")
	)
	(segment
		(start 70.6374 2.6924)
		(end 71.12 2.6924)
		(width 0.104648)
		(layer "In2.Cu")
		(net "DDR0_32A_DQ12")
	)
	(segment
		(start 68.135525 4.330675)
		(end 68.5038 3.9624)
		(width 0.104648)
		(layer "In2.Cu")
		(net "DDR0_32A_DQ12")
	)
	(segment
		(start 67.782821 9.937217)
		(end 67.900728 9.937217)
		(width 0.104648)
		(layer "In2.Cu")
		(net "DDR0_32A_DQ12")
	)
	(segment
		(start 67.341775 10.496169)
		(end 67.341775 10.378262)
		(width 0.104648)
		(layer "In2.Cu")
		(net "DDR0_32A_DQ12")
	)
	(segment
		(start 68.135525 9.702419)
		(end 68.135525 4.330675)
		(width 0.104648)
		(layer "In2.Cu")
		(net "DDR0_32A_DQ12")
	)
	(segment
		(start 66.737001 11.100943)
		(end 67.341775 10.496169)
		(width 0.104648)
		(layer "In2.Cu")
		(net "DDR0_32A_DQ12")
	)
	(segment
		(start 71.12 2.6924)
		(end 72.244407 2.6924)
		(width 0.12065)
		(layer "In2.Cu")
		(net "DDR0_32A_DQ12")
	)
	(segment
		(start 69.5706 3.302)
		(end 70.0278 3.302)
		(width 0.104648)
		(layer "In2.Cu")
		(net "DDR0_32A_DQ12")
	)
	(segment
		(start 67.341775 10.378262)
		(end 67.782821 9.937217)
		(width 0.104648)
		(layer "In2.Cu")
		(net "DDR0_32A_DQ12")
	)
	(segment
		(start 70.0278 3.302)
		(end 70.6374 2.6924)
		(width 0.104648)
		(layer "In2.Cu")
		(net "DDR0_32A_DQ12")
	)
	(segment
		(start 70.736993 11.541989)
		(end 70.236994 12.041988)
		(width 0.13208)
		(layer "F.Cu")
		(net "DDR0_32A_DQ11")
	)
	(via
		(at 70.736993 11.541989)
		(size 0.4826)
		(drill 0.20574)
		(layers "F.Cu" "B.Cu")
		(net "DDR0_32A_DQ11")
	)
	(segment
		(start 72.65101 7.098995)
		(end 72.251011 6.698996)
		(width 0.14732)
		(layer "B.Cu")
		(net "DDR0_32A_DQ11")
	)
	(segment
		(start 74.07275 10.1727)
		(end 74.07275 9.7917)
		(width 0.12065)
		(layer "In2.Cu")
		(net "DDR0_32A_DQ11")
	)
	(segment
		(start 71.971738 6.698996)
		(end 72.251011 6.698996)
		(width 0.12065)
		(layer "In2.Cu")
		(net "DDR0_32A_DQ11")
	)
	(segment
		(start 73.137395 10.438206)
		(end 73.137395 10.3886)
		(width 0.12065)
		(layer "In2.Cu")
		(net "DDR0_32A_DQ11")
	)
	(segment
		(start 71.021397 11.684)
		(end 71.374 11.684)
		(width 0.12065)
		(layer "In2.Cu")
		(net "DDR0_32A_DQ11")
	)
	(segment
		(start 74.07275 9.7917)
		(end 73.98385 9.7028)
		(width 0.12065)
		(layer "In2.Cu")
		(net "DDR0_32A_DQ11")
	)
	(segment
		(start 72.4662 9.017)
		(end 72.2122 9.271)
		(width 0.12065)
		(layer "In2.Cu")
		(net "DDR0_32A_DQ11")
	)
	(segment
		(start 74.07275 10.87755)
		(end 73.9648 10.7696)
		(width 0.12065)
		(layer "In2.Cu")
		(net "DDR0_32A_DQ11")
	)
	(segment
		(start 73.98385 11.33475)
		(end 74.07275 11.24585)
		(width 0.12065)
		(layer "In2.Cu")
		(net "DDR0_32A_DQ11")
	)
	(segment
		(start 72.82815 9.58215)
		(end 72.82815 9.15035)
		(width 0.12065)
		(layer "In2.Cu")
		(net "DDR0_32A_DQ11")
	)
	(segment
		(start 73.98385 9.7028)
		(end 72.9488 9.7028)
		(width 0.12065)
		(layer "In2.Cu")
		(net "DDR0_32A_DQ11")
	)
	(segment
		(start 71.723174 11.33475)
		(end 72.649639 11.33475)
		(width 0.12065)
		(layer "In2.Cu")
		(net "DDR0_32A_DQ11")
	)
	(segment
		(start 73.9648 10.7696)
		(end 73.2536 10.7696)
		(width 0.12065)
		(layer "In2.Cu")
		(net "DDR0_32A_DQ11")
	)
	(segment
		(start 72.649639 11.33475)
		(end 72.894876 11.089513)
		(width 0.12065)
		(layer "In2.Cu")
		(net "DDR0_32A_DQ11")
	)
	(segment
		(start 72.6948 9.017)
		(end 72.4662 9.017)
		(width 0.12065)
		(layer "In2.Cu")
		(net "DDR0_32A_DQ11")
	)
	(segment
		(start 73.137497 10.653497)
		(end 73.137497 10.438308)
		(width 0.12065)
		(layer "In2.Cu")
		(net "DDR0_32A_DQ11")
	)
	(segment
		(start 71.851088 9.113063)
		(end 71.851088 6.819646)
		(width 0.12065)
		(layer "In2.Cu")
		(net "DDR0_32A_DQ11")
	)
	(segment
		(start 73.95845 10.287)
		(end 74.07275 10.1727)
		(width 0.12065)
		(layer "In2.Cu")
		(net "DDR0_32A_DQ11")
	)
	(segment
		(start 72.9488 9.7028)
		(end 72.82815 9.58215)
		(width 0.12065)
		(layer "In2.Cu")
		(net "DDR0_32A_DQ11")
	)
	(segment
		(start 72.894876 11.089513)
		(end 73.065513 11.089513)
		(width 0.12065)
		(layer "In2.Cu")
		(net "DDR0_32A_DQ11")
	)
	(segment
		(start 71.374 11.684)
		(end 71.533563 11.524437)
		(width 0.12065)
		(layer "In2.Cu")
		(net "DDR0_32A_DQ11")
	)
	(segment
		(start 73.065513 11.089513)
		(end 73.31075 11.33475)
		(width 0.12065)
		(layer "In2.Cu")
		(net "DDR0_32A_DQ11")
	)
	(segment
		(start 70.736993 11.541989)
		(end 70.879386 11.541989)
		(width 0.12065)
		(layer "In2.Cu")
		(net "DDR0_32A_DQ11")
	)
	(segment
		(start 72.2122 9.271)
		(end 72.009025 9.271)
		(width 0.12065)
		(layer "In2.Cu")
		(net "DDR0_32A_DQ11")
	)
	(segment
		(start 72.009025 9.271)
		(end 71.851088 9.113063)
		(width 0.12065)
		(layer "In2.Cu")
		(net "DDR0_32A_DQ11")
	)
	(segment
		(start 71.533563 11.524437)
		(end 71.533563 11.524361)
		(width 0.12065)
		(layer "In2.Cu")
		(net "DDR0_32A_DQ11")
	)
	(segment
		(start 72.82815 9.15035)
		(end 72.6948 9.017)
		(width 0.12065)
		(layer "In2.Cu")
		(net "DDR0_32A_DQ11")
	)
	(segment
		(start 73.137395 10.3886)
		(end 73.238995 10.287)
		(width 0.12065)
		(layer "In2.Cu")
		(net "DDR0_32A_DQ11")
	)
	(segment
		(start 70.879386 11.541989)
		(end 71.021397 11.684)
		(width 0.12065)
		(layer "In2.Cu")
		(net "DDR0_32A_DQ11")
	)
	(segment
		(start 73.31075 11.33475)
		(end 73.98385 11.33475)
		(width 0.12065)
		(layer "In2.Cu")
		(net "DDR0_32A_DQ11")
	)
	(segment
		(start 74.07275 11.24585)
		(end 74.07275 10.87755)
		(width 0.12065)
		(layer "In2.Cu")
		(net "DDR0_32A_DQ11")
	)
	(segment
		(start 73.238995 10.287)
		(end 73.95845 10.287)
		(width 0.12065)
		(layer "In2.Cu")
		(net "DDR0_32A_DQ11")
	)
	(segment
		(start 71.851088 6.819646)
		(end 71.971738 6.698996)
		(width 0.12065)
		(layer "In2.Cu")
		(net "DDR0_32A_DQ11")
	)
	(segment
		(start 73.137497 10.438308)
		(end 73.137395 10.438206)
		(width 0.12065)
		(layer "In2.Cu")
		(net "DDR0_32A_DQ11")
	)
	(segment
		(start 73.2536 10.7696)
		(end 73.137497 10.653497)
		(width 0.12065)
		(layer "In2.Cu")
		(net "DDR0_32A_DQ11")
	)
	(segment
		(start 71.533563 11.524361)
		(end 71.723174 11.33475)
		(width 0.12065)
		(layer "In2.Cu")
		(net "DDR0_32A_DQ11")
	)
	(segment
		(start 67.736999 12.542012)
		(end 67.237 13.042011)
		(width 0.13208)
		(layer "F.Cu")
		(net "DDR0_32A_DQ10")
	)
	(via
		(at 67.736999 12.542012)
		(size 0.4826)
		(drill 0.20574)
		(layers "F.Cu" "B.Cu")
		(net "DDR0_32A_DQ10")
	)
	(segment
		(start 73.451009 7.098995)
		(end 73.05101 7.498994)
		(width 0.14732)
		(layer "B.Cu")
		(net "DDR0_32A_DQ10")
	)
	(segment
		(start 73.450933 8.884133)
		(end 73.6092 9.0424)
		(width 0.12065)
		(layer "In2.Cu")
		(net "DDR0_32A_DQ10")
	)
	(segment
		(start 71.017333 12.207596)
		(end 70.956526 12.146788)
		(width 0.104648)
		(layer "In2.Cu")
		(net "DDR0_32A_DQ10")
	)
	(segment
		(start 71.453477 12.207596)
		(end 71.12 12.207596)
		(width 0.12065)
		(layer "In2.Cu")
		(net "DDR0_32A_DQ10")
	)
	(segment
		(start 73.05101 7.733386)
		(end 73.450933 8.133309)
		(width 0.12065)
		(layer "In2.Cu")
		(net "DDR0_32A_DQ10")
	)
	(segment
		(start 73.450933 8.133309)
		(end 73.450933 8.884133)
		(width 0.12065)
		(layer "In2.Cu")
		(net "DDR0_32A_DQ10")
	)
	(segment
		(start 73.05101 7.498994)
		(end 73.05101 7.733386)
		(width 0.12065)
		(layer "In2.Cu")
		(net "DDR0_32A_DQ10")
	)
	(segment
		(start 74.7776 11.7094)
		(end 74.549 11.938)
		(width 0.12065)
		(layer "In2.Cu")
		(net "DDR0_32A_DQ10")
	)
	(segment
		(start 71.453527 12.207646)
		(end 71.453477 12.207596)
		(width 0.12065)
		(layer "In2.Cu")
		(net "DDR0_32A_DQ10")
	)
	(segment
		(start 74.7776 9.144)
		(end 74.7776 11.7094)
		(width 0.12065)
		(layer "In2.Cu")
		(net "DDR0_32A_DQ10")
	)
	(segment
		(start 71.12 12.207596)
		(end 71.017333 12.207596)
		(width 0.104648)
		(layer "In2.Cu")
		(net "DDR0_32A_DQ10")
	)
	(segment
		(start 71.928253 11.938)
		(end 71.658607 12.207646)
		(width 0.12065)
		(layer "In2.Cu")
		(net "DDR0_32A_DQ10")
	)
	(segment
		(start 71.658607 12.207646)
		(end 71.453527 12.207646)
		(width 0.12065)
		(layer "In2.Cu")
		(net "DDR0_32A_DQ10")
	)
	(segment
		(start 70.956526 12.146788)
		(end 67.863187 12.146788)
		(width 0.104648)
		(layer "In2.Cu")
		(net "DDR0_32A_DQ10")
	)
	(segment
		(start 74.676 9.0424)
		(end 74.7776 9.144)
		(width 0.12065)
		(layer "In2.Cu")
		(net "DDR0_32A_DQ10")
	)
	(segment
		(start 67.863187 12.146788)
		(end 67.736999 12.272975)
		(width 0.104648)
		(layer "In2.Cu")
		(net "DDR0_32A_DQ10")
	)
	(segment
		(start 67.736999 12.272975)
		(end 67.736999 12.542012)
		(width 0.104648)
		(layer "In2.Cu")
		(net "DDR0_32A_DQ10")
	)
	(segment
		(start 74.549 11.938)
		(end 71.928253 11.938)
		(width 0.12065)
		(layer "In2.Cu")
		(net "DDR0_32A_DQ10")
	)
	(segment
		(start 73.6092 9.0424)
		(end 74.676 9.0424)
		(width 0.12065)
		(layer "In2.Cu")
		(net "DDR0_32A_DQ10")
	)
	(segment
		(start 69.736995 10.541991)
		(end 69.236996 11.04199)
		(width 0.13208)
		(layer "F.Cu")
		(net "DDR0_32A_DQ9")
	)
	(via
		(at 69.736995 10.541991)
		(size 0.4826)
		(drill 0.25654)
		(layers "F.Cu" "B.Cu")
		(net "DDR0_32A_DQ9")
	)
	(segment
		(start 73.451009 3.099003)
		(end 73.851008 3.499002)
		(width 0.14732)
		(layer "B.Cu")
		(net "DDR0_32A_DQ9")
	)
	(segment
		(start 69.736995 10.541991)
		(end 70.052209 10.541991)
		(width 0.12065)
		(layer "In2.Cu")
		(net "DDR0_32A_DQ9")
	)
	(segment
		(start 71.247 5.105425)
		(end 71.399425 4.953)
		(width 0.12065)
		(layer "In2.Cu")
		(net "DDR0_32A_DQ9")
	)
	(segment
		(start 71.8058 4.572)
		(end 71.9328 4.445)
		(width 0.12065)
		(layer "In2.Cu")
		(net "DDR0_32A_DQ9")
	)
	(segment
		(start 70.35165 5.945226)
		(end 70.904049 5.945226)
		(width 0.12065)
		(layer "In2.Cu")
		(net "DDR0_32A_DQ9")
	)
	(segment
		(start 70.231 10.3632)
		(end 70.231 7.366)
		(width 0.12065)
		(layer "In2.Cu")
		(net "DDR0_32A_DQ9")
	)
	(segment
		(start 70.052209 10.541991)
		(end 70.231 10.3632)
		(width 0.12065)
		(layer "In2.Cu")
		(net "DDR0_32A_DQ9")
	)
	(segment
		(start 70.231 7.366)
		(end 69.984137 7.119137)
		(width 0.12065)
		(layer "In2.Cu")
		(net "DDR0_32A_DQ9")
	)
	(segment
		(start 71.9328 4.445)
		(end 72.263 4.445)
		(width 0.12065)
		(layer "In2.Cu")
		(net "DDR0_32A_DQ9")
	)
	(segment
		(start 72.263 4.445)
		(end 72.3646 4.5466)
		(width 0.12065)
		(layer "In2.Cu")
		(net "DDR0_32A_DQ9")
	)
	(segment
		(start 73.850475 3.499536)
		(end 73.851008 3.499002)
		(width 0.12065)
		(layer "In2.Cu")
		(net "DDR0_32A_DQ9")
	)
	(segment
		(start 71.247 5.588)
		(end 71.247 5.105425)
		(width 0.12065)
		(layer "In2.Cu")
		(net "DDR0_32A_DQ9")
	)
	(segment
		(start 70.231 6.065876)
		(end 70.35165 5.945226)
		(width 0.12065)
		(layer "In2.Cu")
		(net "DDR0_32A_DQ9")
	)
	(segment
		(start 73.850475 4.832325)
		(end 73.850475 3.499536)
		(width 0.12065)
		(layer "In2.Cu")
		(net "DDR0_32A_DQ9")
	)
	(segment
		(start 69.984137 7.119137)
		(end 69.984137 6.865137)
		(width 0.12065)
		(layer "In2.Cu")
		(net "DDR0_32A_DQ9")
	)
	(segment
		(start 70.904049 5.945226)
		(end 71.140218 5.709056)
		(width 0.12065)
		(layer "In2.Cu")
		(net "DDR0_32A_DQ9")
	)
	(segment
		(start 72.3646 4.826)
		(end 72.4916 4.953)
		(width 0.12065)
		(layer "In2.Cu")
		(net "DDR0_32A_DQ9")
	)
	(segment
		(start 72.8726 4.4196)
		(end 72.9742 4.318)
		(width 0.12065)
		(layer "In2.Cu")
		(net "DDR0_32A_DQ9")
	)
	(segment
		(start 72.7456 4.953)
		(end 72.8726 4.826)
		(width 0.12065)
		(layer "In2.Cu")
		(net "DDR0_32A_DQ9")
	)
	(segment
		(start 72.9742 4.318)
		(end 73.2282 4.318)
		(width 0.12065)
		(layer "In2.Cu")
		(net "DDR0_32A_DQ9")
	)
	(segment
		(start 72.8726 4.826)
		(end 72.8726 4.4196)
		(width 0.12065)
		(layer "In2.Cu")
		(net "DDR0_32A_DQ9")
	)
	(segment
		(start 72.3646 4.5466)
		(end 72.3646 4.826)
		(width 0.12065)
		(layer "In2.Cu")
		(net "DDR0_32A_DQ9")
	)
	(segment
		(start 73.4568 4.953)
		(end 73.729799 4.953)
		(width 0.12065)
		(layer "In2.Cu")
		(net "DDR0_32A_DQ9")
	)
	(segment
		(start 71.399425 4.953)
		(end 71.7042 4.953)
		(width 0.12065)
		(layer "In2.Cu")
		(net "DDR0_32A_DQ9")
	)
	(segment
		(start 72.4916 4.953)
		(end 72.7456 4.953)
		(width 0.12065)
		(layer "In2.Cu")
		(net "DDR0_32A_DQ9")
	)
	(segment
		(start 71.8058 4.8514)
		(end 71.8058 4.572)
		(width 0.12065)
		(layer "In2.Cu")
		(net "DDR0_32A_DQ9")
	)
	(segment
		(start 71.7042 4.953)
		(end 71.8058 4.8514)
		(width 0.12065)
		(layer "In2.Cu")
		(net "DDR0_32A_DQ9")
	)
	(segment
		(start 73.3298 4.4196)
		(end 73.3298 4.826)
		(width 0.12065)
		(layer "In2.Cu")
		(net "DDR0_32A_DQ9")
	)
	(segment
		(start 70.231 6.618275)
		(end 70.231 6.065876)
		(width 0.12065)
		(layer "In2.Cu")
		(net "DDR0_32A_DQ9")
	)
	(segment
		(start 71.140218 5.709056)
		(end 71.140218 5.694782)
		(width 0.12065)
		(layer "In2.Cu")
		(net "DDR0_32A_DQ9")
	)
	(segment
		(start 73.729799 4.953)
		(end 73.850475 4.832325)
		(width 0.12065)
		(layer "In2.Cu")
		(net "DDR0_32A_DQ9")
	)
	(segment
		(start 69.984137 6.865137)
		(end 70.231 6.618275)
		(width 0.12065)
		(layer "In2.Cu")
		(net "DDR0_32A_DQ9")
	)
	(segment
		(start 73.2282 4.318)
		(end 73.3298 4.4196)
		(width 0.12065)
		(layer "In2.Cu")
		(net "DDR0_32A_DQ9")
	)
	(segment
		(start 73.3298 4.826)
		(end 73.4568 4.953)
		(width 0.12065)
		(layer "In2.Cu")
		(net "DDR0_32A_DQ9")
	)
	(segment
		(start 71.140218 5.694782)
		(end 71.247 5.588)
		(width 0.12065)
		(layer "In2.Cu")
		(net "DDR0_32A_DQ9")
	)
	(segment
		(start 68.736997 12.542012)
		(end 68.236998 13.042011)
		(width 0.13208)
		(layer "F.Cu")
		(net "DDR0_32A_DQ8")
	)
	(via
		(at 68.736997 12.542012)
		(size 0.4826)
		(drill 0.20574)
		(layers "F.Cu" "B.Cu")
		(net "DDR0_32A_DQ8")
	)
	(segment
		(start 74.251007 6.298997)
		(end 73.851008 6.698996)
		(width 0.14732)
		(layer "B.Cu")
		(net "DDR0_32A_DQ8")
	)
	(segment
		(start 71.838388 12.489612)
		(end 71.348346 12.489612)
		(width 0.12065)
		(layer "In2.Cu")
		(net "DDR0_32A_DQ8")
	)
	(segment
		(start 68.803037 12.542012)
		(end 68.736997 12.542012)
		(width 0.104648)
		(layer "In2.Cu")
		(net "DDR0_32A_DQ8")
	)
	(segment
		(start 75.1078 11.9888)
		(end 74.9046 12.192)
		(width 0.12065)
		(layer "In2.Cu")
		(net "DDR0_32A_DQ8")
	)
	(segment
		(start 74.9046 8.7376)
		(end 75.1078 8.9408)
		(width 0.12065)
		(layer "In2.Cu")
		(net "DDR0_32A_DQ8")
	)
	(segment
		(start 74.9046 12.192)
		(end 72.136 12.192)
		(width 0.12065)
		(layer "In2.Cu")
		(net "DDR0_32A_DQ8")
	)
	(segment
		(start 75.1078 8.9408)
		(end 75.1078 11.9888)
		(width 0.12065)
		(layer "In2.Cu")
		(net "DDR0_32A_DQ8")
	)
	(segment
		(start 73.881996 6.698996)
		(end 74.250931 7.067931)
		(width 0.12065)
		(layer "In2.Cu")
		(net "DDR0_32A_DQ8")
	)
	(segment
		(start 70.838263 12.937236)
		(end 69.198261 12.937236)
		(width 0.104648)
		(layer "In2.Cu")
		(net "DDR0_32A_DQ8")
	)
	(segment
		(start 70.842962 12.932537)
		(end 70.838263 12.937236)
		(width 0.104648)
		(layer "In2.Cu")
		(net "DDR0_32A_DQ8")
	)
	(segment
		(start 72.136 12.192)
		(end 71.838388 12.489612)
		(width 0.12065)
		(layer "In2.Cu")
		(net "DDR0_32A_DQ8")
	)
	(segment
		(start 69.198261 12.937236)
		(end 68.803037 12.542012)
		(width 0.104648)
		(layer "In2.Cu")
		(net "DDR0_32A_DQ8")
	)
	(segment
		(start 74.250931 8.630082)
		(end 74.358449 8.7376)
		(width 0.12065)
		(layer "In2.Cu")
		(net "DDR0_32A_DQ8")
	)
	(segment
		(start 71.12 12.717958)
		(end 70.905421 12.932537)
		(width 0.104648)
		(layer "In2.Cu")
		(net "DDR0_32A_DQ8")
	)
	(segment
		(start 73.851008 6.698996)
		(end 73.881996 6.698996)
		(width 0.12065)
		(layer "In2.Cu")
		(net "DDR0_32A_DQ8")
	)
	(segment
		(start 74.358449 8.7376)
		(end 74.9046 8.7376)
		(width 0.12065)
		(layer "In2.Cu")
		(net "DDR0_32A_DQ8")
	)
	(segment
		(start 70.905421 12.932537)
		(end 70.842962 12.932537)
		(width 0.104648)
		(layer "In2.Cu")
		(net "DDR0_32A_DQ8")
	)
	(segment
		(start 71.348346 12.489612)
		(end 71.12 12.717958)
		(width 0.12065)
		(layer "In2.Cu")
		(net "DDR0_32A_DQ8")
	)
	(segment
		(start 74.250931 7.067931)
		(end 74.250931 8.630082)
		(width 0.12065)
		(layer "In2.Cu")
		(net "DDR0_32A_DQ8")
	)
	(segment
		(start 70.736993 7.541997)
		(end 70.236994 8.041996)
		(width 0.13208)
		(layer "F.Cu")
		(net "DDR0_32A_DQ7")
	)
	(via
		(at 70.736993 7.541997)
		(size 0.4826)
		(drill 0.20574)
		(layers "F.Cu" "B.Cu")
		(net "DDR0_32A_DQ7")
	)
	(segment
		(start 75.851004 7.098995)
		(end 75.451005 7.498994)
		(width 0.14732)
		(layer "B.Cu")
		(net "DDR0_32A_DQ7")
	)
	(segment
		(start 71.6026 10.1092)
		(end 71.2724 9.779)
		(width 0.12065)
		(layer "In3.Cu")
		(net "DDR0_32A_DQ7")
	)
	(segment
		(start 76.294437 10.36955)
		(end 71.71055 10.36955)
		(width 0.12065)
		(layer "In3.Cu")
		(net "DDR0_32A_DQ7")
	)
	(segment
		(start 77.7748 9.7536)
		(end 77.6478 9.8806)
		(width 0.12065)
		(layer "In3.Cu")
		(net "DDR0_32A_DQ7")
	)
	(segment
		(start 71.6026 10.2616)
		(end 71.6026 10.1092)
		(width 0.12065)
		(layer "In3.Cu")
		(net "DDR0_32A_DQ7")
	)
	(segment
		(start 77.6478 9.8806)
		(end 76.783387 9.8806)
		(width 0.12065)
		(layer "In3.Cu")
		(net "DDR0_32A_DQ7")
	)
	(segment
		(start 71.12 7.541997)
		(end 70.736993 7.541997)
		(width 0.12065)
		(layer "In3.Cu")
		(net "DDR0_32A_DQ7")
	)
	(segment
		(start 71.2724 9.779)
		(end 71.2724 7.694397)
		(width 0.12065)
		(layer "In3.Cu")
		(net "DDR0_32A_DQ7")
	)
	(segment
		(start 76.783387 9.8806)
		(end 76.294437 10.36955)
		(width 0.12065)
		(layer "In3.Cu")
		(net "DDR0_32A_DQ7")
	)
	(segment
		(start 75.850928 7.898917)
		(end 77.317117 7.898917)
		(width 0.12065)
		(layer "In3.Cu")
		(net "DDR0_32A_DQ7")
	)
	(segment
		(start 71.2724 7.694397)
		(end 71.12 7.541997)
		(width 0.12065)
		(layer "In3.Cu")
		(net "DDR0_32A_DQ7")
	)
	(segment
		(start 75.451005 7.498994)
		(end 75.850928 7.898917)
		(width 0.12065)
		(layer "In3.Cu")
		(net "DDR0_32A_DQ7")
	)
	(segment
		(start 71.71055 10.36955)
		(end 71.6026 10.2616)
		(width 0.12065)
		(layer "In3.Cu")
		(net "DDR0_32A_DQ7")
	)
	(segment
		(start 77.7748 8.3566)
		(end 77.7748 9.7536)
		(width 0.12065)
		(layer "In3.Cu")
		(net "DDR0_32A_DQ7")
	)
	(segment
		(start 77.317117 7.898917)
		(end 77.7748 8.3566)
		(width 0.12065)
		(layer "In3.Cu")
		(net "DDR0_32A_DQ7")
	)
	(segment
		(start 69.736995 7.541997)
		(end 69.236996 8.041996)
		(width 0.13208)
		(layer "F.Cu")
		(net "DDR0_32A_DQ6")
	)
	(via
		(at 69.736995 7.541997)
		(size 0.4826)
		(drill 0.20574)
		(layers "F.Cu" "B.Cu")
		(net "DDR0_32A_DQ6")
	)
	(segment
		(start 75.851004 6.298997)
		(end 75.451005 6.698996)
		(width 0.14732)
		(layer "B.Cu")
		(net "DDR0_32A_DQ6")
	)
	(segment
		(start 71.7296 9.778187)
		(end 71.7296 7.3152)
		(width 0.12065)
		(layer "In3.Cu")
		(net "DDR0_32A_DQ6")
	)
	(segment
		(start 75.451005 6.698996)
		(end 75.051082 7.098919)
		(width 0.12065)
		(layer "In3.Cu")
		(net "DDR0_32A_DQ6")
	)
	(segment
		(start 75.279682 8.763)
		(end 76.393675 8.763)
		(width 0.12065)
		(layer "In3.Cu")
		(net "DDR0_32A_DQ6")
	)
	(segment
		(start 76.393675 8.763)
		(end 76.5556 8.924925)
		(width 0.12065)
		(layer "In3.Cu")
		(net "DDR0_32A_DQ6")
	)
	(segment
		(start 71.5264 7.112)
		(end 70.104 7.112)
		(width 0.12065)
		(layer "In3.Cu")
		(net "DDR0_32A_DQ6")
	)
	(segment
		(start 71.997113 10.0457)
		(end 71.7296 9.778187)
		(width 0.12065)
		(layer "In3.Cu")
		(net "DDR0_32A_DQ6")
	)
	(segment
		(start 70.104 7.112)
		(end 69.736995 7.479005)
		(width 0.12065)
		(layer "In3.Cu")
		(net "DDR0_32A_DQ6")
	)
	(segment
		(start 76.5556 8.924925)
		(end 76.5556 9.413875)
		(width 0.12065)
		(layer "In3.Cu")
		(net "DDR0_32A_DQ6")
	)
	(segment
		(start 71.7296 7.3152)
		(end 71.5264 7.112)
		(width 0.12065)
		(layer "In3.Cu")
		(net "DDR0_32A_DQ6")
	)
	(segment
		(start 75.051082 8.5344)
		(end 75.279682 8.763)
		(width 0.12065)
		(layer "In3.Cu")
		(net "DDR0_32A_DQ6")
	)
	(segment
		(start 69.736995 7.479005)
		(end 69.736995 7.541997)
		(width 0.12065)
		(layer "In3.Cu")
		(net "DDR0_32A_DQ6")
	)
	(segment
		(start 75.051082 7.098919)
		(end 75.051082 8.5344)
		(width 0.12065)
		(layer "In3.Cu")
		(net "DDR0_32A_DQ6")
	)
	(segment
		(start 75.923775 10.0457)
		(end 71.997113 10.0457)
		(width 0.12065)
		(layer "In3.Cu")
		(net "DDR0_32A_DQ6")
	)
	(segment
		(start 76.5556 9.413875)
		(end 75.923775 10.0457)
		(width 0.12065)
		(layer "In3.Cu")
		(net "DDR0_32A_DQ6")
	)
	(segment
		(start 67.736999 9.541993)
		(end 67.237 10.041992)
		(width 0.13208)
		(layer "F.Cu")
		(net "DDR0_32A_DQ5")
	)
	(via
		(at 67.736999 9.541993)
		(size 0.4826)
		(drill 0.25654)
		(layers "F.Cu" "B.Cu")
		(net "DDR0_32A_DQ5")
	)
	(segment
		(start 75.051006 3.099003)
		(end 74.651006 2.699004)
		(width 0.14732)
		(layer "B.Cu")
		(net "DDR0_32A_DQ5")
	)
	(segment
		(start 67.989882 5.146777)
		(end 69.402376 3.734283)
		(width 0.104648)
		(layer "In3.Cu")
		(net "DDR0_32A_DQ5")
	)
	(segment
		(start 74.651006 2.419756)
		(end 74.651006 2.699004)
		(width 0.12065)
		(layer "In3.Cu")
		(net "DDR0_32A_DQ5")
	)
	(segment
		(start 71.2724 2.946679)
		(end 71.2724 2.3876)
		(width 0.12065)
		(layer "In3.Cu")
		(net "DDR0_32A_DQ5")
	)
	(segment
		(start 67.736999 9.541993)
		(end 67.446423 9.541993)
		(width 0.104648)
		(layer "In3.Cu")
		(net "DDR0_32A_DQ5")
	)
	(segment
		(start 67.573271 5.146777)
		(end 67.989882 5.146777)
		(width 0.104648)
		(layer "In3.Cu")
		(net "DDR0_32A_DQ5")
	)
	(segment
		(start 67.341775 7.747)
		(end 67.564 7.524775)
		(width 0.104648)
		(layer "In3.Cu")
		(net "DDR0_32A_DQ5")
	)
	(segment
		(start 71.360919 2.299081)
		(end 74.530331 2.299081)
		(width 0.12065)
		(layer "In3.Cu")
		(net "DDR0_32A_DQ5")
	)
	(segment
		(start 67.446423 9.541993)
		(end 67.341775 9.437345)
		(width 0.104648)
		(layer "In3.Cu")
		(net "DDR0_32A_DQ5")
	)
	(segment
		(start 71.12 3.099079)
		(end 71.2724 2.946679)
		(width 0.12065)
		(layer "In3.Cu")
		(net "DDR0_32A_DQ5")
	)
	(segment
		(start 71.2724 2.3876)
		(end 71.360919 2.299081)
		(width 0.12065)
		(layer "In3.Cu")
		(net "DDR0_32A_DQ5")
	)
	(segment
		(start 70.306921 3.099079)
		(end 71.12 3.099079)
		(width 0.104648)
		(layer "In3.Cu")
		(net "DDR0_32A_DQ5")
	)
	(segment
		(start 67.341775 9.437345)
		(end 67.341775 7.747)
		(width 0.104648)
		(layer "In3.Cu")
		(net "DDR0_32A_DQ5")
	)
	(segment
		(start 67.564 7.524775)
		(end 67.564 6.985)
		(width 0.104648)
		(layer "In3.Cu")
		(net "DDR0_32A_DQ5")
	)
	(segment
		(start 67.341775 5.378272)
		(end 67.573271 5.146777)
		(width 0.104648)
		(layer "In3.Cu")
		(net "DDR0_32A_DQ5")
	)
	(segment
		(start 69.671717 3.734283)
		(end 70.306921 3.099079)
		(width 0.104648)
		(layer "In3.Cu")
		(net "DDR0_32A_DQ5")
	)
	(segment
		(start 67.564 6.985)
		(end 67.341775 6.762775)
		(width 0.104648)
		(layer "In3.Cu")
		(net "DDR0_32A_DQ5")
	)
	(segment
		(start 69.402376 3.734283)
		(end 69.671717 3.734283)
		(width 0.104648)
		(layer "In3.Cu")
		(net "DDR0_32A_DQ5")
	)
	(segment
		(start 67.341775 6.762775)
		(end 67.341775 5.378272)
		(width 0.104648)
		(layer "In3.Cu")
		(net "DDR0_32A_DQ5")
	)
	(segment
		(start 74.530331 2.299081)
		(end 74.651006 2.419756)
		(width 0.12065)
		(layer "In3.Cu")
		(net "DDR0_32A_DQ5")
	)
	(segment
		(start 69.736995 8.541995)
		(end 69.236996 9.041994)
		(width 0.13208)
		(layer "F.Cu")
		(net "DDR0_32A_DQ4")
	)
	(via
		(at 69.736995 8.541995)
		(size 0.4826)
		(drill 0.25654)
		(layers "F.Cu" "B.Cu")
		(net "DDR0_32A_DQ4")
	)
	(segment
		(start 77.451001 3.099003)
		(end 77.051002 2.699004)
		(width 0.14732)
		(layer "B.Cu")
		(net "DDR0_32A_DQ4")
	)
	(segment
		(start 74.250931 3.664687)
		(end 74.250931 3.600094)
		(width 0.12065)
		(layer "In3.Cu")
		(net "DDR0_32A_DQ4")
	)
	(segment
		(start 76.651079 2.299081)
		(end 77.051002 2.699004)
		(width 0.12065)
		(layer "In3.Cu")
		(net "DDR0_32A_DQ4")
	)
	(segment
		(start 74.919281 3.346577)
		(end 75.273459 2.992399)
		(width 0.12065)
		(layer "In3.Cu")
		(net "DDR0_32A_DQ4")
	)
	(segment
		(start 74.016692 3.898925)
		(end 74.250931 3.664687)
		(width 0.12065)
		(layer "In3.Cu")
		(net "DDR0_32A_DQ4")
	)
	(segment
		(start 74.504448 3.346577)
		(end 74.919281 3.346577)
		(width 0.12065)
		(layer "In3.Cu")
		(net "DDR0_32A_DQ4")
	)
	(segment
		(start 71.12 4.146779)
		(end 71.161402 4.188181)
		(width 0.12065)
		(layer "In3.Cu")
		(net "DDR0_32A_DQ4")
	)
	(segment
		(start 71.161402 4.188181)
		(end 73.662845 4.188181)
		(width 0.12065)
		(layer "In3.Cu")
		(net "DDR0_32A_DQ4")
	)
	(segment
		(start 68.573269 7.937221)
		(end 68.341773 7.705725)
		(width 0.104648)
		(layer "In3.Cu")
		(net "DDR0_32A_DQ4")
	)
	(segment
		(start 75.698452 2.546629)
		(end 75.800737 2.546629)
		(width 0.12065)
		(layer "In3.Cu")
		(net "DDR0_32A_DQ4")
	)
	(segment
		(start 68.744821 7.937221)
		(end 68.573269 7.937221)
		(width 0.104648)
		(layer "In3.Cu")
		(net "DDR0_32A_DQ4")
	)
	(segment
		(start 73.9521 3.898925)
		(end 74.016692 3.898925)
		(width 0.12065)
		(layer "In3.Cu")
		(net "DDR0_32A_DQ4")
	)
	(segment
		(start 68.341773 7.705725)
		(end 68.341773 5.378272)
		(width 0.104648)
		(layer "In3.Cu")
		(net "DDR0_32A_DQ4")
	)
	(segment
		(start 69.573267 4.146779)
		(end 71.12 4.146779)
		(width 0.104648)
		(layer "In3.Cu")
		(net "DDR0_32A_DQ4")
	)
	(segment
		(start 75.273459 2.992399)
		(end 75.273459 2.971622)
		(width 0.12065)
		(layer "In3.Cu")
		(net "DDR0_32A_DQ4")
	)
	(segment
		(start 75.273459 2.971622)
		(end 75.698452 2.546629)
		(width 0.12065)
		(layer "In3.Cu")
		(net "DDR0_32A_DQ4")
	)
	(segment
		(start 74.250931 3.600094)
		(end 74.504448 3.346577)
		(width 0.12065)
		(layer "In3.Cu")
		(net "DDR0_32A_DQ4")
	)
	(segment
		(start 68.341773 5.378272)
		(end 69.573267 4.146779)
		(width 0.104648)
		(layer "In3.Cu")
		(net "DDR0_32A_DQ4")
	)
	(segment
		(start 69.736995 8.541995)
		(end 69.349595 8.541995)
		(width 0.104648)
		(layer "In3.Cu")
		(net "DDR0_32A_DQ4")
	)
	(segment
		(start 75.800737 2.546629)
		(end 76.048286 2.299081)
		(width 0.12065)
		(layer "In3.Cu")
		(net "DDR0_32A_DQ4")
	)
	(segment
		(start 73.662845 4.188181)
		(end 73.9521 3.898925)
		(width 0.12065)
		(layer "In3.Cu")
		(net "DDR0_32A_DQ4")
	)
	(segment
		(start 69.349595 8.541995)
		(end 68.744821 7.937221)
		(width 0.104648)
		(layer "In3.Cu")
		(net "DDR0_32A_DQ4")
	)
	(segment
		(start 76.048286 2.299081)
		(end 76.651079 2.299081)
		(width 0.12065)
		(layer "In3.Cu")
		(net "DDR0_32A_DQ4")
	)
	(segment
		(start 70.736993 10.541991)
		(end 70.236994 11.04199)
		(width 0.13208)
		(layer "F.Cu")
		(net "DDR0_32A_DQ3")
	)
	(via
		(at 70.736993 10.541991)
		(size 0.4826)
		(drill 0.20574)
		(layers "F.Cu" "B.Cu")
		(net "DDR0_32A_DQ3")
	)
	(segment
		(start 77.451001 6.298997)
		(end 77.051002 6.698996)
		(width 0.14732)
		(layer "B.Cu")
		(net "DDR0_32A_DQ3")
	)
	(segment
		(start 78.3844 11.0236)
		(end 70.3326 11.0236)
		(width 0.12065)
		(layer "In3.Cu")
		(net "DDR0_32A_DQ3")
	)
	(segment
		(start 70.231 10.922)
		(end 70.231 10.668)
		(width 0.12065)
		(layer "In3.Cu")
		(net "DDR0_32A_DQ3")
	)
	(segment
		(start 78.1558 7.7216)
		(end 78.5368 8.1026)
		(width 0.12065)
		(layer "In3.Cu")
		(net "DDR0_32A_DQ3")
	)
	(segment
		(start 77.051002 6.698996)
		(end 77.971396 6.698996)
		(width 0.12065)
		(layer "In3.Cu")
		(net "DDR0_32A_DQ3")
	)
	(segment
		(start 70.231 10.668)
		(end 70.357009 10.541991)
		(width 0.12065)
		(layer "In3.Cu")
		(net "DDR0_32A_DQ3")
	)
	(segment
		(start 78.5368 8.1026)
		(end 78.5368 10.8712)
		(width 0.12065)
		(layer "In3.Cu")
		(net "DDR0_32A_DQ3")
	)
	(segment
		(start 70.357009 10.541991)
		(end 70.736993 10.541991)
		(width 0.12065)
		(layer "In3.Cu")
		(net "DDR0_32A_DQ3")
	)
	(segment
		(start 70.3326 11.0236)
		(end 70.231 10.922)
		(width 0.12065)
		(layer "In3.Cu")
		(net "DDR0_32A_DQ3")
	)
	(segment
		(start 78.1558 6.8834)
		(end 78.1558 7.7216)
		(width 0.12065)
		(layer "In3.Cu")
		(net "DDR0_32A_DQ3")
	)
	(segment
		(start 78.5368 10.8712)
		(end 78.3844 11.0236)
		(width 0.12065)
		(layer "In3.Cu")
		(net "DDR0_32A_DQ3")
	)
	(segment
		(start 77.971396 6.698996)
		(end 78.1558 6.8834)
		(width 0.12065)
		(layer "In3.Cu")
		(net "DDR0_32A_DQ3")
	)
	(segment
		(start 69.736995 9.541993)
		(end 69.236996 10.041992)
		(width 0.13208)
		(layer "F.Cu")
		(net "DDR0_32A_DQ2")
	)
	(via
		(at 69.736995 9.541993)
		(size 0.4826)
		(drill 0.25654)
		(layers "F.Cu" "B.Cu")
		(net "DDR0_32A_DQ2")
	)
	(segment
		(start 77.451001 7.098995)
		(end 77.051002 7.498994)
		(width 0.14732)
		(layer "B.Cu")
		(net "DDR0_32A_DQ2")
	)
	(segment
		(start 71.32955 10.69975)
		(end 71.64705 10.69975)
		(width 0.12065)
		(layer "In3.Cu")
		(net "DDR0_32A_DQ2")
	)
	(segment
		(start 71.6534 10.6934)
		(end 76.4286 10.6934)
		(width 0.12065)
		(layer "In3.Cu")
		(net "DDR0_32A_DQ2")
	)
	(segment
		(start 77.9272 10.6934)
		(end 78.105 10.5156)
		(width 0.12065)
		(layer "In3.Cu")
		(net "DDR0_32A_DQ2")
	)
	(segment
		(start 78.105 10.5156)
		(end 78.105 8.2804)
		(width 0.12065)
		(layer "In3.Cu")
		(net "DDR0_32A_DQ2")
	)
	(segment
		(start 71.2216 10.2108)
		(end 71.2216 10.5918)
		(width 0.12065)
		(layer "In3.Cu")
		(net "DDR0_32A_DQ2")
	)
	(segment
		(start 77.8256 8.001)
		(end 77.8256 7.6962)
		(width 0.12065)
		(layer "In3.Cu")
		(net "DDR0_32A_DQ2")
	)
	(segment
		(start 76.4286 10.6934)
		(end 76.9112 10.2108)
		(width 0.12065)
		(layer "In3.Cu")
		(net "DDR0_32A_DQ2")
	)
	(segment
		(start 69.736995 9.541993)
		(end 69.335675 9.541993)
		(width 0.12065)
		(layer "In3.Cu")
		(net "DDR0_32A_DQ2")
	)
	(segment
		(start 77.6732 10.6934)
		(end 77.9272 10.6934)
		(width 0.12065)
		(layer "In3.Cu")
		(net "DDR0_32A_DQ2")
	)
	(segment
		(start 69.335675 9.541993)
		(end 69.215 9.662668)
		(width 0.12065)
		(layer "In3.Cu")
		(net "DDR0_32A_DQ2")
	)
	(segment
		(start 77.1906 10.2108)
		(end 77.6732 10.6934)
		(width 0.12065)
		(layer "In3.Cu")
		(net "DDR0_32A_DQ2")
	)
	(segment
		(start 69.342 10.033)
		(end 71.0438 10.033)
		(width 0.12065)
		(layer "In3.Cu")
		(net "DDR0_32A_DQ2")
	)
	(segment
		(start 77.8256 7.6962)
		(end 77.628394 7.498994)
		(width 0.12065)
		(layer "In3.Cu")
		(net "DDR0_32A_DQ2")
	)
	(segment
		(start 71.64705 10.69975)
		(end 71.6534 10.6934)
		(width 0.12065)
		(layer "In3.Cu")
		(net "DDR0_32A_DQ2")
	)
	(segment
		(start 71.0438 10.033)
		(end 71.2216 10.2108)
		(width 0.12065)
		(layer "In3.Cu")
		(net "DDR0_32A_DQ2")
	)
	(segment
		(start 78.105 8.2804)
		(end 77.8256 8.001)
		(width 0.12065)
		(layer "In3.Cu")
		(net "DDR0_32A_DQ2")
	)
	(segment
		(start 77.628394 7.498994)
		(end 77.051002 7.498994)
		(width 0.12065)
		(layer "In3.Cu")
		(net "DDR0_32A_DQ2")
	)
	(segment
		(start 76.9112 10.2108)
		(end 77.1906 10.2108)
		(width 0.12065)
		(layer "In3.Cu")
		(net "DDR0_32A_DQ2")
	)
	(segment
		(start 71.2216 10.5918)
		(end 71.32955 10.69975)
		(width 0.12065)
		(layer "In3.Cu")
		(net "DDR0_32A_DQ2")
	)
	(segment
		(start 69.215 9.906)
		(end 69.342 10.033)
		(width 0.12065)
		(layer "In3.Cu")
		(net "DDR0_32A_DQ2")
	)
	(segment
		(start 69.215 9.662668)
		(end 69.215 9.906)
		(width 0.12065)
		(layer "In3.Cu")
		(net "DDR0_32A_DQ2")
	)
	(segment
		(start 68.736997 9.541993)
		(end 68.236998 10.041992)
		(width 0.13208)
		(layer "F.Cu")
		(net "DDR0_32A_DQ1")
	)
	(via
		(at 68.736997 9.541993)
		(size 0.4826)
		(drill 0.25654)
		(layers "F.Cu" "B.Cu")
		(net "DDR0_32A_DQ1")
	)
	(segment
		(start 76.651002 2.299005)
		(end 76.251003 1.899006)
		(width 0.14732)
		(layer "B.Cu")
		(net "DDR0_32A_DQ1")
	)
	(segment
		(start 70.976007 3.940531)
		(end 71.01746 3.899078)
		(width 0.104648)
		(layer "In3.Cu")
		(net "DDR0_32A_DQ1")
	)
	(segment
		(start 76.098578 2.051431)
		(end 76.251003 1.899006)
		(width 0.12065)
		(layer "In3.Cu")
		(net "DDR0_32A_DQ1")
	)
	(segment
		(start 68.135525 8.940521)
		(end 68.135525 5.292827)
		(width 0.104648)
		(layer "In3.Cu")
		(net "DDR0_32A_DQ1")
	)
	(segment
		(start 68.736997 9.541993)
		(end 68.135525 8.940521)
		(width 0.104648)
		(layer "In3.Cu")
		(net "DDR0_32A_DQ1")
	)
	(segment
		(start 75.025809 2.869032)
		(end 75.595912 2.298929)
		(width 0.12065)
		(layer "In3.Cu")
		(net "DDR0_32A_DQ1")
	)
	(segment
		(start 74.816691 3.098927)
		(end 75.025809 2.889809)
		(width 0.12065)
		(layer "In3.Cu")
		(net "DDR0_32A_DQ1")
	)
	(segment
		(start 71.058862 3.899078)
		(end 71.22254 3.899078)
		(width 0.12065)
		(layer "In3.Cu")
		(net "DDR0_32A_DQ1")
	)
	(segment
		(start 73.175089 3.940531)
		(end 73.451085 3.664534)
		(width 0.12065)
		(layer "In3.Cu")
		(net "DDR0_32A_DQ1")
	)
	(segment
		(start 75.815901 2.099716)
		(end 75.89741 2.099716)
		(width 0.12065)
		(layer "In3.Cu")
		(net "DDR0_32A_DQ1")
	)
	(segment
		(start 75.945695 2.051431)
		(end 76.098578 2.051431)
		(width 0.12065)
		(layer "In3.Cu")
		(net "DDR0_32A_DQ1")
	)
	(segment
		(start 73.685476 3.098927)
		(end 74.816691 3.098927)
		(width 0.12065)
		(layer "In3.Cu")
		(net "DDR0_32A_DQ1")
	)
	(segment
		(start 71.263993 3.940531)
		(end 73.175089 3.940531)
		(width 0.12065)
		(layer "In3.Cu")
		(net "DDR0_32A_DQ1")
	)
	(segment
		(start 75.595912 2.298929)
		(end 75.616689 2.298929)
		(width 0.12065)
		(layer "In3.Cu")
		(net "DDR0_32A_DQ1")
	)
	(segment
		(start 71.22254 3.899078)
		(end 71.263993 3.940531)
		(width 0.12065)
		(layer "In3.Cu")
		(net "DDR0_32A_DQ1")
	)
	(segment
		(start 75.616689 2.298929)
		(end 75.815901 2.099716)
		(width 0.12065)
		(layer "In3.Cu")
		(net "DDR0_32A_DQ1")
	)
	(segment
		(start 73.451085 3.664534)
		(end 73.451085 3.333318)
		(width 0.12065)
		(layer "In3.Cu")
		(net "DDR0_32A_DQ1")
	)
	(segment
		(start 75.89741 2.099716)
		(end 75.945695 2.051431)
		(width 0.12065)
		(layer "In3.Cu")
		(net "DDR0_32A_DQ1")
	)
	(segment
		(start 75.025809 2.889809)
		(end 75.025809 2.869032)
		(width 0.12065)
		(layer "In3.Cu")
		(net "DDR0_32A_DQ1")
	)
	(segment
		(start 71.01746 3.899078)
		(end 71.058862 3.899078)
		(width 0.104648)
		(layer "In3.Cu")
		(net "DDR0_32A_DQ1")
	)
	(segment
		(start 73.451085 3.333318)
		(end 73.685476 3.098927)
		(width 0.12065)
		(layer "In3.Cu")
		(net "DDR0_32A_DQ1")
	)
	(segment
		(start 69.487821 3.940531)
		(end 70.976007 3.940531)
		(width 0.104648)
		(layer "In3.Cu")
		(net "DDR0_32A_DQ1")
	)
	(segment
		(start 68.135525 5.292827)
		(end 69.487821 3.940531)
		(width 0.104648)
		(layer "In3.Cu")
		(net "DDR0_32A_DQ1")
	)
	(segment
		(start 66.737001 9.541993)
		(end 66.237002 10.041992)
		(width 0.13208)
		(layer "F.Cu")
		(net "DDR0_32A_DQ0")
	)
	(via
		(at 66.737001 9.541993)
		(size 0.4826)
		(drill 0.25654)
		(layers "F.Cu" "B.Cu")
		(net "DDR0_32A_DQ0")
	)
	(segment
		(start 75.851004 2.299005)
		(end 75.451005 1.899006)
		(width 0.14732)
		(layer "B.Cu")
		(net "DDR0_32A_DQ0")
	)
	(segment
		(start 67.135527 5.292827)
		(end 67.491127 4.937227)
		(width 0.104648)
		(layer "In3.Cu")
		(net "DDR0_32A_DQ0")
	)
	(segment
		(start 67.900728 4.937227)
		(end 70.539026 2.298929)
		(width 0.104648)
		(layer "In3.Cu")
		(net "DDR0_32A_DQ0")
	)
	(segment
		(start 71.338872 1.499083)
		(end 74.905083 1.499083)
		(width 0.12065)
		(layer "In3.Cu")
		(net "DDR0_32A_DQ0")
	)
	(segment
		(start 70.539026 2.298929)
		(end 71.338872 1.499083)
		(width 0.12065)
		(layer "In3.Cu")
		(net "DDR0_32A_DQ0")
	)
	(segment
		(start 74.905083 1.499083)
		(end 75.305006 1.899006)
		(width 0.12065)
		(layer "In3.Cu")
		(net "DDR0_32A_DQ0")
	)
	(segment
		(start 75.305006 1.899006)
		(end 75.451005 1.899006)
		(width 0.12065)
		(layer "In3.Cu")
		(net "DDR0_32A_DQ0")
	)
	(segment
		(start 67.135527 9.064473)
		(end 67.135527 5.292827)
		(width 0.104648)
		(layer "In3.Cu")
		(net "DDR0_32A_DQ0")
	)
	(segment
		(start 66.737001 9.541993)
		(end 66.737001 9.462999)
		(width 0.104648)
		(layer "In3.Cu")
		(net "DDR0_32A_DQ0")
	)
	(segment
		(start 66.737001 9.462999)
		(end 67.135527 9.064473)
		(width 0.104648)
		(layer "In3.Cu")
		(net "DDR0_32A_DQ0")
	)
	(segment
		(start 67.491127 4.937227)
		(end 67.900728 4.937227)
		(width 0.104648)
		(layer "In3.Cu")
		(net "DDR0_32A_DQ0")
	)
	(segment
		(start 65.737003 20.541996)
		(end 65.237004 20.041997)
		(width 0.13208)
		(layer "F.Cu")
		(net "DDR0_32A_DM4")
	)
	(via
		(at 65.737003 20.541996)
		(size 0.4826)
		(drill 0.25654)
		(layers "F.Cu" "B.Cu")
		(net "DDR0_32A_DM4")
	)
	(segment
		(start 75.051006 29.412997)
		(end 74.651006 29.812996)
		(width 0.14732)
		(layer "B.Cu")
		(net "DDR0_32A_DM4")
	)
	(segment
		(start 65.737003 20.541996)
		(end 65.737003 23.573003)
		(width 0.12065)
		(layer "In3.Cu")
		(net "DDR0_32A_DM4")
	)
	(segment
		(start 65.278 24.032007)
		(end 65.278 28.0162)
		(width 0.12065)
		(layer "In3.Cu")
		(net "DDR0_32A_DM4")
	)
	(segment
		(start 65.278 28.0162)
		(end 66.3448 29.083)
		(width 0.12065)
		(layer "In3.Cu")
		(net "DDR0_32A_DM4")
	)
	(segment
		(start 69.164073 29.413073)
		(end 74.251083 29.413073)
		(width 0.12065)
		(layer "In3.Cu")
		(net "DDR0_32A_DM4")
	)
	(segment
		(start 66.3448 29.083)
		(end 68.834 29.083)
		(width 0.12065)
		(layer "In3.Cu")
		(net "DDR0_32A_DM4")
	)
	(segment
		(start 68.834 29.083)
		(end 69.164073 29.413073)
		(width 0.12065)
		(layer "In3.Cu")
		(net "DDR0_32A_DM4")
	)
	(segment
		(start 65.737003 23.573003)
		(end 65.278 24.032007)
		(width 0.12065)
		(layer "In3.Cu")
		(net "DDR0_32A_DM4")
	)
	(segment
		(start 74.251083 29.413073)
		(end 74.651006 29.812996)
		(width 0.12065)
		(layer "In3.Cu")
		(net "DDR0_32A_DM4")
	)
	(segment
		(start 66.737001 16.542004)
		(end 66.237002 17.042003)
		(width 0.13208)
		(layer "F.Cu")
		(net "DDR0_32A_DM3")
	)
	(via
		(at 66.737001 16.542004)
		(size 0.4826)
		(drill 0.20574)
		(layers "F.Cu" "B.Cu")
		(net "DDR0_32A_DM3")
	)
	(segment
		(start 74.251007 14.656003)
		(end 73.851008 14.256004)
		(width 0.254)
		(layer "B.Cu")
		(net "DDR0_32A_DM3")
	)
	(segment
		(start 67.691 14.937232)
		(end 67.676979 14.940534)
		(width 0.104648)
		(layer "In2.Cu")
		(net "DDR0_32A_DM3")
	)
	(segment
		(start 66.573273 15.146782)
		(end 66.341777 15.378278)
		(width 0.104648)
		(layer "In2.Cu")
		(net "DDR0_32A_DM3")
	)
	(segment
		(start 67.487825 14.940534)
		(end 67.263239 15.015769)
		(width 0.104648)
		(layer "In2.Cu")
		(net "DDR0_32A_DM3")
	)
	(segment
		(start 73.158172 13.856081)
		(end 72.136 13.856081)
		(width 0.12065)
		(layer "In2.Cu")
		(net "DDR0_32A_DM3")
	)
	(segment
		(start 67.263239 15.015769)
		(end 66.986175 15.14348)
		(width 0.104648)
		(layer "In2.Cu")
		(net "DDR0_32A_DM3")
	)
	(segment
		(start 72.136 13.856081)
		(end 71.152766 13.937234)
		(width 0.12065)
		(layer "In2.Cu")
		(net "DDR0_32A_DM3")
	)
	(segment
		(start 68.135525 14.292834)
		(end 68.135525 14.702434)
		(width 0.104648)
		(layer "In2.Cu")
		(net "DDR0_32A_DM3")
	)
	(segment
		(start 67.676979 14.940534)
		(end 67.487825 14.940534)
		(width 0.104648)
		(layer "In2.Cu")
		(net "DDR0_32A_DM3")
	)
	(segment
		(start 73.851008 14.256004)
		(end 73.158172 13.856081)
		(width 0.12065)
		(layer "In2.Cu")
		(net "DDR0_32A_DM3")
	)
	(segment
		(start 71.152766 13.937234)
		(end 71.12 13.937234)
		(width 0.12065)
		(layer "In2.Cu")
		(net "DDR0_32A_DM3")
	)
	(segment
		(start 66.802 15.146782)
		(end 66.573273 15.146782)
		(width 0.104648)
		(layer "In2.Cu")
		(net "DDR0_32A_DM3")
	)
	(segment
		(start 66.986175 15.14348)
		(end 66.816021 15.14348)
		(width 0.104648)
		(layer "In2.Cu")
		(net "DDR0_32A_DM3")
	)
	(segment
		(start 66.341777 15.623464)
		(end 66.737001 16.542004)
		(width 0.104648)
		(layer "In2.Cu")
		(net "DDR0_32A_DM3")
	)
	(segment
		(start 67.900728 14.937232)
		(end 67.691 14.937232)
		(width 0.104648)
		(layer "In2.Cu")
		(net "DDR0_32A_DM3")
	)
	(segment
		(start 66.816021 15.14348)
		(end 66.802 15.146782)
		(width 0.104648)
		(layer "In2.Cu")
		(net "DDR0_32A_DM3")
	)
	(segment
		(start 66.341777 15.378278)
		(end 66.341777 15.623464)
		(width 0.104648)
		(layer "In2.Cu")
		(net "DDR0_32A_DM3")
	)
	(segment
		(start 68.135525 14.702434)
		(end 67.900728 14.937232)
		(width 0.104648)
		(layer "In2.Cu")
		(net "DDR0_32A_DM3")
	)
	(segment
		(start 68.491125 13.937234)
		(end 68.135525 14.292834)
		(width 0.104648)
		(layer "In2.Cu")
		(net "DDR0_32A_DM3")
	)
	(segment
		(start 71.12 13.937234)
		(end 68.491125 13.937234)
		(width 0.104648)
		(layer "In2.Cu")
		(net "DDR0_32A_DM3")
	)
	(segment
		(start 66.737001 14.542008)
		(end 66.237002 15.042007)
		(width 0.13208)
		(layer "F.Cu")
		(net "DDR0_32A_DM2")
	)
	(via
		(at 66.737001 14.542008)
		(size 0.4826)
		(drill 0.20574)
		(layers "F.Cu" "B.Cu")
		(net "DDR0_32A_DM2")
	)
	(segment
		(start 75.051006 17.855997)
		(end 74.651006 18.255996)
		(width 0.254)
		(layer "B.Cu")
		(net "DDR0_32A_DM2")
	)
	(segment
		(start 66.886353 14.542008)
		(end 66.737001 14.542008)
		(width 0.104648)
		(layer "In3.Cu")
		(net "DDR0_32A_DM2")
	)
	(segment
		(start 69.91223 15.93723)
		(end 69.573267 15.93723)
		(width 0.104648)
		(layer "In3.Cu")
		(net "DDR0_32A_DM2")
	)
	(segment
		(start 69.573267 15.93723)
		(end 69.341771 15.705734)
		(width 0.104648)
		(layer "In3.Cu")
		(net "DDR0_32A_DM2")
	)
	(segment
		(start 74.651006 18.255996)
		(end 74.651006 17.678806)
		(width 0.12065)
		(layer "In3.Cu")
		(net "DDR0_32A_DM2")
	)
	(segment
		(start 73.85685 16.88465)
		(end 73.6346 16.88465)
		(width 0.12065)
		(layer "In3.Cu")
		(net "DDR0_32A_DM2")
	)
	(segment
		(start 73.6346 16.88465)
		(end 73.451085 17.068165)
		(width 0.12065)
		(layer "In3.Cu")
		(net "DDR0_32A_DM2")
	)
	(segment
		(start 72.129625 17.011625)
		(end 71.996249 17.145)
		(width 0.12065)
		(layer "In3.Cu")
		(net "DDR0_32A_DM2")
	)
	(segment
		(start 69.341771 15.705734)
		(end 69.341771 15.493771)
		(width 0.104648)
		(layer "In3.Cu")
		(net "DDR0_32A_DM2")
	)
	(segment
		(start 72.650934 17.634534)
		(end 72.650934 17.290161)
		(width 0.12065)
		(layer "In3.Cu")
		(net "DDR0_32A_DM2")
	)
	(segment
		(start 71.996249 17.145)
		(end 71.628 17.145)
		(width 0.12065)
		(layer "In3.Cu")
		(net "DDR0_32A_DM2")
	)
	(segment
		(start 74.651006 17.678806)
		(end 73.85685 16.88465)
		(width 0.12065)
		(layer "In3.Cu")
		(net "DDR0_32A_DM2")
	)
	(segment
		(start 73.451085 17.068165)
		(end 73.451085 17.621529)
		(width 0.12065)
		(layer "In3.Cu")
		(net "DDR0_32A_DM2")
	)
	(segment
		(start 72.372398 17.011625)
		(end 72.129625 17.011625)
		(width 0.12065)
		(layer "In3.Cu")
		(net "DDR0_32A_DM2")
	)
	(segment
		(start 71.420228 16.937228)
		(end 71.12 16.937228)
		(width 0.12065)
		(layer "In3.Cu")
		(net "DDR0_32A_DM2")
	)
	(segment
		(start 70.573265 16.937228)
		(end 70.341769 16.705732)
		(width 0.104648)
		(layer "In3.Cu")
		(net "DDR0_32A_DM2")
	)
	(segment
		(start 70.341769 16.705732)
		(end 70.341769 16.366769)
		(width 0.104648)
		(layer "In3.Cu")
		(net "DDR0_32A_DM2")
	)
	(segment
		(start 72.872321 17.855921)
		(end 72.650934 17.634534)
		(width 0.12065)
		(layer "In3.Cu")
		(net "DDR0_32A_DM2")
	)
	(segment
		(start 71.628 17.145)
		(end 71.420228 16.937228)
		(width 0.12065)
		(layer "In3.Cu")
		(net "DDR0_32A_DM2")
	)
	(segment
		(start 71.12 16.937228)
		(end 70.573265 16.937228)
		(width 0.104648)
		(layer "In3.Cu")
		(net "DDR0_32A_DM2")
	)
	(segment
		(start 68.99148 15.14348)
		(end 67.487825 15.14348)
		(width 0.104648)
		(layer "In3.Cu")
		(net "DDR0_32A_DM2")
	)
	(segment
		(start 69.341771 15.493771)
		(end 68.99148 15.14348)
		(width 0.104648)
		(layer "In3.Cu")
		(net "DDR0_32A_DM2")
	)
	(segment
		(start 72.650934 17.290161)
		(end 72.372398 17.011625)
		(width 0.12065)
		(layer "In3.Cu")
		(net "DDR0_32A_DM2")
	)
	(segment
		(start 67.487825 15.14348)
		(end 66.886353 14.542008)
		(width 0.104648)
		(layer "In3.Cu")
		(net "DDR0_32A_DM2")
	)
	(segment
		(start 70.341769 16.366769)
		(end 69.91223 15.93723)
		(width 0.104648)
		(layer "In3.Cu")
		(net "DDR0_32A_DM2")
	)
	(segment
		(start 73.216694 17.855921)
		(end 72.872321 17.855921)
		(width 0.12065)
		(layer "In3.Cu")
		(net "DDR0_32A_DM2")
	)
	(segment
		(start 73.451085 17.621529)
		(end 73.216694 17.855921)
		(width 0.12065)
		(layer "In3.Cu")
		(net "DDR0_32A_DM2")
	)
	(segment
		(start 68.736997 10.541991)
		(end 68.236998 11.04199)
		(width 0.13208)
		(layer "F.Cu")
		(net "DDR0_32A_DM1")
	)
	(via
		(at 68.736997 10.541991)
		(size 0.4826)
		(drill 0.25654)
		(layers "F.Cu" "B.Cu")
		(net "DDR0_32A_DM1")
	)
	(segment
		(start 74.251007 3.099003)
		(end 73.851008 2.699004)
		(width 0.14732)
		(layer "B.Cu")
		(net "DDR0_32A_DM1")
	)
	(segment
		(start 69.33377 5.568493)
		(end 68.7578 4.992522)
		(width 0.12065)
		(layer "In2.Cu")
		(net "DDR0_32A_DM1")
	)
	(segment
		(start 70.556653 4.945228)
		(end 70.566051 4.954626)
		(width 0.12065)
		(layer "In2.Cu")
		(net "DDR0_32A_DM1")
	)
	(segment
		(start 73.451085 3.098927)
		(end 73.851008 2.699004)
		(width 0.12065)
		(layer "In2.Cu")
		(net "DDR0_32A_DM1")
	)
	(segment
		(start 73.451085 3.664534)
		(end 73.451085 3.098927)
		(width 0.12065)
		(layer "In2.Cu")
		(net "DDR0_32A_DM1")
	)
	(segment
		(start 70.907935 4.954626)
		(end 71.950961 3.9116)
		(width 0.12065)
		(layer "In2.Cu")
		(net "DDR0_32A_DM1")
	)
	(segment
		(start 69.552312 4.9276)
		(end 69.56994 4.945228)
		(width 0.12065)
		(layer "In2.Cu")
		(net "DDR0_32A_DM1")
	)
	(segment
		(start 68.893334 4.563466)
		(end 69.155666 4.563466)
		(width 0.12065)
		(layer "In2.Cu")
		(net "DDR0_32A_DM1")
	)
	(segment
		(start 68.736997 10.541991)
		(end 69.112409 10.541991)
		(width 0.12065)
		(layer "In2.Cu")
		(net "DDR0_32A_DM1")
	)
	(segment
		(start 69.5198 4.9276)
		(end 69.552312 4.9276)
		(width 0.12065)
		(layer "In2.Cu")
		(net "DDR0_32A_DM1")
	)
	(segment
		(start 69.56994 4.945228)
		(end 70.556653 4.945228)
		(width 0.12065)
		(layer "In2.Cu")
		(net "DDR0_32A_DM1")
	)
	(segment
		(start 69.33377 10.32063)
		(end 69.33377 5.568493)
		(width 0.12065)
		(layer "In2.Cu")
		(net "DDR0_32A_DM1")
	)
	(segment
		(start 73.204019 3.9116)
		(end 73.451085 3.664534)
		(width 0.12065)
		(layer "In2.Cu")
		(net "DDR0_32A_DM1")
	)
	(segment
		(start 68.7578 4.699)
		(end 68.893334 4.563466)
		(width 0.12065)
		(layer "In2.Cu")
		(net "DDR0_32A_DM1")
	)
	(segment
		(start 69.112409 10.541991)
		(end 69.33377 10.32063)
		(width 0.12065)
		(layer "In2.Cu")
		(net "DDR0_32A_DM1")
	)
	(segment
		(start 68.7578 4.992522)
		(end 68.7578 4.699)
		(width 0.12065)
		(layer "In2.Cu")
		(net "DDR0_32A_DM1")
	)
	(segment
		(start 71.950961 3.9116)
		(end 73.204019 3.9116)
		(width 0.12065)
		(layer "In2.Cu")
		(net "DDR0_32A_DM1")
	)
	(segment
		(start 70.566051 4.954626)
		(end 70.907935 4.954626)
		(width 0.12065)
		(layer "In2.Cu")
		(net "DDR0_32A_DM1")
	)
	(segment
		(start 69.155666 4.563466)
		(end 69.5198 4.9276)
		(width 0.12065)
		(layer "In2.Cu")
		(net "DDR0_32A_DM1")
	)
	(segment
		(start 70.736993 6.541999)
		(end 70.236994 7.041998)
		(width 0.13208)
		(layer "F.Cu")
		(net "DDR0_32A_DM0")
	)
	(via
		(at 70.736993 6.541999)
		(size 0.4826)
		(drill 0.20574)
		(layers "F.Cu" "B.Cu")
		(net "DDR0_32A_DM0")
	)
	(segment
		(start 75.051006 6.298997)
		(end 74.651006 6.698996)
		(width 0.14732)
		(layer "B.Cu")
		(net "DDR0_32A_DM0")
	)
	(segment
		(start 76.162078 5.498922)
		(end 76.454 5.207)
		(width 0.12065)
		(layer "In3.Cu")
		(net "DDR0_32A_DM0")
	)
	(segment
		(start 74.205922 5.498922)
		(end 74.377677 5.670677)
		(width 0.12065)
		(layer "In3.Cu")
		(net "DDR0_32A_DM0")
	)
	(segment
		(start 78.5368 5.969)
		(end 78.4098 6.096)
		(width 0.12065)
		(layer "In3.Cu")
		(net "DDR0_32A_DM0")
	)
	(segment
		(start 78.5368 5.588)
		(end 78.5368 5.969)
		(width 0.12065)
		(layer "In3.Cu")
		(net "DDR0_32A_DM0")
	)
	(segment
		(start 77.089 5.498922)
		(end 78.447722 5.498922)
		(width 0.12065)
		(layer "In3.Cu")
		(net "DDR0_32A_DM0")
	)
	(segment
		(start 71.386878 5.498922)
		(end 74.205922 5.498922)
		(width 0.12065)
		(layer "In3.Cu")
		(net "DDR0_32A_DM0")
	)
	(segment
		(start 78.447722 5.498922)
		(end 78.5368 5.588)
		(width 0.12065)
		(layer "In3.Cu")
		(net "DDR0_32A_DM0")
	)
	(segment
		(start 74.409224 6.457213)
		(end 74.651006 6.698996)
		(width 0.12065)
		(layer "In3.Cu")
		(net "DDR0_32A_DM0")
	)
	(segment
		(start 74.409224 6.362776)
		(end 74.409224 6.457213)
		(width 0.12065)
		(layer "In3.Cu")
		(net "DDR0_32A_DM0")
	)
	(segment
		(start 78.4098 6.096)
		(end 75.692 6.096)
		(width 0.12065)
		(layer "In3.Cu")
		(net "DDR0_32A_DM0")
	)
	(segment
		(start 74.6268 6.013323)
		(end 74.9792 6.013323)
		(width 0.12065)
		(layer "In3.Cu")
		(net "DDR0_32A_DM0")
	)
	(segment
		(start 76.797078 5.207)
		(end 77.089 5.498922)
		(width 0.12065)
		(layer "In3.Cu")
		(net "DDR0_32A_DM0")
	)
	(segment
		(start 76.454 5.207)
		(end 76.797078 5.207)
		(width 0.12065)
		(layer "In3.Cu")
		(net "DDR0_32A_DM0")
	)
	(segment
		(start 75.488927 6.299073)
		(end 74.472927 6.299073)
		(width 0.12065)
		(layer "In3.Cu")
		(net "DDR0_32A_DM0")
	)
	(segment
		(start 75.692 6.096)
		(end 75.488927 6.299073)
		(width 0.12065)
		(layer "In3.Cu")
		(net "DDR0_32A_DM0")
	)
	(segment
		(start 74.9792 6.013323)
		(end 75.493601 5.498922)
		(width 0.12065)
		(layer "In3.Cu")
		(net "DDR0_32A_DM0")
	)
	(segment
		(start 74.472927 6.299073)
		(end 74.409224 6.362776)
		(width 0.12065)
		(layer "In3.Cu")
		(net "DDR0_32A_DM0")
	)
	(segment
		(start 75.493601 5.498922)
		(end 76.162078 5.498922)
		(width 0.12065)
		(layer "In3.Cu")
		(net "DDR0_32A_DM0")
	)
	(segment
		(start 74.377677 5.7642)
		(end 74.6268 6.013323)
		(width 0.12065)
		(layer "In3.Cu")
		(net "DDR0_32A_DM0")
	)
	(segment
		(start 70.736993 6.148807)
		(end 71.386878 5.498922)
		(width 0.12065)
		(layer "In3.Cu")
		(net "DDR0_32A_DM0")
	)
	(segment
		(start 70.736993 6.541999)
		(end 70.736993 6.148807)
		(width 0.12065)
		(layer "In3.Cu")
		(net "DDR0_32A_DM0")
	)
	(segment
		(start 74.377677 5.670677)
		(end 74.377677 5.7642)
		(width 0.12065)
		(layer "In3.Cu")
		(net "DDR0_32A_DM0")
	)
	(segment
		(start 79.1972 23.4061)
		(end 79.375 24.13701)
		(width 0.14732)
		(layer "F.Cu")
		(net "DDR0_32A_CS0_L")
	)
	(segment
		(start 79.375 24.13701)
		(end 80.250995 25.013006)
		(width 0.14732)
		(layer "F.Cu")
		(net "DDR0_32A_CS0_L")
	)
	(segment
		(start 62.737009 15.542006)
		(end 62.23701 16.042005)
		(width 0.233528)
		(layer "F.Cu")
		(net "DDR0_32A_CS0_L")
	)
	(via
		(at 80.250995 25.013006)
		(size 0.4572)
		(drill 0.20574)
		(layers "F.Cu" "B.Cu")
		(net "DDR0_32A_CS0_L")
	)
	(via
		(at 80.250995 1.899006)
		(size 0.4572)
		(drill 0.20574)
		(layers "F.Cu" "B.Cu")
		(net "DDR0_32A_CS0_L")
	)
	(via
		(at 62.737009 15.542006)
		(size 0.4826)
		(drill 0.20574)
		(layers "F.Cu" "B.Cu")
		(net "DDR0_32A_CS0_L")
	)
	(via
		(at 80.250995 13.456006)
		(size 0.762)
		(drill 0.20574)
		(layers "F.Cu" "B.Cu")
		(net "DDR0_32A_CS0_L")
	)
	(segment
		(start 79.850996 25.413005)
		(end 80.250995 25.013006)
		(width 0.14732)
		(layer "B.Cu")
		(net "DDR0_32A_CS0_L")
	)
	(segment
		(start 79.850996 13.856005)
		(end 80.250995 13.456006)
		(width 0.14732)
		(layer "B.Cu")
		(net "DDR0_32A_CS0_L")
	)
	(segment
		(start 79.850996 2.299005)
		(end 80.250995 1.899006)
		(width 0.14732)
		(layer "B.Cu")
		(net "DDR0_32A_CS0_L")
	)
	(segment
		(start 63.095403 15.9004)
		(end 63.804825 15.9004)
		(width 0.188697)
		(layer "In2.Cu")
		(net "DDR0_32A_CS0_L")
	)
	(segment
		(start 78.282825 -0.293853)
		(end 78.282825 -1.128547)
		(width 0.188697)
		(layer "In2.Cu")
		(net "DDR0_32A_CS0_L")
	)
	(segment
		(start 65.151 7.773264)
		(end 65.151 7.74639)
		(width 0.188697)
		(layer "In2.Cu")
		(net "DDR0_32A_CS0_L")
	)
	(segment
		(start 64.802563 8.121701)
		(end 65.151 7.773264)
		(width 0.188697)
		(layer "In2.Cu")
		(net "DDR0_32A_CS0_L")
	)
	(segment
		(start 75.354612 -0.928853)
		(end 75.521464 -0.762)
		(width 0.188697)
		(layer "In2.Cu")
		(net "DDR0_32A_CS0_L")
	)
	(segment
		(start 76.573736 -1.128547)
		(end 76.573736 -0.293853)
		(width 0.188697)
		(layer "In2.Cu")
		(net "DDR0_32A_CS0_L")
	)
	(segment
		(start 78.282825 -1.128547)
		(end 78.449678 -1.2954)
		(width 0.188697)
		(layer "In2.Cu")
		(net "DDR0_32A_CS0_L")
	)
	(segment
		(start 77.143432 -0.293853)
		(end 77.143432 -1.128547)
		(width 0.188697)
		(layer "In2.Cu")
		(net "DDR0_32A_CS0_L")
	)
	(segment
		(start 64.299744 3.368599)
		(end 64.5668 3.101543)
		(width 0.188697)
		(layer "In2.Cu")
		(net "DDR0_32A_CS0_L")
	)
	(segment
		(start 75.924308 -0.928853)
		(end 75.924308 -1.128547)
		(width 0.188697)
		(layer "In2.Cu")
		(net "DDR0_32A_CS0_L")
	)
	(segment
		(start 78.926919 0.574929)
		(end 80.250995 1.899006)
		(width 0.188697)
		(layer "In2.Cu")
		(net "DDR0_32A_CS0_L")
	)
	(segment
		(start 75.924308 -1.128547)
		(end 76.091161 -1.2954)
		(width 0.188697)
		(layer "In2.Cu")
		(net "DDR0_32A_CS0_L")
	)
	(segment
		(start 77.713129 -1.128547)
		(end 77.713129 -0.293853)
		(width 0.188697)
		(layer "In2.Cu")
		(net "DDR0_32A_CS0_L")
	)
	(segment
		(start 78.115973 -0.127)
		(end 78.282825 -0.293853)
		(width 0.188697)
		(layer "In2.Cu")
		(net "DDR0_32A_CS0_L")
	)
	(segment
		(start 65.174266 7.723124)
		(end 65.174266 7.360869)
		(width 0.188697)
		(layer "In2.Cu")
		(net "DDR0_32A_CS0_L")
	)
	(segment
		(start 65.151 7.337603)
		(end 65.151 6.477)
		(width 0.188697)
		(layer "In2.Cu")
		(net "DDR0_32A_CS0_L")
	)
	(segment
		(start 76.091161 -1.2954)
		(end 76.406883 -1.2954)
		(width 0.188697)
		(layer "In2.Cu")
		(net "DDR0_32A_CS0_L")
	)
	(segment
		(start 75.521464 -0.762)
		(end 75.757456 -0.762)
		(width 0.188697)
		(layer "In2.Cu")
		(net "DDR0_32A_CS0_L")
	)
	(segment
		(start 77.143432 -1.128547)
		(end 77.310285 -1.2954)
		(width 0.188697)
		(layer "In2.Cu")
		(net "DDR0_32A_CS0_L")
	)
	(segment
		(start 67.071367 -1.284503)
		(end 67.151275 -1.284503)
		(width 0.188697)
		(layer "In2.Cu")
		(net "DDR0_32A_CS0_L")
	)
	(segment
		(start 77.546276 -1.2954)
		(end 77.713129 -1.128547)
		(width 0.188697)
		(layer "In2.Cu")
		(net "DDR0_32A_CS0_L")
	)
	(segment
		(start 65.151 6.477)
		(end 64.643 5.969)
		(width 0.188697)
		(layer "In2.Cu")
		(net "DDR0_32A_CS0_L")
	)
	(segment
		(start 64.389 4.812386)
		(end 64.299744 4.72313)
		(width 0.188697)
		(layer "In2.Cu")
		(net "DDR0_32A_CS0_L")
	)
	(segment
		(start 77.879981 -0.127)
		(end 78.115973 -0.127)
		(width 0.188697)
		(layer "In2.Cu")
		(net "DDR0_32A_CS0_L")
	)
	(segment
		(start 76.406883 -1.2954)
		(end 76.573736 -1.128547)
		(width 0.188697)
		(layer "In2.Cu")
		(net "DDR0_32A_CS0_L")
	)
	(segment
		(start 76.573736 -0.293853)
		(end 76.740588 -0.127)
		(width 0.188697)
		(layer "In2.Cu")
		(net "DDR0_32A_CS0_L")
	)
	(segment
		(start 78.449678 -1.2954)
		(end 78.7654 -1.2954)
		(width 0.188697)
		(layer "In2.Cu")
		(net "DDR0_32A_CS0_L")
	)
	(segment
		(start 64.237006 15.468219)
		(end 64.237006 9.422968)
		(width 0.188697)
		(layer "In2.Cu")
		(net "DDR0_32A_CS0_L")
	)
	(segment
		(start 65.151 7.74639)
		(end 65.174266 7.723124)
		(width 0.188697)
		(layer "In2.Cu")
		(net "DDR0_32A_CS0_L")
	)
	(segment
		(start 64.299744 4.72313)
		(end 64.299744 3.368599)
		(width 0.188697)
		(layer "In2.Cu")
		(net "DDR0_32A_CS0_L")
	)
	(segment
		(start 64.389 4.826)
		(end 64.389 4.812386)
		(width 0.188697)
		(layer "In2.Cu")
		(net "DDR0_32A_CS0_L")
	)
	(segment
		(start 64.802563 8.857412)
		(end 64.802563 8.121701)
		(width 0.188697)
		(layer "In2.Cu")
		(net "DDR0_32A_CS0_L")
	)
	(segment
		(start 65.174266 7.360869)
		(end 65.151 7.337603)
		(width 0.188697)
		(layer "In2.Cu")
		(net "DDR0_32A_CS0_L")
	)
	(segment
		(start 64.237006 9.422968)
		(end 64.802563 8.857412)
		(width 0.188697)
		(layer "In2.Cu")
		(net "DDR0_32A_CS0_L")
	)
	(segment
		(start 67.162172 -1.2954)
		(end 75.187759 -1.2954)
		(width 0.188697)
		(layer "In2.Cu")
		(net "DDR0_32A_CS0_L")
	)
	(segment
		(start 64.5668 3.101543)
		(end 64.5668 1.220064)
		(width 0.188697)
		(layer "In2.Cu")
		(net "DDR0_32A_CS0_L")
	)
	(segment
		(start 76.97658 -0.127)
		(end 77.143432 -0.293853)
		(width 0.188697)
		(layer "In2.Cu")
		(net "DDR0_32A_CS0_L")
	)
	(segment
		(start 77.310285 -1.2954)
		(end 77.546276 -1.2954)
		(width 0.188697)
		(layer "In2.Cu")
		(net "DDR0_32A_CS0_L")
	)
	(segment
		(start 63.804825 15.9004)
		(end 64.237006 15.468219)
		(width 0.188697)
		(layer "In2.Cu")
		(net "DDR0_32A_CS0_L")
	)
	(segment
		(start 64.5668 1.220064)
		(end 67.071367 -1.284503)
		(width 0.188697)
		(layer "In2.Cu")
		(net "DDR0_32A_CS0_L")
	)
	(segment
		(start 75.757456 -0.762)
		(end 75.924308 -0.928853)
		(width 0.188697)
		(layer "In2.Cu")
		(net "DDR0_32A_CS0_L")
	)
	(segment
		(start 64.643 5.969)
		(end 64.643 5.08)
		(width 0.188697)
		(layer "In2.Cu")
		(net "DDR0_32A_CS0_L")
	)
	(segment
		(start 62.737009 15.542006)
		(end 63.095403 15.9004)
		(width 0.188697)
		(layer "In2.Cu")
		(net "DDR0_32A_CS0_L")
	)
	(segment
		(start 67.151275 -1.284503)
		(end 67.162172 -1.2954)
		(width 0.188697)
		(layer "In2.Cu")
		(net "DDR0_32A_CS0_L")
	)
	(segment
		(start 64.643 5.08)
		(end 64.389 4.826)
		(width 0.188697)
		(layer "In2.Cu")
		(net "DDR0_32A_CS0_L")
	)
	(segment
		(start 77.713129 -0.293853)
		(end 77.879981 -0.127)
		(width 0.188697)
		(layer "In2.Cu")
		(net "DDR0_32A_CS0_L")
	)
	(segment
		(start 75.354612 -1.128547)
		(end 75.354612 -0.928853)
		(width 0.188697)
		(layer "In2.Cu")
		(net "DDR0_32A_CS0_L")
	)
	(segment
		(start 78.7654 -1.2954)
		(end 78.926919 -1.133881)
		(width 0.188697)
		(layer "In2.Cu")
		(net "DDR0_32A_CS0_L")
	)
	(segment
		(start 75.187759 -1.2954)
		(end 75.354612 -1.128547)
		(width 0.188697)
		(layer "In2.Cu")
		(net "DDR0_32A_CS0_L")
	)
	(segment
		(start 78.926919 -1.133881)
		(end 78.926919 0.574929)
		(width 0.188697)
		(layer "In2.Cu")
		(net "DDR0_32A_CS0_L")
	)
	(segment
		(start 76.740588 -0.127)
		(end 76.97658 -0.127)
		(width 0.188697)
		(layer "In2.Cu")
		(net "DDR0_32A_CS0_L")
	)
	(segment
		(start 80.250995 13.456006)
		(end 79.856711 13.061721)
		(width 0.12065)
		(layer "In6.Cu")
		(net "DDR0_32A_CS0_L")
	)
	(segment
		(start 80.250995 25.013006)
		(end 79.856711 24.618721)
		(width 0.12065)
		(layer "In6.Cu")
		(net "DDR0_32A_CS0_L")
	)
	(segment
		(start 79.856711 2.29329)
		(end 80.250995 1.899006)
		(width 0.12065)
		(layer "In6.Cu")
		(net "DDR0_32A_CS0_L")
	)
	(segment
		(start 79.856711 13.85029)
		(end 80.250995 13.456006)
		(width 0.12065)
		(layer "In6.Cu")
		(net "DDR0_32A_CS0_L")
	)
	(segment
		(start 79.856711 24.618721)
		(end 79.856711 13.85029)
		(width 0.12065)
		(layer "In6.Cu")
		(net "DDR0_32A_CS0_L")
	)
	(segment
		(start 79.856711 13.061721)
		(end 79.856711 2.29329)
		(width 0.12065)
		(layer "In6.Cu")
		(net "DDR0_32A_CS0_L")
	)
	(segment
		(start 79.375 31.48899)
		(end 79.450997 31.412993)
		(width 0.14732)
		(layer "F.Cu")
		(net "DDR0_32A_CKE0")
	)
	(segment
		(start 64.737005 11.541989)
		(end 64.237006 12.041988)
		(width 0.233528)
		(layer "F.Cu")
		(net "DDR0_32A_CKE0")
	)
	(segment
		(start 79.248 32.157314)
		(end 79.248 31.61599)
		(width 0.139446)
		(layer "F.Cu")
		(net "DDR0_32A_CKE0")
	)
	(segment
		(start 79.248 31.61599)
		(end 79.375 31.48899)
		(width 0.139446)
		(layer "F.Cu")
		(net "DDR0_32A_CKE0")
	)
	(via
		(at 64.737005 11.541989)
		(size 0.4826)
		(drill 0.20574)
		(layers "F.Cu" "B.Cu")
		(net "DDR0_32A_CKE0")
	)
	(via
		(at 79.450997 8.298993)
		(size 0.762)
		(drill 0.20574)
		(layers "F.Cu" "B.Cu")
		(net "DDR0_32A_CKE0")
	)
	(via
		(at 79.450997 31.412993)
		(size 0.4572)
		(drill 0.20574)
		(layers "F.Cu" "B.Cu")
		(net "DDR0_32A_CKE0")
	)
	(via
		(at 79.450997 19.855993)
		(size 0.4572)
		(drill 0.20574)
		(layers "F.Cu" "B.Cu")
		(net "DDR0_32A_CKE0")
	)
	(segment
		(start 79.050998 7.898994)
		(end 79.450997 8.298993)
		(width 0.14732)
		(layer "B.Cu")
		(net "DDR0_32A_CKE0")
	)
	(segment
		(start 79.050998 19.455994)
		(end 79.450997 19.855993)
		(width 0.14732)
		(layer "B.Cu")
		(net "DDR0_32A_CKE0")
	)
	(segment
		(start 79.050998 31.012994)
		(end 79.450997 31.412993)
		(width 0.14732)
		(layer "B.Cu")
		(net "DDR0_32A_CKE0")
	)
	(segment
		(start 79.85092 31.01307)
		(end 79.450997 31.412993)
		(width 0.12065)
		(layer "In2.Cu")
		(net "DDR0_32A_CKE0")
	)
	(segment
		(start 79.450997 19.855993)
		(end 79.85092 20.255916)
		(width 0.12065)
		(layer "In2.Cu")
		(net "DDR0_32A_CKE0")
	)
	(segment
		(start 79.450997 8.298993)
		(end 79.85092 8.698916)
		(width 0.12065)
		(layer "In2.Cu")
		(net "DDR0_32A_CKE0")
	)
	(segment
		(start 79.85092 19.45607)
		(end 79.450997 19.855993)
		(width 0.12065)
		(layer "In2.Cu")
		(net "DDR0_32A_CKE0")
	)
	(segment
		(start 79.85092 8.698916)
		(end 79.85092 19.45607)
		(width 0.12065)
		(layer "In2.Cu")
		(net "DDR0_32A_CKE0")
	)
	(segment
		(start 79.85092 20.255916)
		(end 79.85092 31.01307)
		(width 0.12065)
		(layer "In2.Cu")
		(net "DDR0_32A_CKE0")
	)
	(segment
		(start 79.667456 5.8674)
		(end 78.232 5.8674)
		(width 0.188697)
		(layer "In7.Cu")
		(net "DDR0_32A_CKE0")
	)
	(segment
		(start 72.121878 9.409278)
		(end 75.377827 9.409278)
		(width 0.188697)
		(layer "In7.Cu")
		(net "DDR0_32A_CKE0")
	)
	(segment
		(start 77.9018 7.0358)
		(end 77.6224 7.0358)
		(width 0.188697)
		(layer "In7.Cu")
		(net "DDR0_32A_CKE0")
	)
	(segment
		(start 71.9582 8.9408)
		(end 71.9582 9.2456)
		(width 0.188697)
		(layer "In7.Cu")
		(net "DDR0_32A_CKE0")
	)
	(segment
		(start 77.6224 7.0358)
		(end 77.4954 6.9088)
		(width 0.188697)
		(layer "In7.Cu")
		(net "DDR0_32A_CKE0")
	)
	(segment
		(start 75.377827 9.409278)
		(end 75.5396 9.57105)
		(width 0.188697)
		(layer "In7.Cu")
		(net "DDR0_32A_CKE0")
	)
	(segment
		(start 69.918123 12.979273)
		(end 63.55588 12.979273)
		(width 0.188697)
		(layer "In7.Cu")
		(net "DDR0_32A_CKE0")
	)
	(segment
		(start 79.845281 7.904709)
		(end 79.845281 6.387719)
		(width 0.12065)
		(layer "In7.Cu")
		(net "DDR0_32A_CKE0")
	)
	(segment
		(start 64.791615 11.91641)
		(end 64.791615 11.596599)
		(width 0.188697)
		(layer "In7.Cu")
		(net "DDR0_32A_CKE0")
	)
	(segment
		(start 75.121745 6.357417)
		(end 75.088801 6.357417)
		(width 0.188697)
		(layer "In7.Cu")
		(net "DDR0_32A_CKE0")
	)
	(segment
		(start 79.450997 8.298993)
		(end 79.845281 7.904709)
		(width 0.12065)
		(layer "In7.Cu")
		(net "DDR0_32A_CKE0")
	)
	(segment
		(start 69.943396 12.954)
		(end 69.918123 12.979273)
		(width 0.188697)
		(layer "In7.Cu")
		(net "DDR0_32A_CKE0")
	)
	(segment
		(start 63.17427 12.78067)
		(end 63.17427 12.26754)
		(width 0.188697)
		(layer "In7.Cu")
		(net "DDR0_32A_CKE0")
	)
	(segment
		(start 63.3476 12.954)
		(end 63.17427 12.78067)
		(width 0.188697)
		(layer "In7.Cu")
		(net "DDR0_32A_CKE0")
	)
	(segment
		(start 78.0542 6.0452)
		(end 78.0542 6.8834)
		(width 0.188697)
		(layer "In7.Cu")
		(net "DDR0_32A_CKE0")
	)
	(segment
		(start 75.057 8.509)
		(end 74.803 8.763)
		(width 0.188697)
		(layer "In7.Cu")
		(net "DDR0_32A_CKE0")
	)
	(segment
		(start 77.260831 6.270676)
		(end 75.208486 6.270676)
		(width 0.188697)
		(layer "In7.Cu")
		(net "DDR0_32A_CKE0")
	)
	(segment
		(start 74.12101 11.09599)
		(end 73.9902 11.2268)
		(width 0.188697)
		(layer "In7.Cu")
		(net "DDR0_32A_CKE0")
	)
	(segment
		(start 70.231 12.219813)
		(end 70.231 12.7762)
		(width 0.188697)
		(layer "In7.Cu")
		(net "DDR0_32A_CKE0")
	)
	(segment
		(start 77.4954 6.505245)
		(end 77.260831 6.270676)
		(width 0.188697)
		(layer "In7.Cu")
		(net "DDR0_32A_CKE0")
	)
	(segment
		(start 70.231 12.7762)
		(end 70.0532 12.954)
		(width 0.188697)
		(layer "In7.Cu")
		(net "DDR0_32A_CKE0")
	)
	(segment
		(start 75.088801 6.357417)
		(end 75.056721 6.389497)
		(width 0.12065)
		(layer "In7.Cu")
		(net "DDR0_32A_CKE0")
	)
	(segment
		(start 74.803 8.763)
		(end 72.136 8.763)
		(width 0.188697)
		(layer "In7.Cu")
		(net "DDR0_32A_CKE0")
	)
	(segment
		(start 71.9582 10.5156)
		(end 72.0598 10.6172)
		(width 0.188697)
		(layer "In7.Cu")
		(net "DDR0_32A_CKE0")
	)
	(segment
		(start 75.056721 8.508721)
		(end 75.057 8.509)
		(width 0.12065)
		(layer "In7.Cu")
		(net "DDR0_32A_CKE0")
	)
	(segment
		(start 71.9582 9.2456)
		(end 72.121878 9.409278)
		(width 0.188697)
		(layer "In7.Cu")
		(net "DDR0_32A_CKE0")
	)
	(segment
		(start 74.041 10.6172)
		(end 74.12101 10.69721)
		(width 0.188697)
		(layer "In7.Cu")
		(net "DDR0_32A_CKE0")
	)
	(segment
		(start 71.9582 10.106355)
		(end 71.9582 10.5156)
		(width 0.188697)
		(layer "In7.Cu")
		(net "DDR0_32A_CKE0")
	)
	(segment
		(start 63.3476 12.09421)
		(end 64.613815 12.09421)
		(width 0.188697)
		(layer "In7.Cu")
		(net "DDR0_32A_CKE0")
	)
	(segment
		(start 79.845281 6.045225)
		(end 79.667456 5.8674)
		(width 0.188697)
		(layer "In7.Cu")
		(net "DDR0_32A_CKE0")
	)
	(segment
		(start 64.791615 11.596599)
		(end 64.737005 11.541989)
		(width 0.188697)
		(layer "In7.Cu")
		(net "DDR0_32A_CKE0")
	)
	(segment
		(start 75.208486 6.270676)
		(end 75.121745 6.357417)
		(width 0.188697)
		(layer "In7.Cu")
		(net "DDR0_32A_CKE0")
	)
	(segment
		(start 78.232 5.8674)
		(end 78.0542 6.0452)
		(width 0.188697)
		(layer "In7.Cu")
		(net "DDR0_32A_CKE0")
	)
	(segment
		(start 63.530607 12.954)
		(end 63.3476 12.954)
		(width 0.188697)
		(layer "In7.Cu")
		(net "DDR0_32A_CKE0")
	)
	(segment
		(start 75.056721 6.389497)
		(end 75.056721 8.508721)
		(width 0.12065)
		(layer "In7.Cu")
		(net "DDR0_32A_CKE0")
	)
	(segment
		(start 71.193787 12.042013)
		(end 70.4088 12.042013)
		(width 0.188697)
		(layer "In7.Cu")
		(net "DDR0_32A_CKE0")
	)
	(segment
		(start 70.4088 12.042013)
		(end 70.231 12.219813)
		(width 0.188697)
		(layer "In7.Cu")
		(net "DDR0_32A_CKE0")
	)
	(segment
		(start 73.9902 11.2268)
		(end 72.009 11.2268)
		(width 0.188697)
		(layer "In7.Cu")
		(net "DDR0_32A_CKE0")
	)
	(segment
		(start 72.009 11.2268)
		(end 71.193787 12.042013)
		(width 0.188697)
		(layer "In7.Cu")
		(net "DDR0_32A_CKE0")
	)
	(segment
		(start 77.4954 6.9088)
		(end 77.4954 6.505245)
		(width 0.188697)
		(layer "In7.Cu")
		(net "DDR0_32A_CKE0")
	)
	(segment
		(start 72.096478 9.968078)
		(end 71.9582 10.106355)
		(width 0.188697)
		(layer "In7.Cu")
		(net "DDR0_32A_CKE0")
	)
	(segment
		(start 78.0542 6.8834)
		(end 77.9018 7.0358)
		(width 0.188697)
		(layer "In7.Cu")
		(net "DDR0_32A_CKE0")
	)
	(segment
		(start 63.17427 12.26754)
		(end 63.3476 12.09421)
		(width 0.188697)
		(layer "In7.Cu")
		(net "DDR0_32A_CKE0")
	)
	(segment
		(start 64.613815 12.09421)
		(end 64.791615 11.91641)
		(width 0.188697)
		(layer "In7.Cu")
		(net "DDR0_32A_CKE0")
	)
	(segment
		(start 75.422912 9.968078)
		(end 72.096478 9.968078)
		(width 0.188697)
		(layer "In7.Cu")
		(net "DDR0_32A_CKE0")
	)
	(segment
		(start 72.0598 10.6172)
		(end 74.041 10.6172)
		(width 0.188697)
		(layer "In7.Cu")
		(net "DDR0_32A_CKE0")
	)
	(segment
		(start 79.845281 6.387719)
		(end 79.845281 6.045225)
		(width 0.188697)
		(layer "In7.Cu")
		(net "DDR0_32A_CKE0")
	)
	(segment
		(start 74.12101 10.69721)
		(end 74.12101 11.09599)
		(width 0.188697)
		(layer "In7.Cu")
		(net "DDR0_32A_CKE0")
	)
	(segment
		(start 75.5396 9.57105)
		(end 75.5396 9.85139)
		(width 0.188697)
		(layer "In7.Cu")
		(net "DDR0_32A_CKE0")
	)
	(segment
		(start 70.0532 12.954)
		(end 69.943396 12.954)
		(width 0.188697)
		(layer "In7.Cu")
		(net "DDR0_32A_CKE0")
	)
	(segment
		(start 72.136 8.763)
		(end 71.9582 8.9408)
		(width 0.188697)
		(layer "In7.Cu")
		(net "DDR0_32A_CKE0")
	)
	(segment
		(start 63.55588 12.979273)
		(end 63.530607 12.954)
		(width 0.188697)
		(layer "In7.Cu")
		(net "DDR0_32A_CKE0")
	)
	(segment
		(start 75.5396 9.85139)
		(end 75.422912 9.968078)
		(width 0.188697)
		(layer "In7.Cu")
		(net "DDR0_32A_CKE0")
	)
	(segment
		(start 78.696642 28.990925)
		(end 78.88605 29.180333)
		(width 0.099314)
		(layer "F.Cu")
		(net "DDR0_32A_CK0_P")
	)
	(segment
		(start 78.88605 29.577944)
		(end 78.650998 29.812996)
		(width 0.099314)
		(layer "F.Cu")
		(net "DDR0_32A_CK0_P")
	)
	(segment
		(start 77.646936 28.755975)
		(end 77.881886 28.990925)
		(width 0.099314)
		(layer "F.Cu")
		(net "DDR0_32A_CK0_P")
	)
	(segment
		(start 78.88605 29.180333)
		(end 78.88605 29.577944)
		(width 0.099314)
		(layer "F.Cu")
		(net "DDR0_32A_CK0_P")
	)
	(segment
		(start 77.881886 28.990925)
		(end 78.696642 28.990925)
		(width 0.099314)
		(layer "F.Cu")
		(net "DDR0_32A_CK0_P")
	)
	(segment
		(start 77.454125 28.755975)
		(end 77.646936 28.755975)
		(width 0.099314)
		(layer "F.Cu")
		(net "DDR0_32A_CK0_P")
	)
	(segment
		(start 77.1271 29.083)
		(end 77.454125 28.755975)
		(width 0.099314)
		(layer "F.Cu")
		(net "DDR0_32A_CK0_P")
	)
	(segment
		(start 78.5749 5.715)
		(end 78.5749 6.622898)
		(width 0.099314)
		(layer "F.Cu")
		(net "DDR0_32A_CK0_P")
	)
	(segment
		(start 78.5749 6.622898)
		(end 78.650998 6.698996)
		(width 0.099314)
		(layer "F.Cu")
		(net "DDR0_32A_CK0_P")
	)
	(segment
		(start 63.737007 17.542002)
		(end 63.237008 17.042003)
		(width 0.099314)
		(layer "F.Cu")
		(net "DDR0_32A_CK0_P")
	)
	(via
		(at 78.650998 29.812996)
		(size 0.4572)
		(drill 0.20574)
		(layers "F.Cu" "B.Cu")
		(net "DDR0_32A_CK0_P")
	)
	(via
		(at 78.650998 6.698996)
		(size 0.4572)
		(drill 0.20574)
		(layers "F.Cu" "B.Cu")
		(net "DDR0_32A_CK0_P")
	)
	(via
		(at 63.737007 17.542002)
		(size 0.4826)
		(drill 0.25654)
		(layers "F.Cu" "B.Cu")
		(net "DDR0_32A_CK0_P")
	)
	(via
		(at 78.650998 18.255996)
		(size 0.4572)
		(drill 0.20574)
		(layers "F.Cu" "B.Cu")
		(net "DDR0_32A_CK0_P")
	)
	(segment
		(start 78.250999 17.855997)
		(end 78.650998 18.255996)
		(width 0.099314)
		(layer "B.Cu")
		(net "DDR0_32A_CK0_P")
	)
	(segment
		(start 78.250999 29.412997)
		(end 78.650998 29.812996)
		(width 0.099314)
		(layer "B.Cu")
		(net "DDR0_32A_CK0_P")
	)
	(segment
		(start 78.250999 6.298997)
		(end 78.650998 6.698996)
		(width 0.099314)
		(layer "B.Cu")
		(net "DDR0_32A_CK0_P")
	)
	(segment
		(start 77.97165 26.904848)
		(end 78.920823 27.854021)
		(width 0.096012)
		(layer "In2.Cu")
		(net "DDR0_32A_CK0_P")
	)
	(segment
		(start 78.47965 7.883373)
		(end 78.47965 8.401152)
		(width 0.096012)
		(layer "In2.Cu")
		(net "DDR0_32A_CK0_P")
	)
	(segment
		(start 78.920823 29.543172)
		(end 78.650998 29.812996)
		(width 0.096012)
		(layer "In2.Cu")
		(net "DDR0_32A_CK0_P")
	)
	(segment
		(start 78.920823 17.986172)
		(end 78.650998 18.255996)
		(width 0.096012)
		(layer "In2.Cu")
		(net "DDR0_32A_CK0_P")
	)
	(segment
		(start 78.25806 19.218783)
		(end 78.47965 19.440373)
		(width 0.096012)
		(layer "In2.Cu")
		(net "DDR0_32A_CK0_P")
	)
	(segment
		(start 78.25806 7.091934)
		(end 78.25806 7.661783)
		(width 0.096012)
		(layer "In2.Cu")
		(net "DDR0_32A_CK0_P")
	)
	(segment
		(start 78.47965 19.831152)
		(end 77.97165 20.339152)
		(width 0.096012)
		(layer "In2.Cu")
		(net "DDR0_32A_CK0_P")
	)
	(segment
		(start 78.47965 8.401152)
		(end 77.97165 8.909152)
		(width 0.096012)
		(layer "In2.Cu")
		(net "DDR0_32A_CK0_P")
	)
	(segment
		(start 78.47965 19.440373)
		(end 78.47965 19.831152)
		(width 0.096012)
		(layer "In2.Cu")
		(net "DDR0_32A_CK0_P")
	)
	(segment
		(start 77.97165 20.339152)
		(end 77.97165 26.904848)
		(width 0.096012)
		(layer "In2.Cu")
		(net "DDR0_32A_CK0_P")
	)
	(segment
		(start 77.97165 14.585848)
		(end 78.920823 15.535021)
		(width 0.096012)
		(layer "In2.Cu")
		(net "DDR0_32A_CK0_P")
	)
	(segment
		(start 78.25806 7.661783)
		(end 78.47965 7.883373)
		(width 0.096012)
		(layer "In2.Cu")
		(net "DDR0_32A_CK0_P")
	)
	(segment
		(start 78.920823 27.854021)
		(end 78.920823 29.543172)
		(width 0.096012)
		(layer "In2.Cu")
		(net "DDR0_32A_CK0_P")
	)
	(segment
		(start 78.650998 18.255996)
		(end 78.25806 18.648934)
		(width 0.096012)
		(layer "In2.Cu")
		(net "DDR0_32A_CK0_P")
	)
	(segment
		(start 78.650998 6.698996)
		(end 78.25806 7.091934)
		(width 0.096012)
		(layer "In2.Cu")
		(net "DDR0_32A_CK0_P")
	)
	(segment
		(start 78.920823 15.535021)
		(end 78.920823 17.986172)
		(width 0.096012)
		(layer "In2.Cu")
		(net "DDR0_32A_CK0_P")
	)
	(segment
		(start 77.97165 8.909152)
		(end 77.97165 14.585848)
		(width 0.096012)
		(layer "In2.Cu")
		(net "DDR0_32A_CK0_P")
	)
	(segment
		(start 78.25806 18.648934)
		(end 78.25806 19.218783)
		(width 0.096012)
		(layer "In2.Cu")
		(net "DDR0_32A_CK0_P")
	)
	(segment
		(start 79.74965 9.698812)
		(end 79.74965 9.424492)
		(width 0.096012)
		(layer "In7.Cu")
		(net "DDR0_32A_CK0_P")
	)
	(segment
		(start 71.221727 13.665733)
		(end 71.221727 12.684303)
		(width 0.096012)
		(layer "In7.Cu")
		(net "DDR0_32A_CK0_P")
	)
	(segment
		(start 78.47965 10.064674)
		(end 78.738832 9.805492)
		(width 0.096012)
		(layer "In7.Cu")
		(net "DDR0_32A_CK0_P")
	)
	(segment
		(start 78.47965 9.058631)
		(end 78.47965 7.89305)
		(width 0.096012)
		(layer "In7.Cu")
		(net "DDR0_32A_CK0_P")
	)
	(segment
		(start 75.819 11.80592)
		(end 75.92568 11.9126)
		(width 0.096012)
		(layer "In7.Cu")
		(net "DDR0_32A_CK0_P")
	)
	(segment
		(start 75.552198 10.99185)
		(end 75.819 11.258652)
		(width 0.096012)
		(layer "In7.Cu")
		(net "DDR0_32A_CK0_P")
	)
	(segment
		(start 80.91297 11.301552)
		(end 81.01965 11.194872)
		(width 0.096012)
		(layer "In7.Cu")
		(net "DDR0_32A_CK0_P")
	)
	(segment
		(start 76.38542 11.9126)
		(end 76.47305 11.82497)
		(width 0.096012)
		(layer "In7.Cu")
		(net "DDR0_32A_CK0_P")
	)
	(segment
		(start 63.344069 17.149064)
		(end 63.148743 17.149064)
		(width 0.095758)
		(layer "In7.Cu")
		(net "DDR0_32A_CK0_P")
	)
	(segment
		(start 81.01965 10.920552)
		(end 80.91297 10.813872)
		(width 0.096012)
		(layer "In7.Cu")
		(net "DDR0_32A_CK0_P")
	)
	(segment
		(start 75.819 11.258652)
		(end 75.819 11.80592)
		(width 0.096012)
		(layer "In7.Cu")
		(net "DDR0_32A_CK0_P")
	)
	(segment
		(start 74.903432 10.99185)
		(end 75.552198 10.99185)
		(width 0.096012)
		(layer "In7.Cu")
		(net "DDR0_32A_CK0_P")
	)
	(segment
		(start 63.132106 14.291386)
		(end 63.486386 13.937107)
		(width 0.095758)
		(layer "In7.Cu")
		(net "DDR0_32A_CK0_P")
	)
	(segment
		(start 78.47965 10.554691)
		(end 78.47965 10.064674)
		(width 0.096012)
		(layer "In7.Cu")
		(net "DDR0_32A_CK0_P")
	)
	(segment
		(start 79.64297 9.805492)
		(end 79.74965 9.698812)
		(width 0.096012)
		(layer "In7.Cu")
		(net "DDR0_32A_CK0_P")
	)
	(segment
		(start 78.738832 9.317812)
		(end 78.47965 9.058631)
		(width 0.096012)
		(layer "In7.Cu")
		(net "DDR0_32A_CK0_P")
	)
	(segment
		(start 78.47965 7.89305)
		(end 78.369363 7.782763)
		(width 0.096012)
		(layer "In7.Cu")
		(net "DDR0_32A_CK0_P")
	)
	(segment
		(start 71.99343 11.9126)
		(end 74.54392 11.9126)
		(width 0.096012)
		(layer "In7.Cu")
		(net "DDR0_32A_CK0_P")
	)
	(segment
		(start 78.738832 11.301552)
		(end 80.91297 11.301552)
		(width 0.096012)
		(layer "In7.Cu")
		(net "DDR0_32A_CK0_P")
	)
	(segment
		(start 79.64297 9.317812)
		(end 78.738832 9.317812)
		(width 0.096012)
		(layer "In7.Cu")
		(net "DDR0_32A_CK0_P")
	)
	(segment
		(start 62.782069 16.0496)
		(end 63.132106 15.699562)
		(width 0.095758)
		(layer "In7.Cu")
		(net "DDR0_32A_CK0_P")
	)
	(segment
		(start 70.982967 13.937107)
		(end 71.18637 13.733704)
		(width 0.095758)
		(layer "In7.Cu")
		(net "DDR0_32A_CK0_P")
	)
	(segment
		(start 78.25806 7.661783)
		(end 78.25806 7.336206)
		(width 0.096012)
		(layer "In7.Cu")
		(net "DDR0_32A_CK0_P")
	)
	(segment
		(start 78.47965 11.560734)
		(end 78.738832 11.301552)
		(width 0.096012)
		(layer "In7.Cu")
		(net "DDR0_32A_CK0_P")
	)
	(segment
		(start 79.74965 9.424492)
		(end 79.64297 9.317812)
		(width 0.096012)
		(layer "In7.Cu")
		(net "DDR0_32A_CK0_P")
	)
	(segment
		(start 78.47965 11.87577)
		(end 78.47965 11.560734)
		(width 0.096012)
		(layer "In7.Cu")
		(net "DDR0_32A_CK0_P")
	)
	(segment
		(start 75.92568 11.9126)
		(end 76.38542 11.9126)
		(width 0.096012)
		(layer "In7.Cu")
		(net "DDR0_32A_CK0_P")
	)
	(segment
		(start 78.37297 11.98245)
		(end 78.47965 11.87577)
		(width 0.096012)
		(layer "In7.Cu")
		(net "DDR0_32A_CK0_P")
	)
	(segment
		(start 78.738832 9.805492)
		(end 79.64297 9.805492)
		(width 0.096012)
		(layer "In7.Cu")
		(net "DDR0_32A_CK0_P")
	)
	(segment
		(start 77.464895 8.7122)
		(end 77.746276 8.993581)
		(width 0.096012)
		(layer "In7.Cu")
		(net "DDR0_32A_CK0_P")
	)
	(segment
		(start 77.853032 11.98245)
		(end 78.37297 11.98245)
		(width 0.096012)
		(layer "In7.Cu")
		(net "DDR0_32A_CK0_P")
	)
	(segment
		(start 77.746276 8.993581)
		(end 77.746276 11.875694)
		(width 0.096012)
		(layer "In7.Cu")
		(net "DDR0_32A_CK0_P")
	)
	(segment
		(start 63.486386 13.937107)
		(end 70.982967 13.937107)
		(width 0.095758)
		(layer "In7.Cu")
		(net "DDR0_32A_CK0_P")
	)
	(segment
		(start 78.738832 10.813872)
		(end 78.47965 10.554691)
		(width 0.096012)
		(layer "In7.Cu")
		(net "DDR0_32A_CK0_P")
	)
	(segment
		(start 71.20476 13.682701)
		(end 71.221727 13.665733)
		(width 0.096012)
		(layer "In7.Cu")
		(net "DDR0_32A_CK0_P")
	)
	(segment
		(start 71.221727 12.684303)
		(end 71.99343 11.9126)
		(width 0.096012)
		(layer "In7.Cu")
		(net "DDR0_32A_CK0_P")
	)
	(segment
		(start 71.18637 13.733704)
		(end 71.18637 13.70109)
		(width 0.095758)
		(layer "In7.Cu")
		(net "DDR0_32A_CK0_P")
	)
	(segment
		(start 78.369363 7.773086)
		(end 78.25806 7.661783)
		(width 0.096012)
		(layer "In7.Cu")
		(net "DDR0_32A_CK0_P")
	)
	(segment
		(start 76.47305 11.82497)
		(end 76.47305 8.971382)
		(width 0.096012)
		(layer "In7.Cu")
		(net "DDR0_32A_CK0_P")
	)
	(segment
		(start 74.54392 11.9126)
		(end 74.64425 11.81227)
		(width 0.096012)
		(layer "In7.Cu")
		(net "DDR0_32A_CK0_P")
	)
	(segment
		(start 78.25806 7.336206)
		(end 78.650998 6.943268)
		(width 0.096012)
		(layer "In7.Cu")
		(net "DDR0_32A_CK0_P")
	)
	(segment
		(start 76.732232 8.7122)
		(end 77.464895 8.7122)
		(width 0.096012)
		(layer "In7.Cu")
		(net "DDR0_32A_CK0_P")
	)
	(segment
		(start 63.737007 17.542002)
		(end 63.344069 17.149064)
		(width 0.095758)
		(layer "In7.Cu")
		(net "DDR0_32A_CK0_P")
	)
	(segment
		(start 62.782069 16.78239)
		(end 62.782069 16.0496)
		(width 0.095758)
		(layer "In7.Cu")
		(net "DDR0_32A_CK0_P")
	)
	(segment
		(start 77.746276 11.875694)
		(end 77.853032 11.98245)
		(width 0.096012)
		(layer "In7.Cu")
		(net "DDR0_32A_CK0_P")
	)
	(segment
		(start 80.91297 10.813872)
		(end 78.738832 10.813872)
		(width 0.096012)
		(layer "In7.Cu")
		(net "DDR0_32A_CK0_P")
	)
	(segment
		(start 63.148743 17.149064)
		(end 62.782069 16.78239)
		(width 0.095758)
		(layer "In7.Cu")
		(net "DDR0_32A_CK0_P")
	)
	(segment
		(start 78.369363 7.782763)
		(end 78.369363 7.773086)
		(width 0.096012)
		(layer "In7.Cu")
		(net "DDR0_32A_CK0_P")
	)
	(segment
		(start 81.01965 11.194872)
		(end 81.01965 10.920552)
		(width 0.096012)
		(layer "In7.Cu")
		(net "DDR0_32A_CK0_P")
	)
	(segment
		(start 63.132106 15.699562)
		(end 63.132106 14.291386)
		(width 0.095758)
		(layer "In7.Cu")
		(net "DDR0_32A_CK0_P")
	)
	(segment
		(start 76.47305 8.971382)
		(end 76.732232 8.7122)
		(width 0.096012)
		(layer "In7.Cu")
		(net "DDR0_32A_CK0_P")
	)
	(segment
		(start 71.18637 13.70109)
		(end 71.20476 13.682701)
		(width 0.095758)
		(layer "In7.Cu")
		(net "DDR0_32A_CK0_P")
	)
	(segment
		(start 78.650998 6.943268)
		(end 78.650998 6.698996)
		(width 0.096012)
		(layer "In7.Cu")
		(net "DDR0_32A_CK0_P")
	)
	(segment
		(start 74.64425 11.81227)
		(end 74.64425 11.251032)
		(width 0.096012)
		(layer "In7.Cu")
		(net "DDR0_32A_CK0_P")
	)
	(segment
		(start 74.64425 11.251032)
		(end 74.903432 10.99185)
		(width 0.096012)
		(layer "In7.Cu")
		(net "DDR0_32A_CK0_P")
	)
	(segment
		(start 63.737007 16.542004)
		(end 64.237006 17.042003)
		(width 0.099314)
		(layer "F.Cu")
		(net "DDR0_32A_CK0_N")
	)
	(segment
		(start 79.121 29.482999)
		(end 79.450997 29.812996)
		(width 0.099314)
		(layer "F.Cu")
		(net "DDR0_32A_CK0_N")
	)
	(segment
		(start 77.979219 28.755975)
		(end 78.793975 28.755975)
		(width 0.099314)
		(layer "F.Cu")
		(net "DDR0_32A_CK0_N")
	)
	(segment
		(start 77.454125 28.521025)
		(end 77.744269 28.521025)
		(width 0.099314)
		(layer "F.Cu")
		(net "DDR0_32A_CK0_N")
	)
	(segment
		(start 79.121 29.083)
		(end 79.121 29.482999)
		(width 0.099314)
		(layer "F.Cu")
		(net "DDR0_32A_CK0_N")
	)
	(segment
		(start 78.793975 28.755975)
		(end 79.121 29.083)
		(width 0.099314)
		(layer "F.Cu")
		(net "DDR0_32A_CK0_N")
	)
	(segment
		(start 77.744269 28.521025)
		(end 77.979219 28.755975)
		(width 0.099314)
		(layer "F.Cu")
		(net "DDR0_32A_CK0_N")
	)
	(segment
		(start 79.4131 5.715)
		(end 79.4131 6.661099)
		(width 0.099314)
		(layer "F.Cu")
		(net "DDR0_32A_CK0_N")
	)
	(segment
		(start 77.1271 28.194)
		(end 77.454125 28.521025)
		(width 0.099314)
		(layer "F.Cu")
		(net "DDR0_32A_CK0_N")
	)
	(segment
		(start 79.4131 6.661099)
		(end 79.450997 6.698996)
		(width 0.099314)
		(layer "F.Cu")
		(net "DDR0_32A_CK0_N")
	)
	(via
		(at 79.450997 6.698996)
		(size 0.4572)
		(drill 0.20574)
		(layers "F.Cu" "B.Cu")
		(net "DDR0_32A_CK0_N")
	)
	(via
		(at 63.737007 16.542004)
		(size 0.4826)
		(drill 0.25654)
		(layers "F.Cu" "B.Cu")
		(net "DDR0_32A_CK0_N")
	)
	(via
		(at 79.450997 18.255996)
		(size 0.4572)
		(drill 0.20574)
		(layers "F.Cu" "B.Cu")
		(net "DDR0_32A_CK0_N")
	)
	(via
		(at 79.450997 29.812996)
		(size 0.4572)
		(drill 0.20574)
		(layers "F.Cu" "B.Cu")
		(net "DDR0_32A_CK0_N")
	)
	(segment
		(start 79.050998 6.298997)
		(end 79.450997 6.698996)
		(width 0.099314)
		(layer "B.Cu")
		(net "DDR0_32A_CK0_N")
	)
	(segment
		(start 79.050998 17.855997)
		(end 79.450997 18.255996)
		(width 0.099314)
		(layer "B.Cu")
		(net "DDR0_32A_CK0_N")
	)
	(segment
		(start 79.050998 29.412997)
		(end 79.450997 29.812996)
		(width 0.099314)
		(layer "B.Cu")
		(net "DDR0_32A_CK0_N")
	)
	(segment
		(start 79.450997 18.255996)
		(end 79.058059 18.648934)
		(width 0.096012)
		(layer "In2.Cu")
		(net "DDR0_32A_CK0_N")
	)
	(segment
		(start 79.043936 7.661783)
		(end 78.74 7.965719)
		(width 0.096012)
		(layer "In2.Cu")
		(net "DDR0_32A_CK0_N")
	)
	(segment
		(start 78.232 14.478)
		(end 79.181173 15.427173)
		(width 0.096012)
		(layer "In2.Cu")
		(net "DDR0_32A_CK0_N")
	)
	(segment
		(start 78.74 7.965719)
		(end 78.74 8.509)
		(width 0.096012)
		(layer "In2.Cu")
		(net "DDR0_32A_CK0_N")
	)
	(segment
		(start 78.232 20.447)
		(end 78.232 26.797)
		(width 0.096012)
		(layer "In2.Cu")
		(net "DDR0_32A_CK0_N")
	)
	(segment
		(start 79.181173 17.986172)
		(end 79.450997 18.255996)
		(width 0.096012)
		(layer "In2.Cu")
		(net "DDR0_32A_CK0_N")
	)
	(segment
		(start 78.74 8.509)
		(end 78.232 9.017)
		(width 0.096012)
		(layer "In2.Cu")
		(net "DDR0_32A_CK0_N")
	)
	(segment
		(start 79.043936 7.106056)
		(end 79.043936 7.661783)
		(width 0.096012)
		(layer "In2.Cu")
		(net "DDR0_32A_CK0_N")
	)
	(segment
		(start 78.232 9.017)
		(end 78.232 14.478)
		(width 0.096012)
		(layer "In2.Cu")
		(net "DDR0_32A_CK0_N")
	)
	(segment
		(start 79.058059 18.648934)
		(end 79.058059 19.239941)
		(width 0.096012)
		(layer "In2.Cu")
		(net "DDR0_32A_CK0_N")
	)
	(segment
		(start 79.450997 6.698996)
		(end 79.043936 7.106056)
		(width 0.096012)
		(layer "In2.Cu")
		(net "DDR0_32A_CK0_N")
	)
	(segment
		(start 79.181173 29.543172)
		(end 79.450997 29.812996)
		(width 0.096012)
		(layer "In2.Cu")
		(net "DDR0_32A_CK0_N")
	)
	(segment
		(start 79.181173 15.427173)
		(end 79.181173 17.986172)
		(width 0.096012)
		(layer "In2.Cu")
		(net "DDR0_32A_CK0_N")
	)
	(segment
		(start 79.058059 19.239941)
		(end 78.74 19.558)
		(width 0.096012)
		(layer "In2.Cu")
		(net "DDR0_32A_CK0_N")
	)
	(segment
		(start 79.181173 27.746173)
		(end 79.181173 29.543172)
		(width 0.096012)
		(layer "In2.Cu")
		(net "DDR0_32A_CK0_N")
	)
	(segment
		(start 78.74 19.558)
		(end 78.74 19.939)
		(width 0.096012)
		(layer "In2.Cu")
		(net "DDR0_32A_CK0_N")
	)
	(segment
		(start 78.232 26.797)
		(end 79.181173 27.746173)
		(width 0.096012)
		(layer "In2.Cu")
		(net "DDR0_32A_CK0_N")
	)
	(segment
		(start 78.74 19.939)
		(end 78.232 20.447)
		(width 0.096012)
		(layer "In2.Cu")
		(net "DDR0_32A_CK0_N")
	)
	(segment
		(start 80.01 9.806661)
		(end 80.01 9.316644)
		(width 0.096012)
		(layer "In7.Cu")
		(net "DDR0_32A_CK0_N")
	)
	(segment
		(start 62.996191 16.693642)
		(end 62.996191 16.138347)
		(width 0.095758)
		(layer "In7.Cu")
		(net "DDR0_32A_CK0_N")
	)
	(segment
		(start 79.16164 7.22376)
		(end 79.450997 6.934403)
		(width 0.096012)
		(layer "In7.Cu")
		(net "DDR0_32A_CK0_N")
	)
	(segment
		(start 71.337754 13.885189)
		(end 71.370469 13.885189)
		(width 0.095758)
		(layer "In7.Cu")
		(net "DDR0_32A_CK0_N")
	)
	(segment
		(start 63.346228 15.78831)
		(end 63.346228 14.380134)
		(width 0.095758)
		(layer "In7.Cu")
		(net "DDR0_32A_CK0_N")
	)
	(segment
		(start 62.996191 16.138347)
		(end 63.346228 15.78831)
		(width 0.095758)
		(layer "In7.Cu")
		(net "DDR0_32A_CK0_N")
	)
	(segment
		(start 77.722908 12.2428)
		(end 78.480818 12.2428)
		(width 0.096012)
		(layer "In7.Cu")
		(net "DDR0_32A_CK0_N")
	)
	(segment
		(start 79.058059 7.647661)
		(end 79.058059 7.336206)
		(width 0.096012)
		(layer "In7.Cu")
		(net "DDR0_32A_CK0_N")
	)
	(segment
		(start 76.7334 11.932818)
		(end 76.7334 9.07923)
		(width 0.096012)
		(layer "In7.Cu")
		(net "DDR0_32A_CK0_N")
	)
	(segment
		(start 80.01 9.316644)
		(end 79.750818 9.057462)
		(width 0.096012)
		(layer "In7.Cu")
		(net "DDR0_32A_CK0_N")
	)
	(segment
		(start 77.46365 9.079154)
		(end 77.46365 11.983542)
		(width 0.096012)
		(layer "In7.Cu")
		(net "DDR0_32A_CK0_N")
	)
	(segment
		(start 71.443952 13.811707)
		(end 71.443952 12.830277)
		(width 0.096012)
		(layer "In7.Cu")
		(net "DDR0_32A_CK0_N")
	)
	(segment
		(start 74.642269 12.18245)
		(end 74.9046 11.920118)
		(width 0.096012)
		(layer "In7.Cu")
		(net "DDR0_32A_CK0_N")
	)
	(segment
		(start 75.44435 11.2522)
		(end 75.55865 11.3665)
		(width 0.096012)
		(layer "In7.Cu")
		(net "DDR0_32A_CK0_N")
	)
	(segment
		(start 78.74 11.983618)
		(end 78.74 11.668582)
		(width 0.096012)
		(layer "In7.Cu")
		(net "DDR0_32A_CK0_N")
	)
	(segment
		(start 78.74 11.668582)
		(end 78.84668 11.561902)
		(width 0.096012)
		(layer "In7.Cu")
		(net "DDR0_32A_CK0_N")
	)
	(segment
		(start 78.84668 10.553522)
		(end 78.74 10.446842)
		(width 0.096012)
		(layer "In7.Cu")
		(net "DDR0_32A_CK0_N")
	)
	(segment
		(start 74.9046 11.35888)
		(end 75.01128 11.2522)
		(width 0.096012)
		(layer "In7.Cu")
		(net "DDR0_32A_CK0_N")
	)
	(segment
		(start 81.28 10.812704)
		(end 81.020818 10.553522)
		(width 0.096012)
		(layer "In7.Cu")
		(net "DDR0_32A_CK0_N")
	)
	(segment
		(start 79.16164 7.232625)
		(end 79.16164 7.22376)
		(width 0.096012)
		(layer "In7.Cu")
		(net "DDR0_32A_CK0_N")
	)
	(segment
		(start 78.74 10.446842)
		(end 78.74 10.172522)
		(width 0.096012)
		(layer "In7.Cu")
		(net "DDR0_32A_CK0_N")
	)
	(segment
		(start 63.456033 16.934942)
		(end 63.237491 16.934942)
		(width 0.095758)
		(layer "In7.Cu")
		(net "DDR0_32A_CK0_N")
	)
	(segment
		(start 78.74 7.965719)
		(end 79.058059 7.647661)
		(width 0.096012)
		(layer "In7.Cu")
		(net "DDR0_32A_CK0_N")
	)
	(segment
		(start 75.01128 11.2522)
		(end 75.44435 11.2522)
		(width 0.096012)
		(layer "In7.Cu")
		(net "DDR0_32A_CK0_N")
	)
	(segment
		(start 78.480818 12.2428)
		(end 78.74 11.983618)
		(width 0.096012)
		(layer "In7.Cu")
		(net "DDR0_32A_CK0_N")
	)
	(segment
		(start 78.84668 10.065842)
		(end 79.750818 10.065842)
		(width 0.096012)
		(layer "In7.Cu")
		(net "DDR0_32A_CK0_N")
	)
	(segment
		(start 76.448818 12.2174)
		(end 76.7334 11.932818)
		(width 0.096012)
		(layer "In7.Cu")
		(net "DDR0_32A_CK0_N")
	)
	(segment
		(start 75.55865 11.3665)
		(end 75.55865 11.913768)
		(width 0.096012)
		(layer "In7.Cu")
		(net "DDR0_32A_CK0_N")
	)
	(segment
		(start 75.874982 12.2174)
		(end 76.448818 12.2174)
		(width 0.096012)
		(layer "In7.Cu")
		(net "DDR0_32A_CK0_N")
	)
	(segment
		(start 75.817832 12.17295)
		(end 75.830532 12.17295)
		(width 0.096012)
		(layer "In7.Cu")
		(net "DDR0_32A_CK0_N")
	)
	(segment
		(start 78.84668 11.561902)
		(end 81.020818 11.561902)
		(width 0.096012)
		(layer "In7.Cu")
		(net "DDR0_32A_CK0_N")
	)
	(segment
		(start 76.7334 9.07923)
		(end 76.84008 8.97255)
		(width 0.096012)
		(layer "In7.Cu")
		(net "DDR0_32A_CK0_N")
	)
	(segment
		(start 63.346228 14.380134)
		(end 63.575133 14.151229)
		(width 0.095758)
		(layer "In7.Cu")
		(net "DDR0_32A_CK0_N")
	)
	(segment
		(start 63.737007 16.542004)
		(end 63.737007 16.653967)
		(width 0.095758)
		(layer "In7.Cu")
		(net "DDR0_32A_CK0_N")
	)
	(segment
		(start 63.737007 16.653967)
		(end 63.456033 16.934942)
		(width 0.095758)
		(layer "In7.Cu")
		(net "DDR0_32A_CK0_N")
	)
	(segment
		(start 71.388859 13.8668)
		(end 71.443952 13.811707)
		(width 0.096012)
		(layer "In7.Cu")
		(net "DDR0_32A_CK0_N")
	)
	(segment
		(start 78.74 10.172522)
		(end 78.84668 10.065842)
		(width 0.096012)
		(layer "In7.Cu")
		(net "DDR0_32A_CK0_N")
	)
	(segment
		(start 79.450997 6.934403)
		(end 79.450997 6.698996)
		(width 0.096012)
		(layer "In7.Cu")
		(net "DDR0_32A_CK0_N")
	)
	(segment
		(start 74.9046 11.920118)
		(end 74.9046 11.35888)
		(width 0.096012)
		(layer "In7.Cu")
		(net "DDR0_32A_CK0_N")
	)
	(segment
		(start 78.84668 9.057462)
		(end 78.74 8.950782)
		(width 0.096012)
		(layer "In7.Cu")
		(net "DDR0_32A_CK0_N")
	)
	(segment
		(start 81.020818 11.561902)
		(end 81.28 11.302721)
		(width 0.096012)
		(layer "In7.Cu")
		(net "DDR0_32A_CK0_N")
	)
	(segment
		(start 63.575133 14.151229)
		(end 71.071715 14.151229)
		(width 0.095758)
		(layer "In7.Cu")
		(net "DDR0_32A_CK0_N")
	)
	(segment
		(start 78.74 8.950782)
		(end 78.74 7.965719)
		(width 0.096012)
		(layer "In7.Cu")
		(net "DDR0_32A_CK0_N")
	)
	(segment
		(start 75.830532 12.17295)
		(end 75.874982 12.2174)
		(width 0.096012)
		(layer "In7.Cu")
		(net "DDR0_32A_CK0_N")
	)
	(segment
		(start 76.84008 8.97255)
		(end 77.357046 8.97255)
		(width 0.096012)
		(layer "In7.Cu")
		(net "DDR0_32A_CK0_N")
	)
	(segment
		(start 77.46365 11.983542)
		(end 77.722908 12.2428)
		(width 0.096012)
		(layer "In7.Cu")
		(net "DDR0_32A_CK0_N")
	)
	(segment
		(start 71.443952 12.830277)
		(end 72.091779 12.18245)
		(width 0.096012)
		(layer "In7.Cu")
		(net "DDR0_32A_CK0_N")
	)
	(segment
		(start 79.750818 9.057462)
		(end 78.84668 9.057462)
		(width 0.096012)
		(layer "In7.Cu")
		(net "DDR0_32A_CK0_N")
	)
	(segment
		(start 77.357046 8.97255)
		(end 77.46365 9.079154)
		(width 0.096012)
		(layer "In7.Cu")
		(net "DDR0_32A_CK0_N")
	)
	(segment
		(start 81.020818 10.553522)
		(end 78.84668 10.553522)
		(width 0.096012)
		(layer "In7.Cu")
		(net "DDR0_32A_CK0_N")
	)
	(segment
		(start 79.058059 7.336206)
		(end 79.16164 7.232625)
		(width 0.096012)
		(layer "In7.Cu")
		(net "DDR0_32A_CK0_N")
	)
	(segment
		(start 79.750818 10.065842)
		(end 80.01 9.806661)
		(width 0.096012)
		(layer "In7.Cu")
		(net "DDR0_32A_CK0_N")
	)
	(segment
		(start 63.237491 16.934942)
		(end 62.996191 16.693642)
		(width 0.095758)
		(layer "In7.Cu")
		(net "DDR0_32A_CK0_N")
	)
	(segment
		(start 71.071715 14.151229)
		(end 71.337754 13.885189)
		(width 0.095758)
		(layer "In7.Cu")
		(net "DDR0_32A_CK0_N")
	)
	(segment
		(start 71.370469 13.885189)
		(end 71.388859 13.8668)
		(width 0.095758)
		(layer "In7.Cu")
		(net "DDR0_32A_CK0_N")
	)
	(segment
		(start 75.55865 11.913768)
		(end 75.817832 12.17295)
		(width 0.096012)
		(layer "In7.Cu")
		(net "DDR0_32A_CK0_N")
	)
	(segment
		(start 72.091779 12.18245)
		(end 74.642269 12.18245)
		(width 0.096012)
		(layer "In7.Cu")
		(net "DDR0_32A_CK0_N")
	)
	(segment
		(start 81.28 11.302721)
		(end 81.28 10.812704)
		(width 0.096012)
		(layer "In7.Cu")
		(net "DDR0_32A_CK0_N")
	)
	(segment
		(start 68.736997 19.541998)
		(end 68.236998 19.041999)
		(width 0.13208)
		(layer "F.Cu")
		(net "DDR0_32A_CB7")
	)
	(via
		(at 68.736997 19.541998)
		(size 0.4826)
		(drill 0.25654)
		(layers "F.Cu" "B.Cu")
		(net "DDR0_32A_CB7")
	)
	(segment
		(start 77.451001 26.213003)
		(end 77.051002 25.813004)
		(width 0.14732)
		(layer "B.Cu")
		(net "DDR0_32A_CB7")
	)
	(segment
		(start 69.2404 19.662673)
		(end 69.2404 22.8092)
		(width 0.12065)
		(layer "In3.Cu")
		(net "DDR0_32A_CB7")
	)
	(segment
		(start 68.736997 19.541998)
		(end 69.119725 19.541998)
		(width 0.12065)
		(layer "In3.Cu")
		(net "DDR0_32A_CB7")
	)
	(segment
		(start 77.089 25.851002)
		(end 77.051002 25.813004)
		(width 0.12065)
		(layer "In3.Cu")
		(net "DDR0_32A_CB7")
	)
	(segment
		(start 69.6976 23.2664)
		(end 69.6976 26.797)
		(width 0.12065)
		(layer "In3.Cu")
		(net "DDR0_32A_CB7")
	)
	(segment
		(start 70.8152 27.9146)
		(end 76.96835 27.9146)
		(width 0.12065)
		(layer "In3.Cu")
		(net "DDR0_32A_CB7")
	)
	(segment
		(start 77.089 27.79395)
		(end 77.089 25.851002)
		(width 0.12065)
		(layer "In3.Cu")
		(net "DDR0_32A_CB7")
	)
	(segment
		(start 69.2404 22.8092)
		(end 69.6976 23.2664)
		(width 0.12065)
		(layer "In3.Cu")
		(net "DDR0_32A_CB7")
	)
	(segment
		(start 76.96835 27.9146)
		(end 77.089 27.79395)
		(width 0.12065)
		(layer "In3.Cu")
		(net "DDR0_32A_CB7")
	)
	(segment
		(start 69.6976 26.797)
		(end 70.8152 27.9146)
		(width 0.12065)
		(layer "In3.Cu")
		(net "DDR0_32A_CB7")
	)
	(segment
		(start 69.119725 19.541998)
		(end 69.2404 19.662673)
		(width 0.12065)
		(layer "In3.Cu")
		(net "DDR0_32A_CB7")
	)
	(segment
		(start 70.736993 17.542002)
		(end 70.236994 18.042001)
		(width 0.13208)
		(layer "F.Cu")
		(net "DDR0_32A_CB6")
	)
	(via
		(at 70.736993 17.542002)
		(size 0.4826)
		(drill 0.20574)
		(layers "F.Cu" "B.Cu")
		(net "DDR0_32A_CB6")
	)
	(segment
		(start 76.651002 25.413005)
		(end 76.251003 25.013006)
		(width 0.14732)
		(layer "B.Cu")
		(net "DDR0_32A_CB6")
	)
	(segment
		(start 71.755 20.2184)
		(end 71.755 18.0848)
		(width 0.12065)
		(layer "In3.Cu")
		(net "DDR0_32A_CB6")
	)
	(segment
		(start 78.5368 23.53945)
		(end 78.5368 20.5994)
		(width 0.12065)
		(layer "In3.Cu")
		(net "DDR0_32A_CB6")
	)
	(segment
		(start 77.4954 24.4856)
		(end 77.62273 24.61293)
		(width 0.12065)
		(layer "In3.Cu")
		(net "DDR0_32A_CB6")
	)
	(segment
		(start 78.5368 20.5994)
		(end 78.359 20.4216)
		(width 0.12065)
		(layer "In3.Cu")
		(net "DDR0_32A_CB6")
	)
	(segment
		(start 78.2066 24.4856)
		(end 78.2066 23.86965)
		(width 0.12065)
		(layer "In3.Cu")
		(net "DDR0_32A_CB6")
	)
	(segment
		(start 77.4954 23.8506)
		(end 77.4954 24.4856)
		(width 0.12065)
		(layer "In3.Cu")
		(net "DDR0_32A_CB6")
	)
	(segment
		(start 76.251003 25.013006)
		(end 76.651079 24.61293)
		(width 0.12065)
		(layer "In3.Cu")
		(net "DDR0_32A_CB6")
	)
	(segment
		(start 71.212202 17.542002)
		(end 70.736993 17.542002)
		(width 0.12065)
		(layer "In3.Cu")
		(net "DDR0_32A_CB6")
	)
	(segment
		(start 71.9582 20.4216)
		(end 71.755 20.2184)
		(width 0.12065)
		(layer "In3.Cu")
		(net "DDR0_32A_CB6")
	)
	(segment
		(start 78.07927 24.61293)
		(end 78.2066 24.4856)
		(width 0.12065)
		(layer "In3.Cu")
		(net "DDR0_32A_CB6")
	)
	(segment
		(start 71.755 18.0848)
		(end 71.212202 17.542002)
		(width 0.12065)
		(layer "In3.Cu")
		(net "DDR0_32A_CB6")
	)
	(segment
		(start 78.359 20.4216)
		(end 71.9582 20.4216)
		(width 0.12065)
		(layer "In3.Cu")
		(net "DDR0_32A_CB6")
	)
	(segment
		(start 76.651079 23.907521)
		(end 76.8096 23.749)
		(width 0.12065)
		(layer "In3.Cu")
		(net "DDR0_32A_CB6")
	)
	(segment
		(start 76.8096 23.749)
		(end 77.3938 23.749)
		(width 0.12065)
		(layer "In3.Cu")
		(net "DDR0_32A_CB6")
	)
	(segment
		(start 78.2066 23.86965)
		(end 78.5368 23.53945)
		(width 0.12065)
		(layer "In3.Cu")
		(net "DDR0_32A_CB6")
	)
	(segment
		(start 76.651079 24.61293)
		(end 76.651079 23.907521)
		(width 0.12065)
		(layer "In3.Cu")
		(net "DDR0_32A_CB6")
	)
	(segment
		(start 77.3938 23.749)
		(end 77.4954 23.8506)
		(width 0.12065)
		(layer "In3.Cu")
		(net "DDR0_32A_CB6")
	)
	(segment
		(start 77.62273 24.61293)
		(end 78.07927 24.61293)
		(width 0.12065)
		(layer "In3.Cu")
		(net "DDR0_32A_CB6")
	)
	(segment
		(start 66.737001 20.541996)
		(end 66.237002 20.041997)
		(width 0.13208)
		(layer "F.Cu")
		(net "DDR0_32A_CB5")
	)
	(via
		(at 66.737001 20.541996)
		(size 0.4826)
		(drill 0.25654)
		(layers "F.Cu" "B.Cu")
		(net "DDR0_32A_CB5")
	)
	(segment
		(start 75.851004 29.412997)
		(end 75.451005 29.812996)
		(width 0.14732)
		(layer "B.Cu")
		(net "DDR0_32A_CB5")
	)
	(segment
		(start 68.23075 23.9268)
		(end 68.3514 24.04745)
		(width 0.12065)
		(layer "In3.Cu")
		(net "DDR0_32A_CB5")
	)
	(segment
		(start 67.441724 23.9268)
		(end 68.23075 23.9268)
		(width 0.12065)
		(layer "In3.Cu")
		(net "DDR0_32A_CB5")
	)
	(segment
		(start 68.23075 25.0444)
		(end 67.441724 25.0444)
		(width 0.12065)
		(layer "In3.Cu")
		(net "DDR0_32A_CB5")
	)
	(segment
		(start 67.321074 23.80615)
		(end 67.441724 23.9268)
		(width 0.12065)
		(layer "In3.Cu")
		(net "DDR0_32A_CB5")
	)
	(segment
		(start 68.3514 24.92375)
		(end 68.23075 25.0444)
		(width 0.12065)
		(layer "In3.Cu")
		(net "DDR0_32A_CB5")
	)
	(segment
		(start 70.3326 28.8036)
		(end 75.2602 28.8036)
		(width 0.12065)
		(layer "In3.Cu")
		(net "DDR0_32A_CB5")
	)
	(segment
		(start 67.150996 20.541996)
		(end 67.321074 20.712074)
		(width 0.12065)
		(layer "In3.Cu")
		(net "DDR0_32A_CB5")
	)
	(segment
		(start 67.441724 25.0444)
		(end 67.321074 25.16505)
		(width 0.12065)
		(layer "In3.Cu")
		(net "DDR0_32A_CB5")
	)
	(segment
		(start 67.321074 25.792074)
		(end 70.3326 28.8036)
		(width 0.12065)
		(layer "In3.Cu")
		(net "DDR0_32A_CB5")
	)
	(segment
		(start 67.321074 25.16505)
		(end 67.321074 25.792074)
		(width 0.12065)
		(layer "In3.Cu")
		(net "DDR0_32A_CB5")
	)
	(segment
		(start 67.321074 20.712074)
		(end 67.321074 23.80615)
		(width 0.12065)
		(layer "In3.Cu")
		(net "DDR0_32A_CB5")
	)
	(segment
		(start 68.3514 24.04745)
		(end 68.3514 24.92375)
		(width 0.12065)
		(layer "In3.Cu")
		(net "DDR0_32A_CB5")
	)
	(segment
		(start 66.737001 20.541996)
		(end 67.150996 20.541996)
		(width 0.12065)
		(layer "In3.Cu")
		(net "DDR0_32A_CB5")
	)
	(segment
		(start 75.451005 28.994405)
		(end 75.451005 29.812996)
		(width 0.12065)
		(layer "In3.Cu")
		(net "DDR0_32A_CB5")
	)
	(segment
		(start 75.2602 28.8036)
		(end 75.451005 28.994405)
		(width 0.12065)
		(layer "In3.Cu")
		(net "DDR0_32A_CB5")
	)
	(segment
		(start 65.737003 19.541998)
		(end 65.237004 19.041999)
		(width 0.13208)
		(layer "F.Cu")
		(net "DDR0_32A_CB4")
	)
	(via
		(at 65.737003 19.541998)
		(size 0.4826)
		(drill 0.25654)
		(layers "F.Cu" "B.Cu")
		(net "DDR0_32A_CB4")
	)
	(segment
		(start 75.851004 30.212995)
		(end 75.451005 30.612994)
		(width 0.14732)
		(layer "B.Cu")
		(net "DDR0_32A_CB4")
	)
	(segment
		(start 75.051082 29.635882)
		(end 75.051082 30.213071)
		(width 0.12065)
		(layer "In3.Cu")
		(net "DDR0_32A_CB4")
	)
	(segment
		(start 66.294 19.939)
		(end 66.294 25.3238)
		(width 0.12065)
		(layer "In3.Cu")
		(net "DDR0_32A_CB4")
	)
	(segment
		(start 66.294 25.3238)
		(end 70.0786 29.1084)
		(width 0.12065)
		(layer "In3.Cu")
		(net "DDR0_32A_CB4")
	)
	(segment
		(start 74.5236 29.1084)
		(end 75.051082 29.635882)
		(width 0.12065)
		(layer "In3.Cu")
		(net "DDR0_32A_CB4")
	)
	(segment
		(start 75.051082 30.213071)
		(end 75.451005 30.612994)
		(width 0.12065)
		(layer "In3.Cu")
		(net "DDR0_32A_CB4")
	)
	(segment
		(start 65.896998 19.541998)
		(end 66.294 19.939)
		(width 0.12065)
		(layer "In3.Cu")
		(net "DDR0_32A_CB4")
	)
	(segment
		(start 70.0786 29.1084)
		(end 74.5236 29.1084)
		(width 0.12065)
		(layer "In3.Cu")
		(net "DDR0_32A_CB4")
	)
	(segment
		(start 65.737003 19.541998)
		(end 65.896998 19.541998)
		(width 0.12065)
		(layer "In3.Cu")
		(net "DDR0_32A_CB4")
	)
	(segment
		(start 66.737001 19.541998)
		(end 66.237002 19.041999)
		(width 0.13208)
		(layer "F.Cu")
		(net "DDR0_32A_CB3")
	)
	(via
		(at 66.737001 19.541998)
		(size 0.4826)
		(drill 0.25654)
		(layers "F.Cu" "B.Cu")
		(net "DDR0_32A_CB3")
	)
	(segment
		(start 77.451001 30.212995)
		(end 77.051002 30.612994)
		(width 0.14732)
		(layer "B.Cu")
		(net "DDR0_32A_CB3")
	)
	(segment
		(start 70.5358 28.4988)
		(end 75.5396 28.4988)
		(width 0.12065)
		(layer "In3.Cu")
		(net "DDR0_32A_CB3")
	)
	(segment
		(start 75.5396 28.4988)
		(end 76.650926 29.610126)
		(width 0.12065)
		(layer "In3.Cu")
		(net "DDR0_32A_CB3")
	)
	(segment
		(start 68.152924 20.957921)
		(end 68.152924 22.813924)
		(width 0.12065)
		(layer "In3.Cu")
		(net "DDR0_32A_CB3")
	)
	(segment
		(start 68.152924 22.813924)
		(end 69.140222 23.801222)
		(width 0.12065)
		(layer "In3.Cu")
		(net "DDR0_32A_CB3")
	)
	(segment
		(start 69.140222 27.103222)
		(end 70.5358 28.4988)
		(width 0.12065)
		(layer "In3.Cu")
		(net "DDR0_32A_CB3")
	)
	(segment
		(start 76.650926 30.212919)
		(end 77.051002 30.612994)
		(width 0.12065)
		(layer "In3.Cu")
		(net "DDR0_32A_CB3")
	)
	(segment
		(start 76.650926 29.610126)
		(end 76.650926 30.212919)
		(width 0.12065)
		(layer "In3.Cu")
		(net "DDR0_32A_CB3")
	)
	(segment
		(start 69.140222 23.801222)
		(end 69.140222 27.103222)
		(width 0.12065)
		(layer "In3.Cu")
		(net "DDR0_32A_CB3")
	)
	(segment
		(start 66.737001 19.541998)
		(end 68.152924 20.957921)
		(width 0.12065)
		(layer "In3.Cu")
		(net "DDR0_32A_CB3")
	)
	(segment
		(start 67.736999 17.542002)
		(end 67.237 18.042001)
		(width 0.13208)
		(layer "F.Cu")
		(net "DDR0_32A_CB2")
	)
	(via
		(at 67.736999 17.542002)
		(size 0.4826)
		(drill 0.20574)
		(layers "F.Cu" "B.Cu")
		(net "DDR0_32A_CB2")
	)
	(segment
		(start 75.051006 26.213003)
		(end 74.651006 25.813004)
		(width 0.14732)
		(layer "B.Cu")
		(net "DDR0_32A_CB2")
	)
	(segment
		(start 75.3618 22.9362)
		(end 75.7428 22.9362)
		(width 0.12065)
		(layer "In3.Cu")
		(net "DDR0_32A_CB2")
	)
	(segment
		(start 71.374 21.209)
		(end 71.149616 20.984616)
		(width 0.12065)
		(layer "In3.Cu")
		(net "DDR0_32A_CB2")
	)
	(segment
		(start 75.051082 23.246918)
		(end 75.3618 22.9362)
		(width 0.12065)
		(layer "In3.Cu")
		(net "DDR0_32A_CB2")
	)
	(segment
		(start 75.051082 25.412929)
		(end 75.051082 23.246918)
		(width 0.12065)
		(layer "In3.Cu")
		(net "DDR0_32A_CB2")
	)
	(segment
		(start 74.651006 25.813004)
		(end 75.051082 25.412929)
		(width 0.12065)
		(layer "In3.Cu")
		(net "DDR0_32A_CB2")
	)
	(segment
		(start 76.7334 21.6154)
		(end 76.327 21.209)
		(width 0.12065)
		(layer "In3.Cu")
		(net "DDR0_32A_CB2")
	)
	(segment
		(start 76.7334 21.9456)
		(end 76.7334 21.6154)
		(width 0.12065)
		(layer "In3.Cu")
		(net "DDR0_32A_CB2")
	)
	(segment
		(start 71.028941 18.796)
		(end 67.945 18.796)
		(width 0.12065)
		(layer "In3.Cu")
		(net "DDR0_32A_CB2")
	)
	(segment
		(start 76.327 21.209)
		(end 71.374 21.209)
		(width 0.12065)
		(layer "In3.Cu")
		(net "DDR0_32A_CB2")
	)
	(segment
		(start 67.736999 18.587999)
		(end 67.736999 17.542002)
		(width 0.12065)
		(layer "In3.Cu")
		(net "DDR0_32A_CB2")
	)
	(segment
		(start 67.945 18.796)
		(end 67.736999 18.587999)
		(width 0.12065)
		(layer "In3.Cu")
		(net "DDR0_32A_CB2")
	)
	(segment
		(start 75.7428 22.9362)
		(end 76.7334 21.9456)
		(width 0.12065)
		(layer "In3.Cu")
		(net "DDR0_32A_CB2")
	)
	(segment
		(start 71.149616 18.916675)
		(end 71.028941 18.796)
		(width 0.12065)
		(layer "In3.Cu")
		(net "DDR0_32A_CB2")
	)
	(segment
		(start 71.149616 20.984616)
		(end 71.149616 18.916675)
		(width 0.12065)
		(layer "In3.Cu")
		(net "DDR0_32A_CB2")
	)
	(segment
		(start 67.736999 19.541998)
		(end 67.237 19.041999)
		(width 0.13208)
		(layer "F.Cu")
		(net "DDR0_32A_CB1")
	)
	(via
		(at 67.736999 19.541998)
		(size 0.4826)
		(drill 0.25654)
		(layers "F.Cu" "B.Cu")
		(net "DDR0_32A_CB1")
	)
	(segment
		(start 77.451001 29.412997)
		(end 77.051002 29.812996)
		(width 0.14732)
		(layer "B.Cu")
		(net "DDR0_32A_CB1")
	)
	(segment
		(start 70.6882 28.194)
		(end 76.8858 28.194)
		(width 0.12065)
		(layer "In3.Cu")
		(net "DDR0_32A_CB1")
	)
	(segment
		(start 69.4182 23.5204)
		(end 69.4182 26.924)
		(width 0.12065)
		(layer "In3.Cu")
		(net "DDR0_32A_CB1")
	)
	(segment
		(start 67.736999 19.541998)
		(end 67.736999 19.603999)
		(width 0.12065)
		(layer "In3.Cu")
		(net "DDR0_32A_CB1")
	)
	(segment
		(start 77.051002 28.359202)
		(end 77.051002 29.812996)
		(width 0.12065)
		(layer "In3.Cu")
		(net "DDR0_32A_CB1")
	)
	(segment
		(start 68.453 22.5552)
		(end 69.4182 23.5204)
		(width 0.12065)
		(layer "In3.Cu")
		(net "DDR0_32A_CB1")
	)
	(segment
		(start 67.736999 19.603999)
		(end 68.453 20.32)
		(width 0.12065)
		(layer "In3.Cu")
		(net "DDR0_32A_CB1")
	)
	(segment
		(start 69.4182 26.924)
		(end 70.6882 28.194)
		(width 0.12065)
		(layer "In3.Cu")
		(net "DDR0_32A_CB1")
	)
	(segment
		(start 68.453 20.32)
		(end 68.453 22.5552)
		(width 0.12065)
		(layer "In3.Cu")
		(net "DDR0_32A_CB1")
	)
	(segment
		(start 76.8858 28.194)
		(end 77.051002 28.359202)
		(width 0.12065)
		(layer "In3.Cu")
		(net "DDR0_32A_CB1")
	)
	(segment
		(start 69.736995 17.542002)
		(end 69.236996 18.042001)
		(width 0.13208)
		(layer "F.Cu")
		(net "DDR0_32A_CB0")
	)
	(via
		(at 69.736995 17.542002)
		(size 0.4826)
		(drill 0.25654)
		(layers "F.Cu" "B.Cu")
		(net "DDR0_32A_CB0")
	)
	(segment
		(start 75.851004 25.413005)
		(end 75.451005 25.013006)
		(width 0.14732)
		(layer "B.Cu")
		(net "DDR0_32A_CB0")
	)
	(segment
		(start 76.0222 23.3426)
		(end 75.850928 23.513872)
		(width 0.12065)
		(layer "In3.Cu")
		(net "DDR0_32A_CB0")
	)
	(segment
		(start 71.2978 18.288)
		(end 71.501 18.4912)
		(width 0.12065)
		(layer "In3.Cu")
		(net "DDR0_32A_CB0")
	)
	(segment
		(start 78.1304 21.0058)
		(end 78.1304 23.2156)
		(width 0.12065)
		(layer "In3.Cu")
		(net "DDR0_32A_CB0")
	)
	(segment
		(start 77.9526 20.828)
		(end 78.1304 21.0058)
		(width 0.12065)
		(layer "In3.Cu")
		(net "DDR0_32A_CB0")
	)
	(segment
		(start 69.736995 18.047995)
		(end 69.977 18.288)
		(width 0.12065)
		(layer "In3.Cu")
		(net "DDR0_32A_CB0")
	)
	(segment
		(start 78.0034 23.3426)
		(end 76.0222 23.3426)
		(width 0.12065)
		(layer "In3.Cu")
		(net "DDR0_32A_CB0")
	)
	(segment
		(start 71.501 18.4912)
		(end 71.501 20.701)
		(width 0.12065)
		(layer "In3.Cu")
		(net "DDR0_32A_CB0")
	)
	(segment
		(start 71.501 20.701)
		(end 71.628 20.828)
		(width 0.12065)
		(layer "In3.Cu")
		(net "DDR0_32A_CB0")
	)
	(segment
		(start 78.1304 23.2156)
		(end 78.0034 23.3426)
		(width 0.12065)
		(layer "In3.Cu")
		(net "DDR0_32A_CB0")
	)
	(segment
		(start 71.628 20.828)
		(end 77.9526 20.828)
		(width 0.12065)
		(layer "In3.Cu")
		(net "DDR0_32A_CB0")
	)
	(segment
		(start 75.850928 24.613083)
		(end 75.451005 25.013006)
		(width 0.12065)
		(layer "In3.Cu")
		(net "DDR0_32A_CB0")
	)
	(segment
		(start 69.736995 17.542002)
		(end 69.736995 18.047995)
		(width 0.12065)
		(layer "In3.Cu")
		(net "DDR0_32A_CB0")
	)
	(segment
		(start 69.977 18.288)
		(end 71.2978 18.288)
		(width 0.12065)
		(layer "In3.Cu")
		(net "DDR0_32A_CB0")
	)
	(segment
		(start 75.850928 23.513872)
		(end 75.850928 24.613083)
		(width 0.12065)
		(layer "In3.Cu")
		(net "DDR0_32A_CB0")
	)
	(segment
		(start 62.737009 12.542012)
		(end 62.23701 13.042011)
		(width 0.233528)
		(layer "F.Cu")
		(net "DDR0_32A_CAS_L")
	)
	(segment
		(start 79.248 26.5049)
		(end 79.450997 26.301903)
		(width 0.14732)
		(layer "F.Cu")
		(net "DDR0_32A_CAS_L")
	)
	(segment
		(start 79.450997 26.301903)
		(end 79.450997 25.813004)
		(width 0.14732)
		(layer "F.Cu")
		(net "DDR0_32A_CAS_L")
	)
	(via
		(at 62.737009 12.542012)
		(size 0.4826)
		(drill 0.20574)
		(layers "F.Cu" "B.Cu")
		(net "DDR0_32A_CAS_L")
	)
	(segment
		(start 79.050998 26.213003)
		(end 79.450997 25.813004)
		(width 0.14732)
		(layer "B.Cu")
		(net "DDR0_32A_CAS_L")
	)
	(segment
		(start 79.050998 3.099003)
		(end 79.450997 2.699004)
		(width 0.14732)
		(layer "B.Cu")
		(net "DDR0_32A_CAS_L")
	)
	(segment
		(start 79.050998 14.656003)
		(end 79.450997 14.256004)
		(width 0.14732)
		(layer "B.Cu")
		(net "DDR0_32A_CAS_L")
	)
	(segment
		(start 64.174268 8.723122)
		(end 64.174268 5.360873)
		(width 0.188697)
		(layer "In2.Cu")
		(net "DDR0_32A_CAS_L")
	)
	(segment
		(start 79.375 0.508)
		(end 79.5528 0.6858)
		(width 0.188697)
		(layer "In2.Cu")
		(net "DDR0_32A_CAS_L")
	)
	(segment
		(start 80.628134 0.916127)
		(end 80.628134 1.718513)
		(width 0.12065)
		(layer "In2.Cu")
		(net "DDR0_32A_CAS_L")
	)
	(segment
		(start 64.168807 8.729193)
		(end 64.168807 8.728583)
		(width 0.188697)
		(layer "In2.Cu")
		(net "DDR0_32A_CAS_L")
	)
	(segment
		(start 63.627 3.270402)
		(end 64.174268 2.723134)
		(width 0.188697)
		(layer "In2.Cu")
		(net "DDR0_32A_CAS_L")
	)
	(segment
		(start 66.909036 -1.6764)
		(end 66.988944 -1.6764)
		(width 0.188697)
		(layer "In2.Cu")
		(net "DDR0_32A_CAS_L")
	)
	(segment
		(start 66.988944 -1.6764)
		(end 66.999841 -1.687297)
		(width 0.188697)
		(layer "In2.Cu")
		(net "DDR0_32A_CAS_L")
	)
	(segment
		(start 63.627 4.699)
		(end 63.627 3.270402)
		(width 0.188697)
		(layer "In2.Cu")
		(net "DDR0_32A_CAS_L")
	)
	(segment
		(start 79.375 -1.4986)
		(end 79.375 0.508)
		(width 0.188697)
		(layer "In2.Cu")
		(net "DDR0_32A_CAS_L")
	)
	(segment
		(start 63.591745 9.041994)
		(end 63.856006 9.041994)
		(width 0.188697)
		(layer "In2.Cu")
		(net "DDR0_32A_CAS_L")
	)
	(segment
		(start 80.645279 1.735658)
		(end 80.645279 2.062353)
		(width 0.12065)
		(layer "In2.Cu")
		(net "DDR0_32A_CAS_L")
	)
	(segment
		(start 63.237008 12.042013)
		(end 63.237008 9.39673)
		(width 0.188697)
		(layer "In2.Cu")
		(net "DDR0_32A_CAS_L")
	)
	(segment
		(start 66.999841 -1.687297)
		(end 79.186303 -1.687297)
		(width 0.188697)
		(layer "In2.Cu")
		(net "DDR0_32A_CAS_L")
	)
	(segment
		(start 79.5528 0.6858)
		(end 79.8576 0.6858)
		(width 0.188697)
		(layer "In2.Cu")
		(net "DDR0_32A_CAS_L")
	)
	(segment
		(start 81.0514 -1.213764)
		(end 81.0514 0.414934)
		(width 0.188697)
		(layer "In2.Cu")
		(net "DDR0_32A_CAS_L")
	)
	(segment
		(start 80.588764 -1.6764)
		(end 81.0514 -1.213764)
		(width 0.188697)
		(layer "In2.Cu")
		(net "DDR0_32A_CAS_L")
	)
	(segment
		(start 64.168807 5.240807)
		(end 63.627 4.699)
		(width 0.188697)
		(layer "In2.Cu")
		(net "DDR0_32A_CAS_L")
	)
	(segment
		(start 80.0354 -1.5494)
		(end 80.1624 -1.6764)
		(width 0.188697)
		(layer "In2.Cu")
		(net "DDR0_32A_CAS_L")
	)
	(segment
		(start 81.0514 0.414934)
		(end 80.628134 0.8382)
		(width 0.188697)
		(layer "In2.Cu")
		(net "DDR0_32A_CAS_L")
	)
	(segment
		(start 80.414317 2.29329)
		(end 80.402887 2.30472)
		(width 0.12065)
		(layer "In2.Cu")
		(net "DDR0_32A_CAS_L")
	)
	(segment
		(start 79.8576 0.6858)
		(end 80.0354 0.508)
		(width 0.188697)
		(layer "In2.Cu")
		(net "DDR0_32A_CAS_L")
	)
	(segment
		(start 80.628134 1.718513)
		(end 80.645279 1.735658)
		(width 0.12065)
		(layer "In2.Cu")
		(net "DDR0_32A_CAS_L")
	)
	(segment
		(start 80.645279 2.062353)
		(end 80.414343 2.29329)
		(width 0.12065)
		(layer "In2.Cu")
		(net "DDR0_32A_CAS_L")
	)
	(segment
		(start 64.174268 5.360873)
		(end 64.168807 5.355412)
		(width 0.188697)
		(layer "In2.Cu")
		(net "DDR0_32A_CAS_L")
	)
	(segment
		(start 64.174268 2.667635)
		(end 64.174903 2.667)
		(width 0.188697)
		(layer "In2.Cu")
		(net "DDR0_32A_CAS_L")
	)
	(segment
		(start 80.402887 2.30472)
		(end 79.845281 2.30472)
		(width 0.12065)
		(layer "In2.Cu")
		(net "DDR0_32A_CAS_L")
	)
	(segment
		(start 64.168807 5.355412)
		(end 64.168807 5.240807)
		(width 0.188697)
		(layer "In2.Cu")
		(net "DDR0_32A_CAS_L")
	)
	(segment
		(start 64.174268 2.723134)
		(end 64.174268 2.667635)
		(width 0.188697)
		(layer "In2.Cu")
		(net "DDR0_32A_CAS_L")
	)
	(segment
		(start 80.628134 0.8382)
		(end 80.628134 0.916127)
		(width 0.188697)
		(layer "In2.Cu")
		(net "DDR0_32A_CAS_L")
	)
	(segment
		(start 63.237008 9.39673)
		(end 63.591745 9.041994)
		(width 0.188697)
		(layer "In2.Cu")
		(net "DDR0_32A_CAS_L")
	)
	(segment
		(start 64.174903 1.057732)
		(end 66.909036 -1.6764)
		(width 0.188697)
		(layer "In2.Cu")
		(net "DDR0_32A_CAS_L")
	)
	(segment
		(start 64.174903 2.667)
		(end 64.174903 1.057732)
		(width 0.188697)
		(layer "In2.Cu")
		(net "DDR0_32A_CAS_L")
	)
	(segment
		(start 80.1624 -1.6764)
		(end 80.588764 -1.6764)
		(width 0.188697)
		(layer "In2.Cu")
		(net "DDR0_32A_CAS_L")
	)
	(segment
		(start 79.186303 -1.687297)
		(end 79.375 -1.4986)
		(width 0.188697)
		(layer "In2.Cu")
		(net "DDR0_32A_CAS_L")
	)
	(segment
		(start 80.414343 2.29329)
		(end 80.414317 2.29329)
		(width 0.12065)
		(layer "In2.Cu")
		(net "DDR0_32A_CAS_L")
	)
	(segment
		(start 64.168807 8.728583)
		(end 64.174268 8.723122)
		(width 0.188697)
		(layer "In2.Cu")
		(net "DDR0_32A_CAS_L")
	)
	(segment
		(start 80.0354 0.508)
		(end 80.0354 -1.5494)
		(width 0.188697)
		(layer "In2.Cu")
		(net "DDR0_32A_CAS_L")
	)
	(segment
		(start 63.856006 9.041994)
		(end 64.168807 8.729193)
		(width 0.188697)
		(layer "In2.Cu")
		(net "DDR0_32A_CAS_L")
	)
	(segment
		(start 79.845281 2.30472)
		(end 79.450997 2.699004)
		(width 0.12065)
		(layer "In2.Cu")
		(net "DDR0_32A_CAS_L")
	)
	(segment
		(start 62.737009 12.542012)
		(end 63.237008 12.042013)
		(width 0.188697)
		(layer "In2.Cu")
		(net "DDR0_32A_CAS_L")
	)
	(segment
		(start 79.450997 14.256004)
		(end 79.056713 14.650288)
		(width 0.12065)
		(layer "In3.Cu")
		(net "DDR0_32A_CAS_L")
	)
	(segment
		(start 79.056713 13.86172)
		(end 79.450997 14.256004)
		(width 0.12065)
		(layer "In3.Cu")
		(net "DDR0_32A_CAS_L")
	)
	(segment
		(start 79.056713 14.650288)
		(end 79.056713 25.41872)
		(width 0.12065)
		(layer "In3.Cu")
		(net "DDR0_32A_CAS_L")
	)
	(segment
		(start 79.056713 25.41872)
		(end 79.450997 25.813004)
		(width 0.12065)
		(layer "In3.Cu")
		(net "DDR0_32A_CAS_L")
	)
	(segment
		(start 79.450997 2.699004)
		(end 79.056713 3.093288)
		(width 0.12065)
		(layer "In3.Cu")
		(net "DDR0_32A_CAS_L")
	)
	(segment
		(start 79.056713 3.093288)
		(end 79.056713 13.86172)
		(width 0.12065)
		(layer "In3.Cu")
		(net "DDR0_32A_CAS_L")
	)
	(segment
		(start 65.737003 10.541991)
		(end 65.237004 11.04199)
		(width 0.233528)
		(layer "F.Cu")
		(net "DDR0_32A_BA2")
	)
	(segment
		(start 81.026 26.5049)
		(end 81.050994 26.479906)
		(width 0.14732)
		(layer "F.Cu")
		(net "DDR0_32A_BA2")
	)
	(segment
		(start 81.050994 26.479906)
		(end 81.050994 25.813004)
		(width 0.14732)
		(layer "F.Cu")
		(net "DDR0_32A_BA2")
	)
	(via
		(at 65.737003 10.541991)
		(size 0.4826)
		(drill 0.25654)
		(layers "F.Cu" "B.Cu")
		(net "DDR0_32A_BA2")
	)
	(segment
		(start 80.650994 14.656003)
		(end 81.050994 14.256004)
		(width 0.14732)
		(layer "B.Cu")
		(net "DDR0_32A_BA2")
	)
	(segment
		(start 80.650994 3.099003)
		(end 81.050994 2.699004)
		(width 0.14732)
		(layer "B.Cu")
		(net "DDR0_32A_BA2")
	)
	(segment
		(start 80.650994 26.213003)
		(end 81.050994 25.813004)
		(width 0.14732)
		(layer "B.Cu")
		(net "DDR0_32A_BA2")
	)
	(segment
		(start 80.656709 13.86172)
		(end 80.656709 3.093288)
		(width 0.12065)
		(layer "In3.Cu")
		(net "DDR0_32A_BA2")
	)
	(segment
		(start 81.050994 14.256004)
		(end 80.656709 13.86172)
		(width 0.12065)
		(layer "In3.Cu")
		(net "DDR0_32A_BA2")
	)
	(segment
		(start 81.050994 25.813004)
		(end 80.656709 25.41872)
		(width 0.12065)
		(layer "In3.Cu")
		(net "DDR0_32A_BA2")
	)
	(segment
		(start 80.656709 25.41872)
		(end 80.656709 14.650288)
		(width 0.12065)
		(layer "In3.Cu")
		(net "DDR0_32A_BA2")
	)
	(segment
		(start 80.656709 14.650288)
		(end 81.050994 14.256004)
		(width 0.12065)
		(layer "In3.Cu")
		(net "DDR0_32A_BA2")
	)
	(segment
		(start 80.656709 3.093288)
		(end 81.050994 2.699004)
		(width 0.12065)
		(layer "In3.Cu")
		(net "DDR0_32A_BA2")
	)
	(segment
		(start 66.802 6.09539)
		(end 67.174262 5.723128)
		(width 0.188697)
		(layer "In6.Cu")
		(net "DDR0_32A_BA2")
	)
	(segment
		(start 81.699278 -0.127)
		(end 81.445278 0.127)
		(width 0.188697)
		(layer "In6.Cu")
		(net "DDR0_32A_BA2")
	)
	(segment
		(start 66.7512 0.658622)
		(end 66.422778 0.658622)
		(width 0.188697)
		(layer "In6.Cu")
		(net "DDR0_32A_BA2")
	)
	(segment
		(start 65.737003 10.860303)
		(end 65.9257 11.049)
		(width 0.188697)
		(layer "In6.Cu")
		(net "DDR0_32A_BA2")
	)
	(segment
		(start 66.292222 0.789178)
		(end 66.292222 1.982978)
		(width 0.188697)
		(layer "In6.Cu")
		(net "DDR0_32A_BA2")
	)
	(segment
		(start 66.292222 1.982978)
		(end 66.167 2.1082)
		(width 0.188697)
		(layer "In6.Cu")
		(net "DDR0_32A_BA2")
	)
	(segment
		(start 65.9257 11.049)
		(end 66.613303 11.049)
		(width 0.188697)
		(layer "In6.Cu")
		(net "DDR0_32A_BA2")
	)
	(segment
		(start 67.174262 10.723118)
		(end 67.174262 9.360865)
		(width 0.188697)
		(layer "In6.Cu")
		(net "DDR0_32A_BA2")
	)
	(segment
		(start 81.445278 0.127)
		(end 81.445278 0.800278)
		(width 0.188697)
		(layer "In6.Cu")
		(net "DDR0_32A_BA2")
	)
	(segment
		(start 81.445278 0.800278)
		(end 81.445278 2.062353)
		(width 0.12065)
		(layer "In6.Cu")
		(net "DDR0_32A_BA2")
	)
	(segment
		(start 81.445278 2.062353)
		(end 81.050994 2.456637)
		(width 0.12065)
		(layer "In6.Cu")
		(net "DDR0_32A_BA2")
	)
	(segment
		(start 65.872995 -0.827303)
		(end 82.992697 -0.827303)
		(width 0.188697)
		(layer "In6.Cu")
		(net "DDR0_32A_BA2")
	)
	(segment
		(start 83.178574 -0.374574)
		(end 82.931 -0.127)
		(width 0.188697)
		(layer "In6.Cu")
		(net "DDR0_32A_BA2")
	)
	(segment
		(start 82.931 -0.127)
		(end 81.699278 -0.127)
		(width 0.188697)
		(layer "In6.Cu")
		(net "DDR0_32A_BA2")
	)
	(segment
		(start 66.918129 10.979252)
		(end 67.174262 10.723118)
		(width 0.188697)
		(layer "In6.Cu")
		(net "DDR0_32A_BA2")
	)
	(segment
		(start 66.167 2.921)
		(end 66.8782 2.2098)
		(width 0.188697)
		(layer "In6.Cu")
		(net "DDR0_32A_BA2")
	)
	(segment
		(start 67.174262 9.360865)
		(end 66.802 8.988603)
		(width 0.188697)
		(layer "In6.Cu")
		(net "DDR0_32A_BA2")
	)
	(segment
		(start 65.684298 -0.427126)
		(end 65.684298 -0.638607)
		(width 0.188697)
		(layer "In6.Cu")
		(net "DDR0_32A_BA2")
	)
	(segment
		(start 66.802 6.988607)
		(end 66.802 6.09539)
		(width 0.188697)
		(layer "In6.Cu")
		(net "DDR0_32A_BA2")
	)
	(segment
		(start 67.174262 7.723124)
		(end 67.174262 7.360869)
		(width 0.188697)
		(layer "In6.Cu")
		(net "DDR0_32A_BA2")
	)
	(segment
		(start 66.613303 11.049)
		(end 66.683052 10.979252)
		(width 0.188697)
		(layer "In6.Cu")
		(net "DDR0_32A_BA2")
	)
	(segment
		(start 65.673503 -0.416331)
		(end 65.684298 -0.427126)
		(width 0.188697)
		(layer "In6.Cu")
		(net "DDR0_32A_BA2")
	)
	(segment
		(start 65.6844 0.234036)
		(end 65.684298 0.233934)
		(width 0.188697)
		(layer "In6.Cu")
		(net "DDR0_32A_BA2")
	)
	(segment
		(start 66.8782 0.785622)
		(end 66.7512 0.658622)
		(width 0.188697)
		(layer "In6.Cu")
		(net "DDR0_32A_BA2")
	)
	(segment
		(start 65.6844 1.930375)
		(end 65.6844 0.234036)
		(width 0.188697)
		(layer "In6.Cu")
		(net "DDR0_32A_BA2")
	)
	(segment
		(start 66.167 2.1082)
		(end 65.862225 2.1082)
		(width 0.188697)
		(layer "In6.Cu")
		(net "DDR0_32A_BA2")
	)
	(segment
		(start 65.684298 0.170586)
		(end 65.673503 0.159791)
		(width 0.188697)
		(layer "In6.Cu")
		(net "DDR0_32A_BA2")
	)
	(segment
		(start 82.992697 -0.827303)
		(end 83.178574 -0.641426)
		(width 0.188697)
		(layer "In6.Cu")
		(net "DDR0_32A_BA2")
	)
	(segment
		(start 67.174262 7.360869)
		(end 66.802 6.988607)
		(width 0.188697)
		(layer "In6.Cu")
		(net "DDR0_32A_BA2")
	)
	(segment
		(start 66.8782 2.2098)
		(end 66.8782 0.785622)
		(width 0.188697)
		(layer "In6.Cu")
		(net "DDR0_32A_BA2")
	)
	(segment
		(start 67.174262 5.723128)
		(end 67.174262 4.360875)
		(width 0.188697)
		(layer "In6.Cu")
		(net "DDR0_32A_BA2")
	)
	(segment
		(start 66.167 3.353613)
		(end 66.167 2.921)
		(width 0.188697)
		(layer "In6.Cu")
		(net "DDR0_32A_BA2")
	)
	(segment
		(start 83.178574 -0.641426)
		(end 83.178574 -0.374574)
		(width 0.188697)
		(layer "In6.Cu")
		(net "DDR0_32A_BA2")
	)
	(segment
		(start 66.802 8.095386)
		(end 67.174262 7.723124)
		(width 0.188697)
		(layer "In6.Cu")
		(net "DDR0_32A_BA2")
	)
	(segment
		(start 65.862225 2.1082)
		(end 65.6844 1.930375)
		(width 0.188697)
		(layer "In6.Cu")
		(net "DDR0_32A_BA2")
	)
	(segment
		(start 67.174262 4.360875)
		(end 66.167 3.353613)
		(width 0.188697)
		(layer "In6.Cu")
		(net "DDR0_32A_BA2")
	)
	(segment
		(start 66.422778 0.658622)
		(end 66.292222 0.789178)
		(width 0.188697)
		(layer "In6.Cu")
		(net "DDR0_32A_BA2")
	)
	(segment
		(start 65.673503 0.159791)
		(end 65.673503 -0.416331)
		(width 0.188697)
		(layer "In6.Cu")
		(net "DDR0_32A_BA2")
	)
	(segment
		(start 66.802 8.988603)
		(end 66.802 8.095386)
		(width 0.188697)
		(layer "In6.Cu")
		(net "DDR0_32A_BA2")
	)
	(segment
		(start 65.684298 0.233934)
		(end 65.684298 0.170586)
		(width 0.188697)
		(layer "In6.Cu")
		(net "DDR0_32A_BA2")
	)
	(segment
		(start 81.050994 2.456637)
		(end 81.050994 2.699004)
		(width 0.12065)
		(layer "In6.Cu")
		(net "DDR0_32A_BA2")
	)
	(segment
		(start 65.684298 -0.638607)
		(end 65.872995 -0.827303)
		(width 0.188697)
		(layer "In6.Cu")
		(net "DDR0_32A_BA2")
	)
	(segment
		(start 65.737003 10.541991)
		(end 65.737003 10.860303)
		(width 0.188697)
		(layer "In6.Cu")
		(net "DDR0_32A_BA2")
	)
	(segment
		(start 66.683052 10.979252)
		(end 66.918129 10.979252)
		(width 0.188697)
		(layer "In6.Cu")
		(net "DDR0_32A_BA2")
	)
	(segment
		(start 81.026 29.788002)
		(end 81.850992 30.612994)
		(width 0.14732)
		(layer "F.Cu")
		(net "DDR0_32A_BA1")
	)
	(segment
		(start 65.737003 12.542012)
		(end 65.237004 13.042011)
		(width 0.233528)
		(layer "F.Cu")
		(net "DDR0_32A_BA1")
	)
	(segment
		(start 81.026 29.1211)
		(end 81.026 29.788002)
		(width 0.14732)
		(layer "F.Cu")
		(net "DDR0_32A_BA1")
	)
	(via
		(at 65.737003 12.542012)
		(size 0.4826)
		(drill 0.25654)
		(layers "F.Cu" "B.Cu")
		(net "DDR0_32A_BA1")
	)
	(segment
		(start 81.450993 7.098995)
		(end 81.850992 7.498994)
		(width 0.14732)
		(layer "B.Cu")
		(net "DDR0_32A_BA1")
	)
	(segment
		(start 81.450993 18.655995)
		(end 81.850992 19.055994)
		(width 0.14732)
		(layer "B.Cu")
		(net "DDR0_32A_BA1")
	)
	(segment
		(start 81.450993 30.212995)
		(end 81.850992 30.612994)
		(width 0.14732)
		(layer "B.Cu")
		(net "DDR0_32A_BA1")
	)
	(segment
		(start 82.250915 30.213071)
		(end 82.250915 19.455917)
		(width 0.12065)
		(layer "In2.Cu")
		(net "DDR0_32A_BA1")
	)
	(segment
		(start 81.850992 30.612994)
		(end 82.250915 30.213071)
		(width 0.12065)
		(layer "In2.Cu")
		(net "DDR0_32A_BA1")
	)
	(segment
		(start 81.850992 19.055994)
		(end 82.250915 18.656071)
		(width 0.12065)
		(layer "In2.Cu")
		(net "DDR0_32A_BA1")
	)
	(segment
		(start 82.250915 18.656071)
		(end 82.250915 7.898917)
		(width 0.12065)
		(layer "In2.Cu")
		(net "DDR0_32A_BA1")
	)
	(segment
		(start 82.250915 19.455917)
		(end 81.850992 19.055994)
		(width 0.12065)
		(layer "In2.Cu")
		(net "DDR0_32A_BA1")
	)
	(segment
		(start 82.250915 7.898917)
		(end 81.850992 7.498994)
		(width 0.12065)
		(layer "In2.Cu")
		(net "DDR0_32A_BA1")
	)
	(segment
		(start 82.3976 4.441393)
		(end 82.5246 4.314393)
		(width 0.188697)
		(layer "In7.Cu")
		(net "DDR0_32A_BA1")
	)
	(segment
		(start 68.199 11.8364)
		(end 68.467351 12.104751)
		(width 0.188697)
		(layer "In7.Cu")
		(net "DDR0_32A_BA1")
	)
	(segment
		(start 74.61504 6.04172)
		(end 74.99096 6.04172)
		(width 0.188697)
		(layer "In7.Cu")
		(net "DDR0_32A_BA1")
	)
	(segment
		(start 82.3976 4.978375)
		(end 82.3976 4.441393)
		(width 0.188697)
		(layer "In7.Cu")
		(net "DDR0_32A_BA1")
	)
	(segment
		(start 69.4182 11.04199)
		(end 71.312303 11.04199)
		(width 0.188697)
		(layer "In7.Cu")
		(net "DDR0_32A_BA1")
	)
	(segment
		(start 74.041 5.467706)
		(end 74.61504 6.04172)
		(width 0.188697)
		(layer "In7.Cu")
		(net "DDR0_32A_BA1")
	)
	(segment
		(start 67.237 11.965788)
		(end 67.237 11.248974)
		(width 0.188697)
		(layer "In7.Cu")
		(net "DDR0_32A_BA1")
	)
	(segment
		(start 81.428133 7.076135)
		(end 81.850992 7.498994)
		(width 0.188697)
		(layer "In7.Cu")
		(net "DDR0_32A_BA1")
	)
	(segment
		(start 71.501 9.952228)
		(end 71.5772 9.876028)
		(width 0.188697)
		(layer "In7.Cu")
		(net "DDR0_32A_BA1")
	)
	(segment
		(start 68.972049 12.104751)
		(end 69.2404 11.8364)
		(width 0.188697)
		(layer "In7.Cu")
		(net "DDR0_32A_BA1")
	)
	(segment
		(start 81.673573 6.270676)
		(end 81.422672 6.521577)
		(width 0.188697)
		(layer "In7.Cu")
		(net "DDR0_32A_BA1")
	)
	(segment
		(start 85.5218 4.314393)
		(end 85.6996 4.492193)
		(width 0.188697)
		(layer "In7.Cu")
		(net "DDR0_32A_BA1")
	)
	(segment
		(start 80.54467 6.2484)
		(end 80.79613 6.2484)
		(width 0.188697)
		(layer "In7.Cu")
		(net "DDR0_32A_BA1")
	)
	(segment
		(start 81.7372 5.031715)
		(end 81.915 5.209515)
		(width 0.188697)
		(layer "In7.Cu")
		(net "DDR0_32A_BA1")
	)
	(segment
		(start 78.5114 4.6736)
		(end 78.8416 4.6736)
		(width 0.188697)
		(layer "In7.Cu")
		(net "DDR0_32A_BA1")
	)
	(segment
		(start 65.737003 12.253697)
		(end 65.9257 12.065)
		(width 0.188697)
		(layer "In7.Cu")
		(net "DDR0_32A_BA1")
	)
	(segment
		(start 79.502 5.4864)
		(end 79.629 5.3594)
		(width 0.188697)
		(layer "In7.Cu")
		(net "DDR0_32A_BA1")
	)
	(segment
		(start 71.566303 8.988425)
		(end 71.562697 8.984818)
		(width 0.188697)
		(layer "In7.Cu")
		(net "DDR0_32A_BA1")
	)
	(segment
		(start 79.7814 4.6736)
		(end 80.1624 4.6736)
		(width 0.188697)
		(layer "In7.Cu")
		(net "DDR0_32A_BA1")
	)
	(segment
		(start 81.1784 4.6736)
		(end 81.5848 4.6736)
		(width 0.188697)
		(layer "In7.Cu")
		(net "DDR0_32A_BA1")
	)
	(segment
		(start 84.583321 5.032807)
		(end 84.536128 5.08)
		(width 0.188697)
		(layer "In7.Cu")
		(net "DDR0_32A_BA1")
	)
	(segment
		(start 65.737003 12.542012)
		(end 65.737003 12.253697)
		(width 0.188697)
		(layer "In7.Cu")
		(net "DDR0_32A_BA1")
	)
	(segment
		(start 85.6996 4.492193)
		(end 85.6996 4.754372)
		(width 0.188697)
		(layer "In7.Cu")
		(net "DDR0_32A_BA1")
	)
	(segment
		(start 85.421165 5.032807)
		(end 84.583321 5.032807)
		(width 0.188697)
		(layer "In7.Cu")
		(net "DDR0_32A_BA1")
	)
	(segment
		(start 79.1718 5.4864)
		(end 79.502 5.4864)
		(width 0.188697)
		(layer "In7.Cu")
		(net "DDR0_32A_BA1")
	)
	(segment
		(start 81.422672 6.876415)
		(end 81.428133 6.881876)
		(width 0.188697)
		(layer "In7.Cu")
		(net "DDR0_32A_BA1")
	)
	(segment
		(start 78.359 5.2832)
		(end 78.359 4.826)
		(width 0.188697)
		(layer "In7.Cu")
		(net "DDR0_32A_BA1")
	)
	(segment
		(start 82.871945 5.08)
		(end 81.681269 6.270676)
		(width 0.188697)
		(layer "In7.Cu")
		(net "DDR0_32A_BA1")
	)
	(segment
		(start 69.2404 11.8364)
		(end 69.2404 11.21979)
		(width 0.188697)
		(layer "In7.Cu")
		(net "DDR0_32A_BA1")
	)
	(segment
		(start 67.9958 11.04199)
		(end 68.199 11.24519)
		(width 0.188697)
		(layer "In7.Cu")
		(net "DDR0_32A_BA1")
	)
	(segment
		(start 71.501 10.853293)
		(end 71.501 9.952228)
		(width 0.188697)
		(layer "In7.Cu")
		(net "DDR0_32A_BA1")
	)
	(segment
		(start 82.16646 5.209515)
		(end 82.3976 4.978375)
		(width 0.188697)
		(layer "In7.Cu")
		(net "DDR0_32A_BA1")
	)
	(segment
		(start 75.57168 5.461)
		(end 78.1812 5.461)
		(width 0.188697)
		(layer "In7.Cu")
		(net "DDR0_32A_BA1")
	)
	(segment
		(start 84.536128 5.08)
		(end 82.871945 5.08)
		(width 0.188697)
		(layer "In7.Cu")
		(net "DDR0_32A_BA1")
	)
	(segment
		(start 81.7372 4.826)
		(end 81.7372 5.031715)
		(width 0.188697)
		(layer "In7.Cu")
		(net "DDR0_32A_BA1")
	)
	(segment
		(start 67.137788 12.065)
		(end 67.237 11.965788)
		(width 0.188697)
		(layer "In7.Cu")
		(net "DDR0_32A_BA1")
	)
	(segment
		(start 68.199 11.24519)
		(end 68.199 11.8364)
		(width 0.188697)
		(layer "In7.Cu")
		(net "DDR0_32A_BA1")
	)
	(segment
		(start 71.312303 11.04199)
		(end 71.501 10.853293)
		(width 0.188697)
		(layer "In7.Cu")
		(net "DDR0_32A_BA1")
	)
	(segment
		(start 71.562697 8.984818)
		(end 71.562697 5.907303)
		(width 0.188697)
		(layer "In7.Cu")
		(net "DDR0_32A_BA1")
	)
	(segment
		(start 67.443985 11.04199)
		(end 67.9958 11.04199)
		(width 0.188697)
		(layer "In7.Cu")
		(net "DDR0_32A_BA1")
	)
	(segment
		(start 85.6996 4.754372)
		(end 85.421165 5.032807)
		(width 0.188697)
		(layer "In7.Cu")
		(net "DDR0_32A_BA1")
	)
	(segment
		(start 81.428133 6.881876)
		(end 81.428133 7.076135)
		(width 0.188697)
		(layer "In7.Cu")
		(net "DDR0_32A_BA1")
	)
	(segment
		(start 81.681269 6.270676)
		(end 81.673573 6.270676)
		(width 0.188697)
		(layer "In7.Cu")
		(net "DDR0_32A_BA1")
	)
	(segment
		(start 80.1624 4.6736)
		(end 80.3402 4.8514)
		(width 0.188697)
		(layer "In7.Cu")
		(net "DDR0_32A_BA1")
	)
	(segment
		(start 71.5772 9.418828)
		(end 71.566303 9.407931)
		(width 0.188697)
		(layer "In7.Cu")
		(net "DDR0_32A_BA1")
	)
	(segment
		(start 79.0194 5.334)
		(end 79.1718 5.4864)
		(width 0.188697)
		(layer "In7.Cu")
		(net "DDR0_32A_BA1")
	)
	(segment
		(start 69.2404 11.21979)
		(end 69.4182 11.04199)
		(width 0.188697)
		(layer "In7.Cu")
		(net "DDR0_32A_BA1")
	)
	(segment
		(start 78.359 4.826)
		(end 78.5114 4.6736)
		(width 0.188697)
		(layer "In7.Cu")
		(net "DDR0_32A_BA1")
	)
	(segment
		(start 78.8416 4.6736)
		(end 79.0194 4.8514)
		(width 0.188697)
		(layer "In7.Cu")
		(net "DDR0_32A_BA1")
	)
	(segment
		(start 65.9257 12.065)
		(end 67.137788 12.065)
		(width 0.188697)
		(layer "In7.Cu")
		(net "DDR0_32A_BA1")
	)
	(segment
		(start 81.0006 4.8514)
		(end 81.1784 4.6736)
		(width 0.188697)
		(layer "In7.Cu")
		(net "DDR0_32A_BA1")
	)
	(segment
		(start 67.237 11.248974)
		(end 67.443985 11.04199)
		(width 0.188697)
		(layer "In7.Cu")
		(net "DDR0_32A_BA1")
	)
	(segment
		(start 80.79613 6.2484)
		(end 81.0006 6.04393)
		(width 0.188697)
		(layer "In7.Cu")
		(net "DDR0_32A_BA1")
	)
	(segment
		(start 81.422672 6.521577)
		(end 81.422672 6.876415)
		(width 0.188697)
		(layer "In7.Cu")
		(net "DDR0_32A_BA1")
	)
	(segment
		(start 80.3402 6.04393)
		(end 80.54467 6.2484)
		(width 0.188697)
		(layer "In7.Cu")
		(net "DDR0_32A_BA1")
	)
	(segment
		(start 79.629 5.3594)
		(end 79.629 4.826)
		(width 0.188697)
		(layer "In7.Cu")
		(net "DDR0_32A_BA1")
	)
	(segment
		(start 81.0006 6.04393)
		(end 81.0006 4.8514)
		(width 0.188697)
		(layer "In7.Cu")
		(net "DDR0_32A_BA1")
	)
	(segment
		(start 82.5246 4.314393)
		(end 85.5218 4.314393)
		(width 0.188697)
		(layer "In7.Cu")
		(net "DDR0_32A_BA1")
	)
	(segment
		(start 72.009 5.461)
		(end 74.041 5.461)
		(width 0.188697)
		(layer "In7.Cu")
		(net "DDR0_32A_BA1")
	)
	(segment
		(start 68.467351 12.104751)
		(end 68.972049 12.104751)
		(width 0.188697)
		(layer "In7.Cu")
		(net "DDR0_32A_BA1")
	)
	(segment
		(start 79.629 4.826)
		(end 79.7814 4.6736)
		(width 0.188697)
		(layer "In7.Cu")
		(net "DDR0_32A_BA1")
	)
	(segment
		(start 78.1812 5.461)
		(end 78.359 5.2832)
		(width 0.188697)
		(layer "In7.Cu")
		(net "DDR0_32A_BA1")
	)
	(segment
		(start 71.566303 9.407931)
		(end 71.566303 8.988425)
		(width 0.188697)
		(layer "In7.Cu")
		(net "DDR0_32A_BA1")
	)
	(segment
		(start 80.3402 4.8514)
		(end 80.3402 6.04393)
		(width 0.188697)
		(layer "In7.Cu")
		(net "DDR0_32A_BA1")
	)
	(segment
		(start 79.0194 4.8514)
		(end 79.0194 5.334)
		(width 0.188697)
		(layer "In7.Cu")
		(net "DDR0_32A_BA1")
	)
	(segment
		(start 71.5772 9.876028)
		(end 71.5772 9.418828)
		(width 0.188697)
		(layer "In7.Cu")
		(net "DDR0_32A_BA1")
	)
	(segment
		(start 81.5848 4.6736)
		(end 81.7372 4.826)
		(width 0.188697)
		(layer "In7.Cu")
		(net "DDR0_32A_BA1")
	)
	(segment
		(start 71.562697 5.907303)
		(end 72.009 5.461)
		(width 0.188697)
		(layer "In7.Cu")
		(net "DDR0_32A_BA1")
	)
	(segment
		(start 74.041 5.461)
		(end 74.041 5.467706)
		(width 0.188697)
		(layer "In7.Cu")
		(net "DDR0_32A_BA1")
	)
	(segment
		(start 74.99096 6.04172)
		(end 75.57168 5.461)
		(width 0.188697)
		(layer "In7.Cu")
		(net "DDR0_32A_BA1")
	)
	(segment
		(start 81.915 5.209515)
		(end 82.16646 5.209515)
		(width 0.188697)
		(layer "In7.Cu")
		(net "DDR0_32A_BA1")
	)
	(segment
		(start 80.264 24.226012)
		(end 81.050994 25.013006)
		(width 0.14732)
		(layer "F.Cu")
		(net "DDR0_32A_BA0")
	)
	(segment
		(start 62.737009 17.542002)
		(end 62.23701 18.042001)
		(width 0.233528)
		(layer "F.Cu")
		(net "DDR0_32A_BA0")
	)
	(segment
		(start 80.0862 23.4061)
		(end 80.264 24.226012)
		(width 0.14732)
		(layer "F.Cu")
		(net "DDR0_32A_BA0")
	)
	(via
		(at 62.737009 17.542002)
		(size 0.4826)
		(drill 0.25654)
		(layers "F.Cu" "B.Cu")
		(net "DDR0_32A_BA0")
	)
	(segment
		(start 80.650994 25.413005)
		(end 81.050994 25.013006)
		(width 0.14732)
		(layer "B.Cu")
		(net "DDR0_32A_BA0")
	)
	(segment
		(start 80.650994 13.856005)
		(end 81.050994 13.456006)
		(width 0.14732)
		(layer "B.Cu")
		(net "DDR0_32A_BA0")
	)
	(segment
		(start 80.650994 2.299005)
		(end 81.050994 1.899006)
		(width 0.14732)
		(layer "B.Cu")
		(net "DDR0_32A_BA0")
	)
	(segment
		(start 63.783007 1.469593)
		(end 63.783007 0.895401)
		(width 0.188697)
		(layer "In2.Cu")
		(net "DDR0_32A_BA0")
	)
	(segment
		(start 81.445278 -1.358722)
		(end 81.445278 0.851078)
		(width 0.188697)
		(layer "In2.Cu")
		(net "DDR0_32A_BA0")
	)
	(segment
		(start 62.586006 9.041994)
		(end 62.967006 9.041994)
		(width 0.188697)
		(layer "In2.Cu")
		(net "DDR0_32A_BA0")
	)
	(segment
		(start 73.840772 -2.079193)
		(end 73.84222 -2.080641)
		(width 0.188697)
		(layer "In2.Cu")
		(net "DDR0_32A_BA0")
	)
	(segment
		(start 63.783007 0.895401)
		(end 66.746704 -2.068297)
		(width 0.188697)
		(layer "In2.Cu")
		(net "DDR0_32A_BA0")
	)
	(segment
		(start 81.445278 1.504721)
		(end 81.050994 1.899006)
		(width 0.12065)
		(layer "In2.Cu")
		(net "DDR0_32A_BA0")
	)
	(segment
		(start 62.967006 9.041994)
		(end 63.237008 8.771992)
		(width 0.188697)
		(layer "In2.Cu")
		(net "DDR0_32A_BA0")
	)
	(segment
		(start 63.237008 8.771992)
		(end 63.237008 2.015592)
		(width 0.188697)
		(layer "In2.Cu")
		(net "DDR0_32A_BA0")
	)
	(segment
		(start 62.23701 9.39099)
		(end 62.586006 9.041994)
		(width 0.188697)
		(layer "In2.Cu")
		(net "DDR0_32A_BA0")
	)
	(segment
		(start 66.826613 -2.068297)
		(end 66.837509 -2.079193)
		(width 0.188697)
		(layer "In2.Cu")
		(net "DDR0_32A_BA0")
	)
	(segment
		(start 66.746704 -2.068297)
		(end 66.826613 -2.068297)
		(width 0.188697)
		(layer "In2.Cu")
		(net "DDR0_32A_BA0")
	)
	(segment
		(start 63.237008 2.015592)
		(end 63.783007 1.469593)
		(width 0.188697)
		(layer "In2.Cu")
		(net "DDR0_32A_BA0")
	)
	(segment
		(start 81.443398 -1.360602)
		(end 81.445278 -1.358722)
		(width 0.188697)
		(layer "In2.Cu")
		(net "DDR0_32A_BA0")
	)
	(segment
		(start 73.84222 -2.080641)
		(end 80.738751 -2.080641)
		(width 0.188697)
		(layer "In2.Cu")
		(net "DDR0_32A_BA0")
	)
	(segment
		(start 81.445278 0.851078)
		(end 81.445278 1.504721)
		(width 0.12065)
		(layer "In2.Cu")
		(net "DDR0_32A_BA0")
	)
	(segment
		(start 80.738751 -2.080641)
		(end 81.443398 -1.375994)
		(width 0.188697)
		(layer "In2.Cu")
		(net "DDR0_32A_BA0")
	)
	(segment
		(start 62.23701 17.042003)
		(end 62.23701 9.39099)
		(width 0.188697)
		(layer "In2.Cu")
		(net "DDR0_32A_BA0")
	)
	(segment
		(start 66.837509 -2.079193)
		(end 73.840772 -2.079193)
		(width 0.188697)
		(layer "In2.Cu")
		(net "DDR0_32A_BA0")
	)
	(segment
		(start 62.737009 17.542002)
		(end 62.23701 17.042003)
		(width 0.188697)
		(layer "In2.Cu")
		(net "DDR0_32A_BA0")
	)
	(segment
		(start 81.443398 -1.375994)
		(end 81.443398 -1.360602)
		(width 0.188697)
		(layer "In2.Cu")
		(net "DDR0_32A_BA0")
	)
	(segment
		(start 81.050994 25.013006)
		(end 80.656709 24.618721)
		(width 0.12065)
		(layer "In6.Cu")
		(net "DDR0_32A_BA0")
	)
	(segment
		(start 81.050994 13.456006)
		(end 80.656709 13.061721)
		(width 0.12065)
		(layer "In6.Cu")
		(net "DDR0_32A_BA0")
	)
	(segment
		(start 80.656709 24.618721)
		(end 80.656709 13.85029)
		(width 0.12065)
		(layer "In6.Cu")
		(net "DDR0_32A_BA0")
	)
	(segment
		(start 81.050994 2.006981)
		(end 81.050994 1.899006)
		(width 0.12065)
		(layer "In6.Cu")
		(net "DDR0_32A_BA0")
	)
	(segment
		(start 80.656709 13.85029)
		(end 81.050994 13.456006)
		(width 0.12065)
		(layer "In6.Cu")
		(net "DDR0_32A_BA0")
	)
	(segment
		(start 80.656709 13.061721)
		(end 80.656709 2.401265)
		(width 0.12065)
		(layer "In6.Cu")
		(net "DDR0_32A_BA0")
	)
	(segment
		(start 80.656709 2.401265)
		(end 81.050994 2.006981)
		(width 0.12065)
		(layer "In6.Cu")
		(net "DDR0_32A_BA0")
	)
	(segment
		(start 64.737005 20.541996)
		(end 64.237006 20.041997)
		(width 0.233528)
		(layer "F.Cu")
		(net "DDR0_32A_A14")
	)
	(segment
		(start 84.250987 29.452113)
		(end 84.250987 29.812996)
		(width 0.14732)
		(layer "F.Cu")
		(net "DDR0_32A_A14")
	)
	(segment
		(start 84.582 29.1211)
		(end 84.250987 29.452113)
		(width 0.14732)
		(layer "F.Cu")
		(net "DDR0_32A_A14")
	)
	(via
		(at 64.737005 20.541996)
		(size 0.4826)
		(drill 0.25654)
		(layers "F.Cu" "B.Cu")
		(net "DDR0_32A_A14")
	)
	(segment
		(start 83.850988 17.855997)
		(end 84.250987 18.255996)
		(width 0.14732)
		(layer "B.Cu")
		(net "DDR0_32A_A14")
	)
	(segment
		(start 83.850988 6.298997)
		(end 84.250987 6.698996)
		(width 0.14732)
		(layer "B.Cu")
		(net "DDR0_32A_A14")
	)
	(segment
		(start 83.850988 29.412997)
		(end 84.250987 29.812996)
		(width 0.14732)
		(layer "B.Cu")
		(net "DDR0_32A_A14")
	)
	(segment
		(start 84.703793 18.708802)
		(end 84.250987 18.255996)
		(width 0.12065)
		(layer "In3.Cu")
		(net "DDR0_32A_A14")
	)
	(segment
		(start 84.709 17.797983)
		(end 84.709 7.157009)
		(width 0.12065)
		(layer "In3.Cu")
		(net "DDR0_32A_A14")
	)
	(segment
		(start 84.250987 18.255996)
		(end 84.709 17.797983)
		(width 0.12065)
		(layer "In3.Cu")
		(net "DDR0_32A_A14")
	)
	(segment
		(start 84.703793 29.36019)
		(end 84.703793 18.708802)
		(width 0.12065)
		(layer "In3.Cu")
		(net "DDR0_32A_A14")
	)
	(segment
		(start 84.250987 29.812996)
		(end 84.703793 29.36019)
		(width 0.12065)
		(layer "In3.Cu")
		(net "DDR0_32A_A14")
	)
	(segment
		(start 84.709 7.157009)
		(end 84.250987 6.698996)
		(width 0.12065)
		(layer "In3.Cu")
		(net "DDR0_32A_A14")
	)
	(segment
		(start 71.822691 20.369632)
		(end 71.822691 17.278579)
		(width 0.188697)
		(layer "In7.Cu")
		(net "DDR0_32A_A14")
	)
	(segment
		(start 86.7664 17.78)
		(end 86.9442 17.6022)
		(width 0.188697)
		(layer "In7.Cu")
		(net "DDR0_32A_A14")
	)
	(segment
		(start 86.584028 17.78)
		(end 86.7664 17.78)
		(width 0.188697)
		(layer "In7.Cu")
		(net "DDR0_32A_A14")
	)
	(segment
		(start 74.0664 16.891)
		(end 74.3458 17.1704)
		(width 0.188697)
		(layer "In7.Cu")
		(net "DDR0_32A_A14")
	)
	(segment
		(start 84.583321 17.801793)
		(end 86.278263 17.801793)
		(width 0.188697)
		(layer "In7.Cu")
		(net "DDR0_32A_A14")
	)
	(segment
		(start 86.9442 17.135856)
		(end 86.965993 17.114063)
		(width 0.188697)
		(layer "In7.Cu")
		(net "DDR0_32A_A14")
	)
	(segment
		(start 84.561528 17.78)
		(end 84.583321 17.801793)
		(width 0.188697)
		(layer "In7.Cu")
		(net "DDR0_32A_A14")
	)
	(segment
		(start 86.9442 6.876796)
		(end 86.7664 6.698996)
		(width 0.188697)
		(layer "In7.Cu")
		(net "DDR0_32A_A14")
	)
	(segment
		(start 71.822691 17.278579)
		(end 72.009 17.09227)
		(width 0.188697)
		(layer "In7.Cu")
		(net "DDR0_32A_A14")
	)
	(segment
		(start 72.009 17.071848)
		(end 72.189848 16.891)
		(width 0.188697)
		(layer "In7.Cu")
		(net "DDR0_32A_A14")
	)
	(segment
		(start 72.009 17.09227)
		(end 72.009 17.071848)
		(width 0.188697)
		(layer "In7.Cu")
		(net "DDR0_32A_A14")
	)
	(segment
		(start 74.3458 17.5768)
		(end 74.549 17.78)
		(width 0.188697)
		(layer "In7.Cu")
		(net "DDR0_32A_A14")
	)
	(segment
		(start 65.223263 21.028254)
		(end 66.982746 21.028254)
		(width 0.188697)
		(layer "In7.Cu")
		(net "DDR0_32A_A14")
	)
	(segment
		(start 86.9442 17.6022)
		(end 86.9442 17.135856)
		(width 0.188697)
		(layer "In7.Cu")
		(net "DDR0_32A_A14")
	)
	(segment
		(start 64.737005 20.541996)
		(end 65.223263 21.028254)
		(width 0.188697)
		(layer "In7.Cu")
		(net "DDR0_32A_A14")
	)
	(segment
		(start 74.549 17.78)
		(end 84.561528 17.78)
		(width 0.188697)
		(layer "In7.Cu")
		(net "DDR0_32A_A14")
	)
	(segment
		(start 86.7664 6.698996)
		(end 84.250987 6.698996)
		(width 0.188697)
		(layer "In7.Cu")
		(net "DDR0_32A_A14")
	)
	(segment
		(start 71.650327 20.541996)
		(end 71.822691 20.369632)
		(width 0.188697)
		(layer "In7.Cu")
		(net "DDR0_32A_A14")
	)
	(segment
		(start 86.9442 7.603744)
		(end 86.9442 6.876796)
		(width 0.188697)
		(layer "In7.Cu")
		(net "DDR0_32A_A14")
	)
	(segment
		(start 86.573131 17.790897)
		(end 86.584028 17.78)
		(width 0.188697)
		(layer "In7.Cu")
		(net "DDR0_32A_A14")
	)
	(segment
		(start 67.469004 20.541996)
		(end 71.650327 20.541996)
		(width 0.188697)
		(layer "In7.Cu")
		(net "DDR0_32A_A14")
	)
	(segment
		(start 66.982746 21.028254)
		(end 67.469004 20.541996)
		(width 0.188697)
		(layer "In7.Cu")
		(net "DDR0_32A_A14")
	)
	(segment
		(start 86.965993 17.114063)
		(end 86.965993 7.625537)
		(width 0.188697)
		(layer "In7.Cu")
		(net "DDR0_32A_A14")
	)
	(segment
		(start 72.189848 16.891)
		(end 74.0664 16.891)
		(width 0.188697)
		(layer "In7.Cu")
		(net "DDR0_32A_A14")
	)
	(segment
		(start 86.289159 17.790897)
		(end 86.573131 17.790897)
		(width 0.188697)
		(layer "In7.Cu")
		(net "DDR0_32A_A14")
	)
	(segment
		(start 86.278263 17.801793)
		(end 86.289159 17.790897)
		(width 0.188697)
		(layer "In7.Cu")
		(net "DDR0_32A_A14")
	)
	(segment
		(start 74.3458 17.1704)
		(end 74.3458 17.5768)
		(width 0.188697)
		(layer "In7.Cu")
		(net "DDR0_32A_A14")
	)
	(segment
		(start 86.965993 7.625537)
		(end 86.9442 7.603744)
		(width 0.188697)
		(layer "In7.Cu")
		(net "DDR0_32A_A14")
	)
	(segment
		(start 84.250987 26.173887)
		(end 84.250987 25.813004)
		(width 0.14732)
		(layer "F.Cu")
		(net "DDR0_32A_A13")
	)
	(segment
		(start 63.737007 9.541993)
		(end 63.237008 10.041992)
		(width 0.233528)
		(layer "F.Cu")
		(net "DDR0_32A_A13")
	)
	(segment
		(start 84.582 26.5049)
		(end 84.250987 26.173887)
		(width 0.14732)
		(layer "F.Cu")
		(net "DDR0_32A_A13")
	)
	(via
		(at 63.737007 9.541993)
		(size 0.4826)
		(drill 0.20574)
		(layers "F.Cu" "B.Cu")
		(net "DDR0_32A_A13")
	)
	(segment
		(start 83.850988 26.213003)
		(end 84.250987 25.813004)
		(width 0.14732)
		(layer "B.Cu")
		(net "DDR0_32A_A13")
	)
	(segment
		(start 83.850988 14.656003)
		(end 84.250987 14.256004)
		(width 0.14732)
		(layer "B.Cu")
		(net "DDR0_32A_A13")
	)
	(segment
		(start 83.850988 3.099003)
		(end 84.250987 2.699004)
		(width 0.14732)
		(layer "B.Cu")
		(net "DDR0_32A_A13")
	)
	(segment
		(start 62.5856 -0.4064)
		(end 62.8396 -0.1524)
		(width 0.188697)
		(layer "In6.Cu")
		(net "DDR0_32A_A13")
	)
	(segment
		(start 84.645271 3.093288)
		(end 84.250987 2.699004)
		(width 0.12065)
		(layer "In6.Cu")
		(net "DDR0_32A_A13")
	)
	(segment
		(start 84.250987 14.256004)
		(end 84.645271 13.86172)
		(width 0.12065)
		(layer "In6.Cu")
		(net "DDR0_32A_A13")
	)
	(segment
		(start 84.250987 25.813004)
		(end 84.703793 25.360198)
		(width 0.12065)
		(layer "In6.Cu")
		(net "DDR0_32A_A13")
	)
	(segment
		(start 64.174268 2.723134)
		(end 64.168807 2.728595)
		(width 0.188697)
		(layer "In6.Cu")
		(net "DDR0_32A_A13")
	)
	(segment
		(start 84.673846 -1.605382)
		(end 84.673846 -1.8542)
		(width 0.188697)
		(layer "In6.Cu")
		(net "DDR0_32A_A13")
	)
	(segment
		(start 64.174268 2.360879)
		(end 64.174268 2.723134)
		(width 0.188697)
		(layer "In6.Cu")
		(net "DDR0_32A_A13")
	)
	(segment
		(start 63.237008 9.041994)
		(end 63.737007 9.541993)
		(width 0.188697)
		(layer "In6.Cu")
		(net "DDR0_32A_A13")
	)
	(segment
		(start 63.237008 3.692017)
		(end 63.237008 9.041994)
		(width 0.188697)
		(layer "In6.Cu")
		(net "DDR0_32A_A13")
	)
	(segment
		(start 84.703793 14.70881)
		(end 84.250987 14.256004)
		(width 0.12065)
		(layer "In6.Cu")
		(net "DDR0_32A_A13")
	)
	(segment
		(start 84.703793 25.360198)
		(end 84.703793 14.70881)
		(width 0.12065)
		(layer "In6.Cu")
		(net "DDR0_32A_A13")
	)
	(segment
		(start 62.5856 -1.8288)
		(end 62.5856 -0.4064)
		(width 0.188697)
		(layer "In6.Cu")
		(net "DDR0_32A_A13")
	)
	(segment
		(start 84.684743 -1.594485)
		(end 84.673846 -1.605382)
		(width 0.188697)
		(layer "In6.Cu")
		(net "DDR0_32A_A13")
	)
	(segment
		(start 64.168807 2.760218)
		(end 63.237008 3.692017)
		(width 0.188697)
		(layer "In6.Cu")
		(net "DDR0_32A_A13")
	)
	(segment
		(start 84.496046 -2.032)
		(end 62.7888 -2.032)
		(width 0.188697)
		(layer "In6.Cu")
		(net "DDR0_32A_A13")
	)
	(segment
		(start 84.250987 2.699004)
		(end 84.684743 2.265248)
		(width 0.188697)
		(layer "In6.Cu")
		(net "DDR0_32A_A13")
	)
	(segment
		(start 62.7888 -2.032)
		(end 62.5856 -1.8288)
		(width 0.188697)
		(layer "In6.Cu")
		(net "DDR0_32A_A13")
	)
	(segment
		(start 63.950215 -0.1524)
		(end 64.157911 0.055296)
		(width 0.188697)
		(layer "In6.Cu")
		(net "DDR0_32A_A13")
	)
	(segment
		(start 64.157911 0.055296)
		(end 64.157911 1.686458)
		(width 0.188697)
		(layer "In6.Cu")
		(net "DDR0_32A_A13")
	)
	(segment
		(start 62.8396 -0.1524)
		(end 63.950215 -0.1524)
		(width 0.188697)
		(layer "In6.Cu")
		(net "DDR0_32A_A13")
	)
	(segment
		(start 84.673846 -1.8542)
		(end 84.496046 -2.032)
		(width 0.188697)
		(layer "In6.Cu")
		(net "DDR0_32A_A13")
	)
	(segment
		(start 64.157911 1.686458)
		(end 64.168807 1.697355)
		(width 0.188697)
		(layer "In6.Cu")
		(net "DDR0_32A_A13")
	)
	(segment
		(start 84.684743 2.265248)
		(end 84.684743 -1.594485)
		(width 0.188697)
		(layer "In6.Cu")
		(net "DDR0_32A_A13")
	)
	(segment
		(start 84.645271 13.86172)
		(end 84.645271 3.093288)
		(width 0.12065)
		(layer "In6.Cu")
		(net "DDR0_32A_A13")
	)
	(segment
		(start 64.168807 1.697355)
		(end 64.168807 2.355418)
		(width 0.188697)
		(layer "In6.Cu")
		(net "DDR0_32A_A13")
	)
	(segment
		(start 64.168807 2.355418)
		(end 64.174268 2.360879)
		(width 0.188697)
		(layer "In6.Cu")
		(net "DDR0_32A_A13")
	)
	(segment
		(start 64.168807 2.728595)
		(end 64.168807 2.760218)
		(width 0.188697)
		(layer "In6.Cu")
		(net "DDR0_32A_A13")
	)
	(segment
		(start 63.737007 14.542008)
		(end 63.237008 15.042007)
		(width 0.233528)
		(layer "F.Cu")
		(net "DDR0_32A_A12")
	)
	(segment
		(start 81.850992 29.185108)
		(end 81.850992 29.812996)
		(width 0.14732)
		(layer "F.Cu")
		(net "DDR0_32A_A12")
	)
	(segment
		(start 81.915 29.1211)
		(end 81.850992 29.185108)
		(width 0.14732)
		(layer "F.Cu")
		(net "DDR0_32A_A12")
	)
	(via
		(at 63.737007 14.542008)
		(size 0.4826)
		(drill 0.20574)
		(layers "F.Cu" "B.Cu")
		(net "DDR0_32A_A12")
	)
	(segment
		(start 81.450993 29.412997)
		(end 81.850992 29.812996)
		(width 0.14732)
		(layer "B.Cu")
		(net "DDR0_32A_A12")
	)
	(segment
		(start 81.450993 17.855997)
		(end 81.850992 18.255996)
		(width 0.14732)
		(layer "B.Cu")
		(net "DDR0_32A_A12")
	)
	(segment
		(start 81.450993 6.298997)
		(end 81.850992 6.698996)
		(width 0.14732)
		(layer "B.Cu")
		(net "DDR0_32A_A12")
	)
	(segment
		(start 81.456708 18.65028)
		(end 81.850992 18.255996)
		(width 0.12065)
		(layer "In2.Cu")
		(net "DDR0_32A_A12")
	)
	(segment
		(start 81.456708 17.861712)
		(end 81.456708 7.09328)
		(width 0.12065)
		(layer "In2.Cu")
		(net "DDR0_32A_A12")
	)
	(segment
		(start 81.456708 29.418712)
		(end 81.456708 18.65028)
		(width 0.12065)
		(layer "In2.Cu")
		(net "DDR0_32A_A12")
	)
	(segment
		(start 81.456708 7.09328)
		(end 81.850992 6.698996)
		(width 0.12065)
		(layer "In2.Cu")
		(net "DDR0_32A_A12")
	)
	(segment
		(start 81.850992 18.255996)
		(end 81.456708 17.861712)
		(width 0.12065)
		(layer "In2.Cu")
		(net "DDR0_32A_A12")
	)
	(segment
		(start 81.850992 29.812996)
		(end 81.456708 29.418712)
		(width 0.12065)
		(layer "In2.Cu")
		(net "DDR0_32A_A12")
	)
	(segment
		(start 71.92645 15.783662)
		(end 71.211338 15.783662)
		(width 0.188697)
		(layer "In7.Cu")
		(net "DDR0_32A_A12")
	)
	(segment
		(start 71.211338 15.783662)
		(end 70.952995 16.042005)
		(width 0.188697)
		(layer "In7.Cu")
		(net "DDR0_32A_A12")
	)
	(segment
		(start 75.168862 15.783662)
		(end 73.375571 15.783662)
		(width 0.188697)
		(layer "In7.Cu")
		(net "DDR0_32A_A12")
	)
	(segment
		(start 73.375571 15.783662)
		(end 73.359213 15.800019)
		(width 0.188697)
		(layer "In7.Cu")
		(net "DDR0_32A_A12")
	)
	(segment
		(start 71.942808 15.800019)
		(end 71.92645 15.783662)
		(width 0.188697)
		(layer "In7.Cu")
		(net "DDR0_32A_A12")
	)
	(segment
		(start 82.4738 11.3284)
		(end 83.3374 11.3284)
		(width 0.188697)
		(layer "In7.Cu")
		(net "DDR0_32A_A12")
	)
	(segment
		(start 85.7758 9.5504)
		(end 85.7758 16.4338)
		(width 0.188697)
		(layer "In7.Cu")
		(net "DDR0_32A_A12")
	)
	(segment
		(start 84.583321 16.626103)
		(end 84.572424 16.637)
		(width 0.188697)
		(layer "In7.Cu")
		(net "DDR0_32A_A12")
	)
	(segment
		(start 73.359213 15.800019)
		(end 71.942808 15.800019)
		(width 0.188697)
		(layer "In7.Cu")
		(net "DDR0_32A_A12")
	)
	(segment
		(start 85.7758 16.4338)
		(end 85.583497 16.626103)
		(width 0.188697)
		(layer "In7.Cu")
		(net "DDR0_32A_A12")
	)
	(segment
		(start 81.850992 6.698996)
		(end 81.850992 6.941363)
		(width 0.12065)
		(layer "In7.Cu")
		(net "DDR0_32A_A12")
	)
	(segment
		(start 84.572424 16.637)
		(end 75.7682 16.637)
		(width 0.188697)
		(layer "In7.Cu")
		(net "DDR0_32A_A12")
	)
	(segment
		(start 81.850992 6.941363)
		(end 82.245276 7.335647)
		(width 0.12065)
		(layer "In7.Cu")
		(net "DDR0_32A_A12")
	)
	(segment
		(start 83.6676 9.3472)
		(end 85.5726 9.3472)
		(width 0.188697)
		(layer "In7.Cu")
		(net "DDR0_32A_A12")
	)
	(segment
		(start 65.237004 16.042005)
		(end 63.737007 14.542008)
		(width 0.188697)
		(layer "In7.Cu")
		(net "DDR0_32A_A12")
	)
	(segment
		(start 83.3374 11.3284)
		(end 83.5152 11.1506)
		(width 0.188697)
		(layer "In7.Cu")
		(net "DDR0_32A_A12")
	)
	(segment
		(start 83.5152 9.4996)
		(end 83.6676 9.3472)
		(width 0.188697)
		(layer "In7.Cu")
		(net "DDR0_32A_A12")
	)
	(segment
		(start 82.245276 7.335647)
		(end 82.245276 8.712276)
		(width 0.12065)
		(layer "In7.Cu")
		(net "DDR0_32A_A12")
	)
	(segment
		(start 85.583497 16.626103)
		(end 84.583321 16.626103)
		(width 0.188697)
		(layer "In7.Cu")
		(net "DDR0_32A_A12")
	)
	(segment
		(start 82.245276 8.712276)
		(end 82.245276 11.099876)
		(width 0.188697)
		(layer "In7.Cu")
		(net "DDR0_32A_A12")
	)
	(segment
		(start 75.5904 16.4592)
		(end 75.5904 16.2052)
		(width 0.188697)
		(layer "In7.Cu")
		(net "DDR0_32A_A12")
	)
	(segment
		(start 82.245276 11.099876)
		(end 82.4738 11.3284)
		(width 0.188697)
		(layer "In7.Cu")
		(net "DDR0_32A_A12")
	)
	(segment
		(start 83.5152 11.1506)
		(end 83.5152 9.4996)
		(width 0.188697)
		(layer "In7.Cu")
		(net "DDR0_32A_A12")
	)
	(segment
		(start 75.5904 16.2052)
		(end 75.168862 15.783662)
		(width 0.188697)
		(layer "In7.Cu")
		(net "DDR0_32A_A12")
	)
	(segment
		(start 75.7682 16.637)
		(end 75.5904 16.4592)
		(width 0.188697)
		(layer "In7.Cu")
		(net "DDR0_32A_A12")
	)
	(segment
		(start 85.5726 9.3472)
		(end 85.7758 9.5504)
		(width 0.188697)
		(layer "In7.Cu")
		(net "DDR0_32A_A12")
	)
	(segment
		(start 70.952995 16.042005)
		(end 65.237004 16.042005)
		(width 0.188697)
		(layer "In7.Cu")
		(net "DDR0_32A_A12")
	)
	(segment
		(start 83.693 29.1211)
		(end 83.450989 29.363111)
		(width 0.14732)
		(layer "F.Cu")
		(net "DDR0_32A_A11")
	)
	(segment
		(start 83.450989 29.363111)
		(end 83.450989 29.812996)
		(width 0.14732)
		(layer "F.Cu")
		(net "DDR0_32A_A11")
	)
	(segment
		(start 63.737007 20.541996)
		(end 63.237008 20.041997)
		(width 0.233528)
		(layer "F.Cu")
		(net "DDR0_32A_A11")
	)
	(via
		(at 63.737007 20.541996)
		(size 0.4826)
		(drill 0.25654)
		(layers "F.Cu" "B.Cu")
		(net "DDR0_32A_A11")
	)
	(segment
		(start 83.05099 6.298997)
		(end 83.450989 6.698996)
		(width 0.14732)
		(layer "B.Cu")
		(net "DDR0_32A_A11")
	)
	(segment
		(start 83.05099 17.855997)
		(end 83.450989 18.255996)
		(width 0.14732)
		(layer "B.Cu")
		(net "DDR0_32A_A11")
	)
	(segment
		(start 83.05099 29.412997)
		(end 83.450989 29.812996)
		(width 0.14732)
		(layer "B.Cu")
		(net "DDR0_32A_A11")
	)
	(segment
		(start 83.450989 18.255996)
		(end 83.845273 17.861712)
		(width 0.12065)
		(layer "In3.Cu")
		(net "DDR0_32A_A11")
	)
	(segment
		(start 83.845273 17.861712)
		(end 83.845273 7.09328)
		(width 0.12065)
		(layer "In3.Cu")
		(net "DDR0_32A_A11")
	)
	(segment
		(start 83.450989 29.812996)
		(end 83.845273 29.418712)
		(width 0.12065)
		(layer "In3.Cu")
		(net "DDR0_32A_A11")
	)
	(segment
		(start 83.845273 18.65028)
		(end 83.450989 18.255996)
		(width 0.12065)
		(layer "In3.Cu")
		(net "DDR0_32A_A11")
	)
	(segment
		(start 83.845273 29.418712)
		(end 83.845273 18.65028)
		(width 0.12065)
		(layer "In3.Cu")
		(net "DDR0_32A_A11")
	)
	(segment
		(start 83.845273 7.09328)
		(end 83.450989 6.698996)
		(width 0.12065)
		(layer "In3.Cu")
		(net "DDR0_32A_A11")
	)
	(segment
		(start 83.845273 7.7216)
		(end 83.845273 7.300671)
		(width 0.12065)
		(layer "In7.Cu")
		(net "DDR0_32A_A11")
	)
	(segment
		(start 86.552303 7.766075)
		(end 86.552303 7.583703)
		(width 0.188697)
		(layer "In7.Cu")
		(net "DDR0_32A_A11")
	)
	(segment
		(start 86.552303 16.973525)
		(end 86.574097 16.951731)
		(width 0.188697)
		(layer "In7.Cu")
		(net "DDR0_32A_A11")
	)
	(segment
		(start 74.3458 16.51)
		(end 74.803 16.9672)
		(width 0.188697)
		(layer "In7.Cu")
		(net "DDR0_32A_A11")
	)
	(segment
		(start 83.450989 6.906387)
		(end 83.450989 6.698996)
		(width 0.12065)
		(layer "In7.Cu")
		(net "DDR0_32A_A11")
	)
	(segment
		(start 84.572424 17.399)
		(end 84.583321 17.409897)
		(width 0.188697)
		(layer "In7.Cu")
		(net "DDR0_32A_A11")
	)
	(segment
		(start 86.552303 7.583703)
		(end 86.3346 7.366)
		(width 0.188697)
		(layer "In7.Cu")
		(net "DDR0_32A_A11")
	)
	(segment
		(start 70.916063 18.542)
		(end 71.506994 17.951069)
		(width 0.188697)
		(layer "In7.Cu")
		(net "DDR0_32A_A11")
	)
	(segment
		(start 86.574097 16.951731)
		(end 86.574097 7.787869)
		(width 0.188697)
		(layer "In7.Cu")
		(net "DDR0_32A_A11")
	)
	(segment
		(start 71.506994 17.147794)
		(end 71.523352 17.131436)
		(width 0.188697)
		(layer "In7.Cu")
		(net "DDR0_32A_A11")
	)
	(segment
		(start 64.262 20.066)
		(end 64.897 20.066)
		(width 0.188697)
		(layer "In7.Cu")
		(net "DDR0_32A_A11")
	)
	(segment
		(start 83.845273 7.300671)
		(end 83.450989 6.906387)
		(width 0.12065)
		(layer "In7.Cu")
		(net "DDR0_32A_A11")
	)
	(segment
		(start 84.023073 7.8994)
		(end 83.845273 7.7216)
		(width 0.12065)
		(layer "In7.Cu")
		(net "DDR0_32A_A11")
	)
	(segment
		(start 84.583321 17.409897)
		(end 86.115931 17.409897)
		(width 0.188697)
		(layer "In7.Cu")
		(net "DDR0_32A_A11")
	)
	(segment
		(start 71.523352 16.741648)
		(end 71.755 16.51)
		(width 0.188697)
		(layer "In7.Cu")
		(net "DDR0_32A_A11")
	)
	(segment
		(start 86.552303 17.257497)
		(end 86.552303 16.973525)
		(width 0.188697)
		(layer "In7.Cu")
		(net "DDR0_32A_A11")
	)
	(segment
		(start 71.755 16.51)
		(end 74.3458 16.51)
		(width 0.188697)
		(layer "In7.Cu")
		(net "DDR0_32A_A11")
	)
	(segment
		(start 65.532 18.542)
		(end 70.916063 18.542)
		(width 0.188697)
		(layer "In7.Cu")
		(net "DDR0_32A_A11")
	)
	(segment
		(start 74.803 17.2212)
		(end 74.9808 17.399)
		(width 0.188697)
		(layer "In7.Cu")
		(net "DDR0_32A_A11")
	)
	(segment
		(start 65.237004 19.725996)
		(end 65.237004 18.836996)
		(width 0.188697)
		(layer "In7.Cu")
		(net "DDR0_32A_A11")
	)
	(segment
		(start 86.574097 7.787869)
		(end 86.552303 7.766075)
		(width 0.188697)
		(layer "In7.Cu")
		(net "DDR0_32A_A11")
	)
	(segment
		(start 86.3346 7.366)
		(end 85.0138 7.366)
		(width 0.188697)
		(layer "In7.Cu")
		(net "DDR0_32A_A11")
	)
	(segment
		(start 84.4804 7.8994)
		(end 84.023073 7.8994)
		(width 0.12065)
		(layer "In7.Cu")
		(net "DDR0_32A_A11")
	)
	(segment
		(start 86.126828 17.399)
		(end 86.4108 17.399)
		(width 0.188697)
		(layer "In7.Cu")
		(net "DDR0_32A_A11")
	)
	(segment
		(start 74.803 16.9672)
		(end 74.803 17.2212)
		(width 0.188697)
		(layer "In7.Cu")
		(net "DDR0_32A_A11")
	)
	(segment
		(start 74.9808 17.399)
		(end 84.572424 17.399)
		(width 0.188697)
		(layer "In7.Cu")
		(net "DDR0_32A_A11")
	)
	(segment
		(start 85.0138 7.366)
		(end 84.4804 7.8994)
		(width 0.188697)
		(layer "In7.Cu")
		(net "DDR0_32A_A11")
	)
	(segment
		(start 63.786004 20.541996)
		(end 64.262 20.066)
		(width 0.188697)
		(layer "In7.Cu")
		(net "DDR0_32A_A11")
	)
	(segment
		(start 86.115931 17.409897)
		(end 86.126828 17.399)
		(width 0.188697)
		(layer "In7.Cu")
		(net "DDR0_32A_A11")
	)
	(segment
		(start 63.737007 20.541996)
		(end 63.786004 20.541996)
		(width 0.188697)
		(layer "In7.Cu")
		(net "DDR0_32A_A11")
	)
	(segment
		(start 71.523352 17.131436)
		(end 71.523352 16.741648)
		(width 0.188697)
		(layer "In7.Cu")
		(net "DDR0_32A_A11")
	)
	(segment
		(start 64.897 20.066)
		(end 65.237004 19.725996)
		(width 0.188697)
		(layer "In7.Cu")
		(net "DDR0_32A_A11")
	)
	(segment
		(start 71.506994 17.951069)
		(end 71.506994 17.147794)
		(width 0.188697)
		(layer "In7.Cu")
		(net "DDR0_32A_A11")
	)
	(segment
		(start 65.237004 18.836996)
		(end 65.532 18.542)
		(width 0.188697)
		(layer "In7.Cu")
		(net "DDR0_32A_A11")
	)
	(segment
		(start 86.4108 17.399)
		(end 86.552303 17.257497)
		(width 0.188697)
		(layer "In7.Cu")
		(net "DDR0_32A_A11")
	)
	(segment
		(start 80.137 29.699001)
		(end 80.250995 29.812996)
		(width 0.14732)
		(layer "F.Cu")
		(net "DDR0_32A_A10")
	)
	(segment
		(start 64.737005 14.542008)
		(end 64.237006 15.042007)
		(width 0.233528)
		(layer "F.Cu")
		(net "DDR0_32A_A10")
	)
	(segment
		(start 80.137 29.1211)
		(end 80.137 29.699001)
		(width 0.14732)
		(layer "F.Cu")
		(net "DDR0_32A_A10")
	)
	(via
		(at 64.737005 14.542008)
		(size 0.4826)
		(drill 0.20574)
		(layers "F.Cu" "B.Cu")
		(net "DDR0_32A_A10")
	)
	(segment
		(start 79.850996 17.855997)
		(end 80.250995 18.255996)
		(width 0.14732)
		(layer "B.Cu")
		(net "DDR0_32A_A10")
	)
	(segment
		(start 79.850996 6.298997)
		(end 80.250995 6.698996)
		(width 0.14732)
		(layer "B.Cu")
		(net "DDR0_32A_A10")
	)
	(segment
		(start 79.850996 29.412997)
		(end 80.250995 29.812996)
		(width 0.14732)
		(layer "B.Cu")
		(net "DDR0_32A_A10")
	)
	(segment
		(start 80.250995 18.255996)
		(end 80.645279 18.65028)
		(width 0.12065)
		(layer "In2.Cu")
		(net "DDR0_32A_A10")
	)
	(segment
		(start 80.250995 6.698996)
		(end 80.645279 7.09328)
		(width 0.12065)
		(layer "In2.Cu")
		(net "DDR0_32A_A10")
	)
	(segment
		(start 80.645279 7.09328)
		(end 80.645279 17.861712)
		(width 0.12065)
		(layer "In2.Cu")
		(net "DDR0_32A_A10")
	)
	(segment
		(start 80.645279 18.65028)
		(end 80.645279 29.418712)
		(width 0.12065)
		(layer "In2.Cu")
		(net "DDR0_32A_A10")
	)
	(segment
		(start 80.645279 17.861712)
		(end 80.250995 18.255996)
		(width 0.12065)
		(layer "In2.Cu")
		(net "DDR0_32A_A10")
	)
	(segment
		(start 80.645279 29.418712)
		(end 80.250995 29.812996)
		(width 0.12065)
		(layer "In2.Cu")
		(net "DDR0_32A_A10")
	)
	(segment
		(start 75.8952 15.875)
		(end 75.5142 15.494)
		(width 0.188697)
		(layer "In7.Cu")
		(net "DDR0_32A_A10")
	)
	(segment
		(start 78.7908 15.5448)
		(end 78.5368 15.7988)
		(width 0.188697)
		(layer "In7.Cu")
		(net "DDR0_32A_A10")
	)
	(segment
		(start 85.344 9.9822)
		(end 85.344 16.1036)
		(width 0.188697)
		(layer "In7.Cu")
		(net "DDR0_32A_A10")
	)
	(segment
		(start 80.656709 7.10471)
		(end 80.656709 8.763)
		(width 0.12065)
		(layer "In7.Cu")
		(net "DDR0_32A_A10")
	)
	(segment
		(start 72.073592 15.484323)
		(end 71.822691 15.233421)
		(width 0.188697)
		(layer "In7.Cu")
		(net "DDR0_32A_A10")
	)
	(segment
		(start 84.0232 9.9568)
		(end 84.1756 9.8044)
		(width 0.188697)
		(layer "In7.Cu")
		(net "DDR0_32A_A10")
	)
	(segment
		(start 84.0232 11.7094)
		(end 84.0232 9.9568)
		(width 0.188697)
		(layer "In7.Cu")
		(net "DDR0_32A_A10")
	)
	(segment
		(start 81.8134 11.7094)
		(end 81.9658 11.8618)
		(width 0.188697)
		(layer "In7.Cu")
		(net "DDR0_32A_A10")
	)
	(segment
		(start 79.502 15.9766)
		(end 79.502 15.7226)
		(width 0.188697)
		(layer "In7.Cu")
		(net "DDR0_32A_A10")
	)
	(segment
		(start 85.1662 9.8044)
		(end 85.344 9.9822)
		(width 0.188697)
		(layer "In7.Cu")
		(net "DDR0_32A_A10")
	)
	(segment
		(start 75.325681 15.494)
		(end 75.299646 15.467965)
		(width 0.188697)
		(layer "In7.Cu")
		(net "DDR0_32A_A10")
	)
	(segment
		(start 81.9658 11.8618)
		(end 83.8708 11.8618)
		(width 0.188697)
		(layer "In7.Cu")
		(net "DDR0_32A_A10")
	)
	(segment
		(start 73.228429 15.484323)
		(end 72.073592 15.484323)
		(width 0.188697)
		(layer "In7.Cu")
		(net "DDR0_32A_A10")
	)
	(segment
		(start 76.0984 16.2306)
		(end 75.8952 16.0274)
		(width 0.188697)
		(layer "In7.Cu")
		(net "DDR0_32A_A10")
	)
	(segment
		(start 75.299646 15.467965)
		(end 73.244786 15.467965)
		(width 0.188697)
		(layer "In7.Cu")
		(net "DDR0_32A_A10")
	)
	(segment
		(start 78.5368 15.7988)
		(end 78.5368 15.9766)
		(width 0.188697)
		(layer "In7.Cu")
		(net "DDR0_32A_A10")
	)
	(segment
		(start 78.5368 15.9766)
		(end 78.2828 16.2306)
		(width 0.188697)
		(layer "In7.Cu")
		(net "DDR0_32A_A10")
	)
	(segment
		(start 71.822691 15.233421)
		(end 71.822691 15.225725)
		(width 0.188697)
		(layer "In7.Cu")
		(net "DDR0_32A_A10")
	)
	(segment
		(start 85.344 16.1036)
		(end 85.217 16.2306)
		(width 0.188697)
		(layer "In7.Cu")
		(net "DDR0_32A_A10")
	)
	(segment
		(start 83.8708 11.8618)
		(end 84.0232 11.7094)
		(width 0.188697)
		(layer "In7.Cu")
		(net "DDR0_32A_A10")
	)
	(segment
		(start 81.8134 9.398)
		(end 81.8134 11.7094)
		(width 0.188697)
		(layer "In7.Cu")
		(net "DDR0_32A_A10")
	)
	(segment
		(start 78.2828 16.2306)
		(end 76.0984 16.2306)
		(width 0.188697)
		(layer "In7.Cu")
		(net "DDR0_32A_A10")
	)
	(segment
		(start 75.8952 16.0274)
		(end 75.8952 15.875)
		(width 0.188697)
		(layer "In7.Cu")
		(net "DDR0_32A_A10")
	)
	(segment
		(start 79.3242 15.5448)
		(end 78.7908 15.5448)
		(width 0.188697)
		(layer "In7.Cu")
		(net "DDR0_32A_A10")
	)
	(segment
		(start 85.217 16.2306)
		(end 79.756 16.2306)
		(width 0.188697)
		(layer "In7.Cu")
		(net "DDR0_32A_A10")
	)
	(segment
		(start 79.502 15.7226)
		(end 79.3242 15.5448)
		(width 0.188697)
		(layer "In7.Cu")
		(net "DDR0_32A_A10")
	)
	(segment
		(start 71.822691 15.225725)
		(end 71.638973 15.042007)
		(width 0.188697)
		(layer "In7.Cu")
		(net "DDR0_32A_A10")
	)
	(segment
		(start 65.237004 15.042007)
		(end 64.737005 14.542008)
		(width 0.188697)
		(layer "In7.Cu")
		(net "DDR0_32A_A10")
	)
	(segment
		(start 73.244786 15.467965)
		(end 73.228429 15.484323)
		(width 0.188697)
		(layer "In7.Cu")
		(net "DDR0_32A_A10")
	)
	(segment
		(start 84.1756 9.8044)
		(end 85.1662 9.8044)
		(width 0.188697)
		(layer "In7.Cu")
		(net "DDR0_32A_A10")
	)
	(segment
		(start 80.656709 8.763)
		(end 80.656709 9.054109)
		(width 0.188697)
		(layer "In7.Cu")
		(net "DDR0_32A_A10")
	)
	(segment
		(start 71.638973 15.042007)
		(end 65.237004 15.042007)
		(width 0.188697)
		(layer "In7.Cu")
		(net "DDR0_32A_A10")
	)
	(segment
		(start 79.756 16.2306)
		(end 79.502 15.9766)
		(width 0.188697)
		(layer "In7.Cu")
		(net "DDR0_32A_A10")
	)
	(segment
		(start 75.5142 15.494)
		(end 75.325681 15.494)
		(width 0.188697)
		(layer "In7.Cu")
		(net "DDR0_32A_A10")
	)
	(segment
		(start 80.250995 6.698996)
		(end 80.656709 7.10471)
		(width 0.12065)
		(layer "In7.Cu")
		(net "DDR0_32A_A10")
	)
	(segment
		(start 80.656709 9.054109)
		(end 80.8482 9.2456)
		(width 0.188697)
		(layer "In7.Cu")
		(net "DDR0_32A_A10")
	)
	(segment
		(start 80.8482 9.2456)
		(end 81.661 9.2456)
		(width 0.188697)
		(layer "In7.Cu")
		(net "DDR0_32A_A10")
	)
	(segment
		(start 81.661 9.2456)
		(end 81.8134 9.398)
		(width 0.188697)
		(layer "In7.Cu")
		(net "DDR0_32A_A10")
	)
	(segment
		(start 65.737003 9.541993)
		(end 65.237004 10.041992)
		(width 0.233528)
		(layer "F.Cu")
		(net "DDR0_32A_A9")
	)
	(segment
		(start 83.450989 26.262889)
		(end 83.450989 25.813004)
		(width 0.14732)
		(layer "F.Cu")
		(net "DDR0_32A_A9")
	)
	(segment
		(start 83.693 26.5049)
		(end 83.450989 26.262889)
		(width 0.14732)
		(layer "F.Cu")
		(net "DDR0_32A_A9")
	)
	(via
		(at 65.737003 9.541993)
		(size 0.4826)
		(drill 0.25654)
		(layers "F.Cu" "B.Cu")
		(net "DDR0_32A_A9")
	)
	(segment
		(start 83.05099 26.213003)
		(end 83.450989 25.813004)
		(width 0.14732)
		(layer "B.Cu")
		(net "DDR0_32A_A9")
	)
	(segment
		(start 83.05099 14.656003)
		(end 83.450989 14.256004)
		(width 0.14732)
		(layer "B.Cu")
		(net "DDR0_32A_A9")
	)
	(segment
		(start 83.05099 3.099003)
		(end 83.450989 2.699004)
		(width 0.14732)
		(layer "B.Cu")
		(net "DDR0_32A_A9")
	)
	(segment
		(start 74.498403 4.241622)
		(end 74.3204 4.419625)
		(width 0.188697)
		(layer "In2.Cu")
		(net "DDR0_32A_A9")
	)
	(segment
		(start 77.8764 0.8636)
		(end 77.8764 4.3942)
		(width 0.188697)
		(layer "In2.Cu")
		(net "DDR0_32A_A9")
	)
	(segment
		(start 77.228421 0.670687)
		(end 77.233882 0.676148)
		(width 0.188697)
		(layer "In2.Cu")
		(net "DDR0_32A_A9")
	)
	(segment
		(start 77.6732 4.5974)
		(end 77.0636 4.5974)
		(width 0.188697)
		(layer "In2.Cu")
		(net "DDR0_32A_A9")
	)
	(segment
		(start 66.237002 9.041994)
		(end 66.237002 3.358998)
		(width 0.188697)
		(layer "In2.Cu")
		(net "DDR0_32A_A9")
	)
	(segment
		(start 83.273189 3.175)
		(end 83.450989 2.9972)
		(width 0.188697)
		(layer "In2.Cu")
		(net "DDR0_32A_A9")
	)
	(segment
		(start 77.0636 4.5974)
		(end 76.835 4.3688)
		(width 0.188697)
		(layer "In2.Cu")
		(net "DDR0_32A_A9")
	)
	(segment
		(start 81.8134 3.3528)
		(end 81.9912 3.175)
		(width 0.188697)
		(layer "In2.Cu")
		(net "DDR0_32A_A9")
	)
	(segment
		(start 81.8134 5.0038)
		(end 81.8134 3.3528)
		(width 0.188697)
		(layer "In2.Cu")
		(net "DDR0_32A_A9")
	)
	(segment
		(start 78.8924 5.1816)
		(end 81.6356 5.1816)
		(width 0.188697)
		(layer "In2.Cu")
		(net "DDR0_32A_A9")
	)
	(segment
		(start 75.295582 3.937)
		(end 74.99096 4.241622)
		(width 0.188697)
		(layer "In2.Cu")
		(net "DDR0_32A_A9")
	)
	(segment
		(start 65.737003 9.541993)
		(end 66.237002 9.041994)
		(width 0.188697)
		(layer "In2.Cu")
		(net "DDR0_32A_A9")
	)
	(segment
		(start 76.5302 3.937)
		(end 75.295582 3.937)
		(width 0.188697)
		(layer "In2.Cu")
		(net "DDR0_32A_A9")
	)
	(segment
		(start 72.068131 0.676148)
		(end 72.073592 0.670687)
		(width 0.188697)
		(layer "In2.Cu")
		(net "DDR0_32A_A9")
	)
	(segment
		(start 74.549 6.223)
		(end 77.851 6.223)
		(width 0.188697)
		(layer "In2.Cu")
		(net "DDR0_32A_A9")
	)
	(segment
		(start 74.3204 5.9944)
		(end 74.549 6.223)
		(width 0.188697)
		(layer "In2.Cu")
		(net "DDR0_32A_A9")
	)
	(segment
		(start 74.3204 4.419625)
		(end 74.3204 5.9944)
		(width 0.188697)
		(layer "In2.Cu")
		(net "DDR0_32A_A9")
	)
	(segment
		(start 74.99096 4.241622)
		(end 74.498403 4.241622)
		(width 0.188697)
		(layer "In2.Cu")
		(net "DDR0_32A_A9")
	)
	(segment
		(start 76.835 4.2418)
		(end 76.5302 3.937)
		(width 0.188697)
		(layer "In2.Cu")
		(net "DDR0_32A_A9")
	)
	(segment
		(start 72.073592 0.670687)
		(end 77.228421 0.670687)
		(width 0.188697)
		(layer "In2.Cu")
		(net "DDR0_32A_A9")
	)
	(segment
		(start 77.233882 0.676148)
		(end 77.688948 0.676148)
		(width 0.188697)
		(layer "In2.Cu")
		(net "DDR0_32A_A9")
	)
	(segment
		(start 77.851 6.223)
		(end 78.8924 5.1816)
		(width 0.188697)
		(layer "In2.Cu")
		(net "DDR0_32A_A9")
	)
	(segment
		(start 81.9912 3.175)
		(end 83.273189 3.175)
		(width 0.188697)
		(layer "In2.Cu")
		(net "DDR0_32A_A9")
	)
	(segment
		(start 81.6356 5.1816)
		(end 81.8134 5.0038)
		(width 0.188697)
		(layer "In2.Cu")
		(net "DDR0_32A_A9")
	)
	(segment
		(start 77.688948 0.676148)
		(end 77.8764 0.8636)
		(width 0.188697)
		(layer "In2.Cu")
		(net "DDR0_32A_A9")
	)
	(segment
		(start 83.450989 2.9972)
		(end 83.450989 2.699004)
		(width 0.188697)
		(layer "In2.Cu")
		(net "DDR0_32A_A9")
	)
	(segment
		(start 66.237002 3.358998)
		(end 68.919852 0.676148)
		(width 0.188697)
		(layer "In2.Cu")
		(net "DDR0_32A_A9")
	)
	(segment
		(start 68.919852 0.676148)
		(end 72.068131 0.676148)
		(width 0.188697)
		(layer "In2.Cu")
		(net "DDR0_32A_A9")
	)
	(segment
		(start 77.8764 4.3942)
		(end 77.6732 4.5974)
		(width 0.188697)
		(layer "In2.Cu")
		(net "DDR0_32A_A9")
	)
	(segment
		(start 76.835 4.3688)
		(end 76.835 4.2418)
		(width 0.188697)
		(layer "In2.Cu")
		(net "DDR0_32A_A9")
	)
	(segment
		(start 83.845273 13.86172)
		(end 83.845273 3.093288)
		(width 0.12065)
		(layer "In6.Cu")
		(net "DDR0_32A_A9")
	)
	(segment
		(start 83.845273 14.650288)
		(end 83.450989 14.256004)
		(width 0.12065)
		(layer "In6.Cu")
		(net "DDR0_32A_A9")
	)
	(segment
		(start 83.845273 25.41872)
		(end 83.845273 14.650288)
		(width 0.12065)
		(layer "In6.Cu")
		(net "DDR0_32A_A9")
	)
	(segment
		(start 83.845273 3.093288)
		(end 83.450989 2.699004)
		(width 0.12065)
		(layer "In6.Cu")
		(net "DDR0_32A_A9")
	)
	(segment
		(start 83.450989 14.256004)
		(end 83.845273 13.86172)
		(width 0.12065)
		(layer "In6.Cu")
		(net "DDR0_32A_A9")
	)
	(segment
		(start 83.450989 25.813004)
		(end 83.845273 25.41872)
		(width 0.12065)
		(layer "In6.Cu")
		(net "DDR0_32A_A9")
	)
	(segment
		(start 84.250987 30.612994)
		(end 84.777986 31.139994)
		(width 0.14732)
		(layer "F.Cu")
		(net "DDR0_32A_A8")
	)
	(segment
		(start 84.777986 31.139994)
		(end 84.777986 31.961328)
		(width 0.14732)
		(layer "F.Cu")
		(net "DDR0_32A_A8")
	)
	(segment
		(start 64.737005 9.541993)
		(end 64.237006 10.041992)
		(width 0.233528)
		(layer "F.Cu")
		(net "DDR0_32A_A8")
	)
	(segment
		(start 84.777986 31.961328)
		(end 84.582 32.157314)
		(width 0.14732)
		(layer "F.Cu")
		(net "DDR0_32A_A8")
	)
	(via
		(at 64.737005 9.541993)
		(size 0.4826)
		(drill 0.20574)
		(layers "F.Cu" "B.Cu")
		(net "DDR0_32A_A8")
	)
	(segment
		(start 83.850988 18.655995)
		(end 84.250987 19.055994)
		(width 0.14732)
		(layer "B.Cu")
		(net "DDR0_32A_A8")
	)
	(segment
		(start 83.850988 7.098995)
		(end 84.250987 7.498994)
		(width 0.14732)
		(layer "B.Cu")
		(net "DDR0_32A_A8")
	)
	(segment
		(start 83.850988 30.212995)
		(end 84.250987 30.612994)
		(width 0.14732)
		(layer "B.Cu")
		(net "DDR0_32A_A8")
	)
	(segment
		(start 84.709432 19.514439)
		(end 84.250987 19.055994)
		(width 0.12065)
		(layer "In2.Cu")
		(net "DDR0_32A_A8")
	)
	(segment
		(start 84.250987 19.055994)
		(end 84.65091 18.656071)
		(width 0.12065)
		(layer "In2.Cu")
		(net "DDR0_32A_A8")
	)
	(segment
		(start 84.250987 30.612994)
		(end 84.709432 30.15455)
		(width 0.12065)
		(layer "In2.Cu")
		(net "DDR0_32A_A8")
	)
	(segment
		(start 84.65091 18.656071)
		(end 84.65091 7.898917)
		(width 0.12065)
		(layer "In2.Cu")
		(net "DDR0_32A_A8")
	)
	(segment
		(start 84.709432 30.15455)
		(end 84.709432 19.514439)
		(width 0.12065)
		(layer "In2.Cu")
		(net "DDR0_32A_A8")
	)
	(segment
		(start 84.65091 7.898917)
		(end 84.250987 7.498994)
		(width 0.12065)
		(layer "In2.Cu")
		(net "DDR0_32A_A8")
	)
	(segment
		(start 65.516404 8.041996)
		(end 69.059196 8.041996)
		(width 0.188697)
		(layer "In7.Cu")
		(net "DDR0_32A_A8")
	)
	(segment
		(start 86.995 5.121656)
		(end 86.995 5.5372)
		(width 0.188697)
		(layer "In7.Cu")
		(net "DDR0_32A_A8")
	)
	(segment
		(start 75.437746 4.241622)
		(end 75.514124 4.318)
		(width 0.188697)
		(layer "In7.Cu")
		(net "DDR0_32A_A8")
	)
	(segment
		(start 77.4954 3.5306)
		(end 81.4578 3.5306)
		(width 0.188697)
		(layer "In7.Cu")
		(net "DDR0_32A_A8")
	)
	(segment
		(start 77.0636 4.318)
		(end 77.3176 4.064)
		(width 0.188697)
		(layer "In7.Cu")
		(net "DDR0_32A_A8")
	)
	(segment
		(start 75.514124 4.318)
		(end 77.0636 4.318)
		(width 0.188697)
		(layer "In7.Cu")
		(net "DDR0_32A_A8")
	)
	(segment
		(start 86.3092 6.223)
		(end 84.023073 6.223)
		(width 0.188697)
		(layer "In7.Cu")
		(net "DDR0_32A_A8")
	)
	(segment
		(start 64.737005 8.821395)
		(end 65.516404 8.041996)
		(width 0.188697)
		(layer "In7.Cu")
		(net "DDR0_32A_A8")
	)
	(segment
		(start 74.091876 4.318)
		(end 74.168254 4.241622)
		(width 0.188697)
		(layer "In7.Cu")
		(net "DDR0_32A_A8")
	)
	(segment
		(start 69.236996 5.151603)
		(end 69.409335 4.979264)
		(width 0.188697)
		(layer "In7.Cu")
		(net "DDR0_32A_A8")
	)
	(segment
		(start 71.628025 4.318)
		(end 74.091876 4.318)
		(width 0.188697)
		(layer "In7.Cu")
		(net "DDR0_32A_A8")
	)
	(segment
		(start 71.374025 4.064)
		(end 71.628025 4.318)
		(width 0.188697)
		(layer "In7.Cu")
		(net "DDR0_32A_A8")
	)
	(segment
		(start 77.3176 4.064)
		(end 77.3176 3.7084)
		(width 0.188697)
		(layer "In7.Cu")
		(net "DDR0_32A_A8")
	)
	(segment
		(start 86.8172 0.2286)
		(end 86.995 0.4064)
		(width 0.188697)
		(layer "In7.Cu")
		(net "DDR0_32A_A8")
	)
	(segment
		(start 74.168254 4.241622)
		(end 75.437746 4.241622)
		(width 0.188697)
		(layer "In7.Cu")
		(net "DDR0_32A_A8")
	)
	(segment
		(start 69.409335 4.979264)
		(end 69.918123 4.979264)
		(width 0.188697)
		(layer "In7.Cu")
		(net "DDR0_32A_A8")
	)
	(segment
		(start 83.845273 6.850913)
		(end 84.250987 7.256628)
		(width 0.12065)
		(layer "In7.Cu")
		(net "DDR0_32A_A8")
	)
	(segment
		(start 84.455 3.175)
		(end 84.709 2.921)
		(width 0.188697)
		(layer "In7.Cu")
		(net "DDR0_32A_A8")
	)
	(segment
		(start 84.9122 0.2286)
		(end 86.8172 0.2286)
		(width 0.188697)
		(layer "In7.Cu")
		(net "DDR0_32A_A8")
	)
	(segment
		(start 77.3176 3.7084)
		(end 77.4954 3.5306)
		(width 0.188697)
		(layer "In7.Cu")
		(net "DDR0_32A_A8")
	)
	(segment
		(start 81.4578 3.5306)
		(end 81.8134 3.175)
		(width 0.188697)
		(layer "In7.Cu")
		(net "DDR0_32A_A8")
	)
	(segment
		(start 69.059196 8.041996)
		(end 69.236996 7.864196)
		(width 0.188697)
		(layer "In7.Cu")
		(net "DDR0_32A_A8")
	)
	(segment
		(start 70.174256 4.72313)
		(end 70.174256 4.282542)
		(width 0.188697)
		(layer "In7.Cu")
		(net "DDR0_32A_A8")
	)
	(segment
		(start 83.845273 6.4008)
		(end 83.845273 6.850913)
		(width 0.12065)
		(layer "In7.Cu")
		(net "DDR0_32A_A8")
	)
	(segment
		(start 70.392798 4.064)
		(end 71.374025 4.064)
		(width 0.188697)
		(layer "In7.Cu")
		(net "DDR0_32A_A8")
	)
	(segment
		(start 81.8134 3.175)
		(end 84.455 3.175)
		(width 0.188697)
		(layer "In7.Cu")
		(net "DDR0_32A_A8")
	)
	(segment
		(start 86.995 1.660144)
		(end 87.005897 1.671041)
		(width 0.188697)
		(layer "In7.Cu")
		(net "DDR0_32A_A8")
	)
	(segment
		(start 86.995 5.5372)
		(end 86.3092 6.223)
		(width 0.188697)
		(layer "In7.Cu")
		(net "DDR0_32A_A8")
	)
	(segment
		(start 86.995 0.4064)
		(end 86.995 1.660144)
		(width 0.188697)
		(layer "In7.Cu")
		(net "DDR0_32A_A8")
	)
	(segment
		(start 84.709 0.4318)
		(end 84.9122 0.2286)
		(width 0.188697)
		(layer "In7.Cu")
		(net "DDR0_32A_A8")
	)
	(segment
		(start 84.250987 7.256628)
		(end 84.250987 7.498994)
		(width 0.12065)
		(layer "In7.Cu")
		(net "DDR0_32A_A8")
	)
	(segment
		(start 69.236996 7.864196)
		(end 69.236996 5.151603)
		(width 0.188697)
		(layer "In7.Cu")
		(net "DDR0_32A_A8")
	)
	(segment
		(start 70.174256 4.282542)
		(end 70.392798 4.064)
		(width 0.188697)
		(layer "In7.Cu")
		(net "DDR0_32A_A8")
	)
	(segment
		(start 84.709 2.921)
		(end 84.709 0.4318)
		(width 0.188697)
		(layer "In7.Cu")
		(net "DDR0_32A_A8")
	)
	(segment
		(start 69.918123 4.979264)
		(end 70.174256 4.72313)
		(width 0.188697)
		(layer "In7.Cu")
		(net "DDR0_32A_A8")
	)
	(segment
		(start 84.023073 6.223)
		(end 83.845273 6.4008)
		(width 0.188697)
		(layer "In7.Cu")
		(net "DDR0_32A_A8")
	)
	(segment
		(start 64.737005 9.541993)
		(end 64.737005 8.821395)
		(width 0.188697)
		(layer "In7.Cu")
		(net "DDR0_32A_A8")
	)
	(segment
		(start 87.005897 1.671041)
		(end 87.005897 5.110759)
		(width 0.188697)
		(layer "In7.Cu")
		(net "DDR0_32A_A8")
	)
	(segment
		(start 87.005897 5.110759)
		(end 86.995 5.121656)
		(width 0.188697)
		(layer "In7.Cu")
		(net "DDR0_32A_A8")
	)
	(segment
		(start 84.6328 23.4061)
		(end 84.4931 23.4061)
		(width 0.14732)
		(layer "F.Cu")
		(net "DDR0_32A_A7")
	)
	(segment
		(start 84.4931 23.4061)
		(end 84.836 23.749)
		(width 0.14732)
		(layer "F.Cu")
		(net "DDR0_32A_A7")
	)
	(segment
		(start 83.626477 25.013006)
		(end 83.450989 25.013006)
		(width 0.14732)
		(layer "F.Cu")
		(net "DDR0_32A_A7")
	)
	(segment
		(start 62.737009 20.541996)
		(end 62.23701 20.041997)
		(width 0.233528)
		(layer "F.Cu")
		(net "DDR0_32A_A7")
	)
	(segment
		(start 84.836 24.257)
		(end 84.509254 24.583746)
		(width 0.14732)
		(layer "F.Cu")
		(net "DDR0_32A_A7")
	)
	(segment
		(start 84.055737 24.583746)
		(end 83.626477 25.013006)
		(width 0.14732)
		(layer "F.Cu")
		(net "DDR0_32A_A7")
	)
	(segment
		(start 84.509254 24.583746)
		(end 84.055737 24.583746)
		(width 0.14732)
		(layer "F.Cu")
		(net "DDR0_32A_A7")
	)
	(segment
		(start 84.836 23.749)
		(end 84.836 24.257)
		(width 0.14732)
		(layer "F.Cu")
		(net "DDR0_32A_A7")
	)
	(via
		(at 62.737009 20.541996)
		(size 0.4826)
		(drill 0.25654)
		(layers "F.Cu" "B.Cu")
		(net "DDR0_32A_A7")
	)
	(segment
		(start 83.05099 25.413005)
		(end 83.450989 25.013006)
		(width 0.14732)
		(layer "B.Cu")
		(net "DDR0_32A_A7")
	)
	(segment
		(start 83.05099 13.856005)
		(end 83.450989 13.456006)
		(width 0.14732)
		(layer "B.Cu")
		(net "DDR0_32A_A7")
	)
	(segment
		(start 83.05099 2.299005)
		(end 83.450989 1.899006)
		(width 0.14732)
		(layer "B.Cu")
		(net "DDR0_32A_A7")
	)
	(segment
		(start 83.056705 13.85029)
		(end 83.450989 13.456006)
		(width 0.12065)
		(layer "In6.Cu")
		(net "DDR0_32A_A7")
	)
	(segment
		(start 83.056705 2.401164)
		(end 83.292925 2.164944)
		(width 0.12065)
		(layer "In6.Cu")
		(net "DDR0_32A_A7")
	)
	(segment
		(start 83.450989 13.456006)
		(end 83.056705 13.061721)
		(width 0.12065)
		(layer "In6.Cu")
		(net "DDR0_32A_A7")
	)
	(segment
		(start 83.056705 24.618721)
		(end 83.056705 13.85029)
		(width 0.12065)
		(layer "In6.Cu")
		(net "DDR0_32A_A7")
	)
	(segment
		(start 83.292925 2.05707)
		(end 83.450989 1.899006)
		(width 0.12065)
		(layer "In6.Cu")
		(net "DDR0_32A_A7")
	)
	(segment
		(start 83.450989 25.013006)
		(end 83.056705 24.618721)
		(width 0.12065)
		(layer "In6.Cu")
		(net "DDR0_32A_A7")
	)
	(segment
		(start 83.292925 2.164944)
		(end 83.292925 2.05707)
		(width 0.12065)
		(layer "In6.Cu")
		(net "DDR0_32A_A7")
	)
	(segment
		(start 83.056705 13.061721)
		(end 83.056705 2.401164)
		(width 0.12065)
		(layer "In6.Cu")
		(net "DDR0_32A_A7")
	)
	(segment
		(start 62.174272 8.691728)
		(end 62.23 8.636)
		(width 0.188697)
		(layer "In7.Cu")
		(net "DDR0_32A_A7")
	)
	(segment
		(start 61.214 19.304)
		(end 60.299727 18.389727)
		(width 0.188697)
		(layer "In7.Cu")
		(net "DDR0_32A_A7")
	)
	(segment
		(start 70.414312 0.254)
		(end 82.092063 0.254)
		(width 0.188697)
		(layer "In7.Cu")
		(net "DDR0_32A_A7")
	)
	(segment
		(start 63.17427 7.43773)
		(end 67.632732 2.979268)
		(width 0.188697)
		(layer "In7.Cu")
		(net "DDR0_32A_A7")
	)
	(segment
		(start 62.737009 20.541996)
		(end 62.103 20.541996)
		(width 0.188697)
		(layer "In7.Cu")
		(net "DDR0_32A_A7")
	)
	(segment
		(start 83.057365 0.634365)
		(end 83.057365 0.635635)
		(width 0.188697)
		(layer "In7.Cu")
		(net "DDR0_32A_A7")
	)
	(segment
		(start 63.17427 7.723124)
		(end 63.17427 7.43773)
		(width 0.188697)
		(layer "In7.Cu")
		(net "DDR0_32A_A7")
	)
	(segment
		(start 68.563566 2.104746)
		(end 70.414312 0.254)
		(width 0.188697)
		(layer "In7.Cu")
		(net "DDR0_32A_A7")
	)
	(segment
		(start 68.17426 2.494051)
		(end 68.299736 2.368575)
		(width 0.188697)
		(layer "In7.Cu")
		(net "DDR0_32A_A7")
	)
	(segment
		(start 62.23 8.636)
		(end 62.23 8.382)
		(width 0.188697)
		(layer "In7.Cu")
		(net "DDR0_32A_A7")
	)
	(segment
		(start 68.299736 2.360879)
		(end 68.55587 2.104746)
		(width 0.188697)
		(layer "In7.Cu")
		(net "DDR0_32A_A7")
	)
	(segment
		(start 61.174249 9.72312)
		(end 61.174249 9.437751)
		(width 0.188697)
		(layer "In7.Cu")
		(net "DDR0_32A_A7")
	)
	(segment
		(start 83.056705 1.504721)
		(end 83.450989 1.899006)
		(width 0.12065)
		(layer "In7.Cu")
		(net "DDR0_32A_A7")
	)
	(segment
		(start 60.555861 10.10473)
		(end 60.563557 10.10473)
		(width 0.188697)
		(layer "In7.Cu")
		(net "DDR0_32A_A7")
	)
	(segment
		(start 60.689033 9.979254)
		(end 60.918115 9.979254)
		(width 0.188697)
		(layer "In7.Cu")
		(net "DDR0_32A_A7")
	)
	(segment
		(start 82.804 0.381)
		(end 83.057365 0.634365)
		(width 0.188697)
		(layer "In7.Cu")
		(net "DDR0_32A_A7")
	)
	(segment
		(start 83.057365 0.635635)
		(end 83.056705 0.636295)
		(width 0.12065)
		(layer "In7.Cu")
		(net "DDR0_32A_A7")
	)
	(segment
		(start 62.632742 7.979258)
		(end 62.918137 7.979258)
		(width 0.188697)
		(layer "In7.Cu")
		(net "DDR0_32A_A7")
	)
	(segment
		(start 60.299727 18.389727)
		(end 60.299727 10.360863)
		(width 0.188697)
		(layer "In7.Cu")
		(net "DDR0_32A_A7")
	)
	(segment
		(start 60.563557 10.10473)
		(end 60.689033 9.979254)
		(width 0.188697)
		(layer "In7.Cu")
		(net "DDR0_32A_A7")
	)
	(segment
		(start 83.056705 0.636295)
		(end 83.056705 1.504721)
		(width 0.12065)
		(layer "In7.Cu")
		(net "DDR0_32A_A7")
	)
	(segment
		(start 62.103 20.541996)
		(end 61.214 19.652996)
		(width 0.188697)
		(layer "In7.Cu")
		(net "DDR0_32A_A7")
	)
	(segment
		(start 60.918115 9.979254)
		(end 61.174249 9.72312)
		(width 0.188697)
		(layer "In7.Cu")
		(net "DDR0_32A_A7")
	)
	(segment
		(start 62.918137 7.979258)
		(end 63.17427 7.723124)
		(width 0.188697)
		(layer "In7.Cu")
		(net "DDR0_32A_A7")
	)
	(segment
		(start 62.23 8.382)
		(end 62.632742 7.979258)
		(width 0.188697)
		(layer "In7.Cu")
		(net "DDR0_32A_A7")
	)
	(segment
		(start 67.632732 2.979268)
		(end 67.918127 2.979268)
		(width 0.188697)
		(layer "In7.Cu")
		(net "DDR0_32A_A7")
	)
	(segment
		(start 61.918139 8.979256)
		(end 62.174272 8.723122)
		(width 0.188697)
		(layer "In7.Cu")
		(net "DDR0_32A_A7")
	)
	(segment
		(start 82.092063 0.254)
		(end 82.219063 0.381)
		(width 0.188697)
		(layer "In7.Cu")
		(net "DDR0_32A_A7")
	)
	(segment
		(start 82.219063 0.381)
		(end 82.804 0.381)
		(width 0.188697)
		(layer "In7.Cu")
		(net "DDR0_32A_A7")
	)
	(segment
		(start 60.299727 10.360863)
		(end 60.555861 10.10473)
		(width 0.188697)
		(layer "In7.Cu")
		(net "DDR0_32A_A7")
	)
	(segment
		(start 67.918127 2.979268)
		(end 68.17426 2.723134)
		(width 0.188697)
		(layer "In7.Cu")
		(net "DDR0_32A_A7")
	)
	(segment
		(start 68.17426 2.723134)
		(end 68.17426 2.494051)
		(width 0.188697)
		(layer "In7.Cu")
		(net "DDR0_32A_A7")
	)
	(segment
		(start 68.55587 2.104746)
		(end 68.563566 2.104746)
		(width 0.188697)
		(layer "In7.Cu")
		(net "DDR0_32A_A7")
	)
	(segment
		(start 61.214 19.652996)
		(end 61.214 19.304)
		(width 0.188697)
		(layer "In7.Cu")
		(net "DDR0_32A_A7")
	)
	(segment
		(start 61.632744 8.979256)
		(end 61.918139 8.979256)
		(width 0.188697)
		(layer "In7.Cu")
		(net "DDR0_32A_A7")
	)
	(segment
		(start 61.174249 9.437751)
		(end 61.632744 8.979256)
		(width 0.188697)
		(layer "In7.Cu")
		(net "DDR0_32A_A7")
	)
	(segment
		(start 62.174272 8.723122)
		(end 62.174272 8.691728)
		(width 0.188697)
		(layer "In7.Cu")
		(net "DDR0_32A_A7")
	)
	(segment
		(start 68.299736 2.368575)
		(end 68.299736 2.360879)
		(width 0.188697)
		(layer "In7.Cu")
		(net "DDR0_32A_A7")
	)
	(segment
		(start 64.737005 10.541991)
		(end 64.237006 11.04199)
		(width 0.233528)
		(layer "F.Cu")
		(net "DDR0_32A_A6")
	)
	(segment
		(start 83.450989 30.745989)
		(end 83.93877 31.23377)
		(width 0.14732)
		(layer "F.Cu")
		(net "DDR0_32A_A6")
	)
	(segment
		(start 83.450989 30.612994)
		(end 83.450989 30.745989)
		(width 0.14732)
		(layer "F.Cu")
		(net "DDR0_32A_A6")
	)
	(segment
		(start 83.93877 31.23377)
		(end 83.93877 31.911544)
		(width 0.14732)
		(layer "F.Cu")
		(net "DDR0_32A_A6")
	)
	(segment
		(start 83.93877 31.911544)
		(end 83.693 32.157314)
		(width 0.14732)
		(layer "F.Cu")
		(net "DDR0_32A_A6")
	)
	(via
		(at 64.737005 10.541991)
		(size 0.4826)
		(drill 0.25654)
		(layers "F.Cu" "B.Cu")
		(net "DDR0_32A_A6")
	)
	(segment
		(start 83.05099 18.655995)
		(end 83.450989 19.055994)
		(width 0.14732)
		(layer "B.Cu")
		(net "DDR0_32A_A6")
	)
	(segment
		(start 83.05099 30.212995)
		(end 83.450989 30.612994)
		(width 0.14732)
		(layer "B.Cu")
		(net "DDR0_32A_A6")
	)
	(segment
		(start 83.05099 7.098995)
		(end 83.450989 7.498994)
		(width 0.14732)
		(layer "B.Cu")
		(net "DDR0_32A_A6")
	)
	(segment
		(start 83.850912 19.455917)
		(end 83.450989 19.055994)
		(width 0.12065)
		(layer "In2.Cu")
		(net "DDR0_32A_A6")
	)
	(segment
		(start 83.450989 19.055994)
		(end 83.850912 18.656071)
		(width 0.12065)
		(layer "In2.Cu")
		(net "DDR0_32A_A6")
	)
	(segment
		(start 83.450989 30.612994)
		(end 83.850912 30.213071)
		(width 0.12065)
		(layer "In2.Cu")
		(net "DDR0_32A_A6")
	)
	(segment
		(start 83.850912 30.213071)
		(end 83.850912 19.455917)
		(width 0.12065)
		(layer "In2.Cu")
		(net "DDR0_32A_A6")
	)
	(segment
		(start 83.850912 18.656071)
		(end 83.850912 7.898917)
		(width 0.12065)
		(layer "In2.Cu")
		(net "DDR0_32A_A6")
	)
	(segment
		(start 83.850912 7.898917)
		(end 83.450989 7.498994)
		(width 0.12065)
		(layer "In2.Cu")
		(net "DDR0_32A_A6")
	)
	(segment
		(start 77.6732 4.5212)
		(end 77.6732 4.0894)
		(width 0.188697)
		(layer "In7.Cu")
		(net "DDR0_32A_A6")
	)
	(segment
		(start 65.557806 9.041994)
		(end 69.952032 9.041994)
		(width 0.188697)
		(layer "In7.Cu")
		(net "DDR0_32A_A6")
	)
	(segment
		(start 86.262972 5.715)
		(end 85.847428 5.715)
		(width 0.188697)
		(layer "In7.Cu")
		(net "DDR0_32A_A6")
	)
	(segment
		(start 65.2526 9.3472)
		(end 65.557806 9.041994)
		(width 0.188697)
		(layer "In7.Cu")
		(net "DDR0_32A_A6")
	)
	(segment
		(start 70.866 5.08)
		(end 71.247 4.699)
		(width 0.188697)
		(layer "In7.Cu")
		(net "DDR0_32A_A6")
	)
	(segment
		(start 77.851 3.9116)
		(end 81.6102 3.9116)
		(width 0.188697)
		(layer "In7.Cu")
		(net "DDR0_32A_A6")
	)
	(segment
		(start 85.1916 0.635)
		(end 86.4616 0.635)
		(width 0.188697)
		(layer "In7.Cu")
		(net "DDR0_32A_A6")
	)
	(segment
		(start 86.603103 0.776503)
		(end 86.603103 1.822475)
		(width 0.188697)
		(layer "In7.Cu")
		(net "DDR0_32A_A6")
	)
	(segment
		(start 83.056705 6.862343)
		(end 83.450989 7.256628)
		(width 0.12065)
		(layer "In7.Cu")
		(net "DDR0_32A_A6")
	)
	(segment
		(start 86.614 4.948428)
		(end 86.603103 4.959325)
		(width 0.188697)
		(layer "In7.Cu")
		(net "DDR0_32A_A6")
	)
	(segment
		(start 86.603103 4.959325)
		(end 86.603103 5.374869)
		(width 0.188697)
		(layer "In7.Cu")
		(net "DDR0_32A_A6")
	)
	(segment
		(start 81.9912 3.5306)
		(end 84.8106 3.5306)
		(width 0.188697)
		(layer "In7.Cu")
		(net "DDR0_32A_A6")
	)
	(segment
		(start 69.952032 9.041994)
		(end 70.236994 8.757031)
		(width 0.188697)
		(layer "In7.Cu")
		(net "DDR0_32A_A6")
	)
	(segment
		(start 86.603103 5.374869)
		(end 86.262972 5.715)
		(width 0.188697)
		(layer "In7.Cu")
		(net "DDR0_32A_A6")
	)
	(segment
		(start 86.603103 1.822475)
		(end 86.614 1.833372)
		(width 0.188697)
		(layer "In7.Cu")
		(net "DDR0_32A_A6")
	)
	(segment
		(start 85.745828 5.8166)
		(end 84.583321 5.8166)
		(width 0.188697)
		(layer "In7.Cu")
		(net "DDR0_32A_A6")
	)
	(segment
		(start 84.8106 3.5306)
		(end 85.0392 3.302)
		(width 0.188697)
		(layer "In7.Cu")
		(net "DDR0_32A_A6")
	)
	(segment
		(start 64.737005 10.541991)
		(end 65.2526 10.026396)
		(width 0.188697)
		(layer "In7.Cu")
		(net "DDR0_32A_A6")
	)
	(segment
		(start 84.44164 5.7404)
		(end 84.41624 5.715)
		(width 0.188697)
		(layer "In7.Cu")
		(net "DDR0_32A_A6")
	)
	(segment
		(start 65.2526 10.026396)
		(end 65.2526 9.3472)
		(width 0.188697)
		(layer "In7.Cu")
		(net "DDR0_32A_A6")
	)
	(segment
		(start 85.0392 3.302)
		(end 85.0392 0.7874)
		(width 0.188697)
		(layer "In7.Cu")
		(net "DDR0_32A_A6")
	)
	(segment
		(start 86.614 1.833372)
		(end 86.614 4.948428)
		(width 0.188697)
		(layer "In7.Cu")
		(net "DDR0_32A_A6")
	)
	(segment
		(start 85.847428 5.715)
		(end 85.745828 5.8166)
		(width 0.188697)
		(layer "In7.Cu")
		(net "DDR0_32A_A6")
	)
	(segment
		(start 84.507121 5.7404)
		(end 84.44164 5.7404)
		(width 0.188697)
		(layer "In7.Cu")
		(net "DDR0_32A_A6")
	)
	(segment
		(start 70.236994 5.328006)
		(end 70.485 5.08)
		(width 0.188697)
		(layer "In7.Cu")
		(net "DDR0_32A_A6")
	)
	(segment
		(start 77.4954 4.699)
		(end 77.6732 4.5212)
		(width 0.188697)
		(layer "In7.Cu")
		(net "DDR0_32A_A6")
	)
	(segment
		(start 84.583321 5.8166)
		(end 84.507121 5.7404)
		(width 0.188697)
		(layer "In7.Cu")
		(net "DDR0_32A_A6")
	)
	(segment
		(start 71.247 4.699)
		(end 77.4954 4.699)
		(width 0.188697)
		(layer "In7.Cu")
		(net "DDR0_32A_A6")
	)
	(segment
		(start 81.6102 3.9116)
		(end 81.9912 3.5306)
		(width 0.188697)
		(layer "In7.Cu")
		(net "DDR0_32A_A6")
	)
	(segment
		(start 83.056705 6.122721)
		(end 83.056705 6.862343)
		(width 0.12065)
		(layer "In7.Cu")
		(net "DDR0_32A_A6")
	)
	(segment
		(start 84.41624 5.715)
		(end 83.464425 5.715)
		(width 0.188697)
		(layer "In7.Cu")
		(net "DDR0_32A_A6")
	)
	(segment
		(start 85.0392 0.7874)
		(end 85.1916 0.635)
		(width 0.188697)
		(layer "In7.Cu")
		(net "DDR0_32A_A6")
	)
	(segment
		(start 86.4616 0.635)
		(end 86.603103 0.776503)
		(width 0.188697)
		(layer "In7.Cu")
		(net "DDR0_32A_A6")
	)
	(segment
		(start 70.236994 8.757031)
		(end 70.236994 5.328006)
		(width 0.188697)
		(layer "In7.Cu")
		(net "DDR0_32A_A6")
	)
	(segment
		(start 77.6732 4.0894)
		(end 77.851 3.9116)
		(width 0.188697)
		(layer "In7.Cu")
		(net "DDR0_32A_A6")
	)
	(segment
		(start 70.485 5.08)
		(end 70.866 5.08)
		(width 0.188697)
		(layer "In7.Cu")
		(net "DDR0_32A_A6")
	)
	(segment
		(start 83.450989 7.256628)
		(end 83.450989 7.498994)
		(width 0.12065)
		(layer "In7.Cu")
		(net "DDR0_32A_A6")
	)
	(segment
		(start 83.464425 5.715)
		(end 83.056705 6.122721)
		(width 0.188697)
		(layer "In7.Cu")
		(net "DDR0_32A_A6")
	)
	(segment
		(start 83.7438 23.4061)
		(end 83.880249 23.720349)
		(width 0.14732)
		(layer "F.Cu")
		(net "DDR0_32A_A5")
	)
	(segment
		(start 62.737009 19.541998)
		(end 62.23701 19.041999)
		(width 0.233528)
		(layer "F.Cu")
		(net "DDR0_32A_A5")
	)
	(segment
		(start 83.880249 24.343131)
		(end 83.639635 24.583746)
		(width 0.14732)
		(layer "F.Cu")
		(net "DDR0_32A_A5")
	)
	(segment
		(start 83.08025 24.583746)
		(end 82.65099 25.013006)
		(width 0.14732)
		(layer "F.Cu")
		(net "DDR0_32A_A5")
	)
	(segment
		(start 83.639635 24.583746)
		(end 83.08025 24.583746)
		(width 0.14732)
		(layer "F.Cu")
		(net "DDR0_32A_A5")
	)
	(segment
		(start 83.880249 23.720349)
		(end 83.880249 24.343131)
		(width 0.14732)
		(layer "F.Cu")
		(net "DDR0_32A_A5")
	)
	(via
		(at 62.737009 19.541998)
		(size 0.4826)
		(drill 0.25654)
		(layers "F.Cu" "B.Cu")
		(net "DDR0_32A_A5")
	)
	(segment
		(start 82.250991 13.856005)
		(end 82.65099 13.456006)
		(width 0.14732)
		(layer "B.Cu")
		(net "DDR0_32A_A5")
	)
	(segment
		(start 82.250991 25.413005)
		(end 82.65099 25.013006)
		(width 0.14732)
		(layer "B.Cu")
		(net "DDR0_32A_A5")
	)
	(segment
		(start 82.250991 2.299005)
		(end 82.65099 1.899006)
		(width 0.14732)
		(layer "B.Cu")
		(net "DDR0_32A_A5")
	)
	(segment
		(start 82.65099 25.013006)
		(end 82.256706 24.618721)
		(width 0.12065)
		(layer "In6.Cu")
		(net "DDR0_32A_A5")
	)
	(segment
		(start 82.65099 13.456006)
		(end 82.256706 13.061721)
		(width 0.12065)
		(layer "In6.Cu")
		(net "DDR0_32A_A5")
	)
	(segment
		(start 82.256706 2.401164)
		(end 82.492926 2.164944)
		(width 0.12065)
		(layer "In6.Cu")
		(net "DDR0_32A_A5")
	)
	(segment
		(start 82.492926 2.05707)
		(end 82.65099 1.899006)
		(width 0.12065)
		(layer "In6.Cu")
		(net "DDR0_32A_A5")
	)
	(segment
		(start 82.256706 13.061721)
		(end 82.256706 2.401164)
		(width 0.12065)
		(layer "In6.Cu")
		(net "DDR0_32A_A5")
	)
	(segment
		(start 82.492926 2.164944)
		(end 82.492926 2.05707)
		(width 0.12065)
		(layer "In6.Cu")
		(net "DDR0_32A_A5")
	)
	(segment
		(start 82.256706 13.85029)
		(end 82.65099 13.456006)
		(width 0.12065)
		(layer "In6.Cu")
		(net "DDR0_32A_A5")
	)
	(segment
		(start 82.256706 24.618721)
		(end 82.256706 13.85029)
		(width 0.12065)
		(layer "In6.Cu")
		(net "DDR0_32A_A5")
	)
	(segment
		(start 67.550411 4.110203)
		(end 67.555872 4.104742)
		(width 0.188697)
		(layer "In7.Cu")
		(net "DDR0_32A_A5")
	)
	(segment
		(start 70.358 0.9144)
		(end 70.626503 0.645897)
		(width 0.188697)
		(layer "In7.Cu")
		(net "DDR0_32A_A5")
	)
	(segment
		(start 61.521746 9.979254)
		(end 61.918139 9.979254)
		(width 0.188697)
		(layer "In7.Cu")
		(net "DDR0_32A_A5")
	)
	(segment
		(start 71.282458 0.645897)
		(end 71.293355 0.635)
		(width 0.188697)
		(layer "In7.Cu")
		(net "DDR0_32A_A5")
	)
	(segment
		(start 62.534775 18.923)
		(end 61.5442 18.923)
		(width 0.188697)
		(layer "In7.Cu")
		(net "DDR0_32A_A5")
	)
	(segment
		(start 63.690398 7.759802)
		(end 63.690398 7.4295)
		(width 0.188697)
		(layer "In7.Cu")
		(net "DDR0_32A_A5")
	)
	(segment
		(start 68.299736 3.937864)
		(end 68.299736 3.360877)
		(width 0.188697)
		(layer "In7.Cu")
		(net "DDR0_32A_A5")
	)
	(segment
		(start 68.5038 3.022524)
		(end 70.104076 3.022524)
		(width 0.188697)
		(layer "In7.Cu")
		(net "DDR0_32A_A5")
	)
	(segment
		(start 82.103697 0.696697)
		(end 82.169 0.762)
		(width 0.188697)
		(layer "In7.Cu")
		(net "DDR0_32A_A5")
	)
	(segment
		(start 63.246 8.2042)
		(end 63.690398 7.759802)
		(width 0.188697)
		(layer "In7.Cu")
		(net "DDR0_32A_A5")
	)
	(segment
		(start 67.4878 4.110203)
		(end 67.550411 4.110203)
		(width 0.188697)
		(layer "In7.Cu")
		(net "DDR0_32A_A5")
	)
	(segment
		(start 61.214 18.5928)
		(end 61.214 10.287)
		(width 0.188697)
		(layer "In7.Cu")
		(net "DDR0_32A_A5")
	)
	(segment
		(start 70.104076 3.022524)
		(end 70.358 2.7686)
		(width 0.188697)
		(layer "In7.Cu")
		(net "DDR0_32A_A5")
	)
	(segment
		(start 71.293355 0.635)
		(end 82.026582 0.635)
		(width 0.188697)
		(layer "In7.Cu")
		(net "DDR0_32A_A5")
	)
	(segment
		(start 61.5442 18.923)
		(end 61.214 18.5928)
		(width 0.188697)
		(layer "In7.Cu")
		(net "DDR0_32A_A5")
	)
	(segment
		(start 62.737009 19.125235)
		(end 62.534775 18.923)
		(width 0.188697)
		(layer "In7.Cu")
		(net "DDR0_32A_A5")
	)
	(segment
		(start 67.31 4.288003)
		(end 67.4878 4.110203)
		(width 0.188697)
		(layer "In7.Cu")
		(net "DDR0_32A_A5")
	)
	(segment
		(start 62.737009 19.541998)
		(end 62.737009 19.125235)
		(width 0.188697)
		(layer "In7.Cu")
		(net "DDR0_32A_A5")
	)
	(segment
		(start 67.299738 4.360875)
		(end 67.31 4.350614)
		(width 0.188697)
		(layer "In7.Cu")
		(net "DDR0_32A_A5")
	)
	(segment
		(start 63.690398 7.4295)
		(end 64.757198 6.3627)
		(width 0.188697)
		(layer "In7.Cu")
		(net "DDR0_32A_A5")
	)
	(segment
		(start 67.299738 5.723128)
		(end 67.299738 4.360875)
		(width 0.188697)
		(layer "In7.Cu")
		(net "DDR0_32A_A5")
	)
	(segment
		(start 68.326 3.334614)
		(end 68.326 3.200324)
		(width 0.188697)
		(layer "In7.Cu")
		(net "DDR0_32A_A5")
	)
	(segment
		(start 64.757198 6.3627)
		(end 67.114674 6.3627)
		(width 0.188697)
		(layer "In7.Cu")
		(net "DDR0_32A_A5")
	)
	(segment
		(start 63.057303 8.973795)
		(end 63.246 8.785098)
		(width 0.188697)
		(layer "In7.Cu")
		(net "DDR0_32A_A5")
	)
	(segment
		(start 67.31 5.73339)
		(end 67.299738 5.723128)
		(width 0.188697)
		(layer "In7.Cu")
		(net "DDR0_32A_A5")
	)
	(segment
		(start 68.326 3.200324)
		(end 68.5038 3.022524)
		(width 0.188697)
		(layer "In7.Cu")
		(net "DDR0_32A_A5")
	)
	(segment
		(start 68.299736 3.360877)
		(end 68.326 3.334614)
		(width 0.188697)
		(layer "In7.Cu")
		(net "DDR0_32A_A5")
	)
	(segment
		(start 70.626503 0.645897)
		(end 71.282458 0.645897)
		(width 0.188697)
		(layer "In7.Cu")
		(net "DDR0_32A_A5")
	)
	(segment
		(start 67.31 6.167374)
		(end 67.31 5.73339)
		(width 0.188697)
		(layer "In7.Cu")
		(net "DDR0_32A_A5")
	)
	(segment
		(start 62.299748 9.582252)
		(end 62.299748 9.360865)
		(width 0.188697)
		(layer "In7.Cu")
		(net "DDR0_32A_A5")
	)
	(segment
		(start 67.923588 4.110203)
		(end 68.127397 4.110203)
		(width 0.188697)
		(layer "In7.Cu")
		(net "DDR0_32A_A5")
	)
	(segment
		(start 62.305209 9.355404)
		(end 62.305209 9.170391)
		(width 0.188697)
		(layer "In7.Cu")
		(net "DDR0_32A_A5")
	)
	(segment
		(start 67.114674 6.3627)
		(end 67.31 6.167374)
		(width 0.188697)
		(layer "In7.Cu")
		(net "DDR0_32A_A5")
	)
	(segment
		(start 62.923598 8.973795)
		(end 63.057303 8.973795)
		(width 0.188697)
		(layer "In7.Cu")
		(net "DDR0_32A_A5")
	)
	(segment
		(start 82.169 0.762)
		(end 82.245276 0.838276)
		(width 0.12065)
		(layer "In7.Cu")
		(net "DDR0_32A_A5")
	)
	(segment
		(start 82.245276 1.493291)
		(end 82.65099 1.899006)
		(width 0.12065)
		(layer "In7.Cu")
		(net "DDR0_32A_A5")
	)
	(segment
		(start 67.918127 4.104742)
		(end 67.923588 4.110203)
		(width 0.188697)
		(layer "In7.Cu")
		(net "DDR0_32A_A5")
	)
	(segment
		(start 62.496344 8.979256)
		(end 62.918137 8.979256)
		(width 0.188697)
		(layer "In7.Cu")
		(net "DDR0_32A_A5")
	)
	(segment
		(start 82.245276 0.838276)
		(end 82.245276 1.493291)
		(width 0.12065)
		(layer "In7.Cu")
		(net "DDR0_32A_A5")
	)
	(segment
		(start 63.246 8.785098)
		(end 63.246 8.2042)
		(width 0.188697)
		(layer "In7.Cu")
		(net "DDR0_32A_A5")
	)
	(segment
		(start 67.31 4.350614)
		(end 67.31 4.288003)
		(width 0.188697)
		(layer "In7.Cu")
		(net "DDR0_32A_A5")
	)
	(segment
		(start 61.214 10.287)
		(end 61.521746 9.979254)
		(width 0.188697)
		(layer "In7.Cu")
		(net "DDR0_32A_A5")
	)
	(segment
		(start 62.299748 9.360865)
		(end 62.305209 9.355404)
		(width 0.188697)
		(layer "In7.Cu")
		(net "DDR0_32A_A5")
	)
	(segment
		(start 67.555872 4.104742)
		(end 67.918127 4.104742)
		(width 0.188697)
		(layer "In7.Cu")
		(net "DDR0_32A_A5")
	)
	(segment
		(start 82.026582 0.635)
		(end 82.088279 0.696697)
		(width 0.188697)
		(layer "In7.Cu")
		(net "DDR0_32A_A5")
	)
	(segment
		(start 61.918139 9.979254)
		(end 62.174272 9.72312)
		(width 0.188697)
		(layer "In7.Cu")
		(net "DDR0_32A_A5")
	)
	(segment
		(start 70.358 2.7686)
		(end 70.358 0.9144)
		(width 0.188697)
		(layer "In7.Cu")
		(net "DDR0_32A_A5")
	)
	(segment
		(start 62.174272 9.707728)
		(end 62.299748 9.582252)
		(width 0.188697)
		(layer "In7.Cu")
		(net "DDR0_32A_A5")
	)
	(segment
		(start 62.174272 9.72312)
		(end 62.174272 9.707728)
		(width 0.188697)
		(layer "In7.Cu")
		(net "DDR0_32A_A5")
	)
	(segment
		(start 82.088279 0.696697)
		(end 82.103697 0.696697)
		(width 0.188697)
		(layer "In7.Cu")
		(net "DDR0_32A_A5")
	)
	(segment
		(start 68.127397 4.110203)
		(end 68.299736 3.937864)
		(width 0.188697)
		(layer "In7.Cu")
		(net "DDR0_32A_A5")
	)
	(segment
		(start 62.918137 8.979256)
		(end 62.923598 8.973795)
		(width 0.188697)
		(layer "In7.Cu")
		(net "DDR0_32A_A5")
	)
	(segment
		(start 62.305209 9.170391)
		(end 62.496344 8.979256)
		(width 0.188697)
		(layer "In7.Cu")
		(net "DDR0_32A_A5")
	)
	(segment
		(start 63.737007 11.541989)
		(end 63.237008 12.041988)
		(width 0.233528)
		(layer "F.Cu")
		(net "DDR0_32A_A4")
	)
	(segment
		(start 83.08025 31.042254)
		(end 83.08025 31.881064)
		(width 0.14732)
		(layer "F.Cu")
		(net "DDR0_32A_A4")
	)
	(segment
		(start 82.65099 30.612994)
		(end 83.08025 31.042254)
		(width 0.14732)
		(layer "F.Cu")
		(net "DDR0_32A_A4")
	)
	(segment
		(start 83.08025 31.881064)
		(end 82.804 32.157314)
		(width 0.14732)
		(layer "F.Cu")
		(net "DDR0_32A_A4")
	)
	(via
		(at 63.737007 11.541989)
		(size 0.4826)
		(drill 0.20574)
		(layers "F.Cu" "B.Cu")
		(net "DDR0_32A_A4")
	)
	(segment
		(start 82.250991 30.212995)
		(end 82.65099 30.612994)
		(width 0.14732)
		(layer "B.Cu")
		(net "DDR0_32A_A4")
	)
	(segment
		(start 82.250991 18.655995)
		(end 82.65099 19.055994)
		(width 0.14732)
		(layer "B.Cu")
		(net "DDR0_32A_A4")
	)
	(segment
		(start 82.250991 7.098995)
		(end 82.65099 7.498994)
		(width 0.14732)
		(layer "B.Cu")
		(net "DDR0_32A_A4")
	)
	(segment
		(start 82.65099 30.612994)
		(end 83.050913 30.213071)
		(width 0.12065)
		(layer "In2.Cu")
		(net "DDR0_32A_A4")
	)
	(segment
		(start 83.050913 19.455917)
		(end 82.65099 19.055994)
		(width 0.12065)
		(layer "In2.Cu")
		(net "DDR0_32A_A4")
	)
	(segment
		(start 83.050913 30.213071)
		(end 83.050913 19.455917)
		(width 0.12065)
		(layer "In2.Cu")
		(net "DDR0_32A_A4")
	)
	(segment
		(start 82.65099 19.055994)
		(end 83.051066 18.655919)
		(width 0.12065)
		(layer "In2.Cu")
		(net "DDR0_32A_A4")
	)
	(segment
		(start 83.051066 18.655919)
		(end 83.051066 7.89907)
		(width 0.12065)
		(layer "In2.Cu")
		(net "DDR0_32A_A4")
	)
	(segment
		(start 83.051066 7.89907)
		(end 82.65099 7.498994)
		(width 0.12065)
		(layer "In2.Cu")
		(net "DDR0_32A_A4")
	)
	(segment
		(start 84.972931 3.922497)
		(end 84.561528 3.922497)
		(width 0.188697)
		(layer "In7.Cu")
		(net "DDR0_32A_A4")
	)
	(segment
		(start 85.6996 1.375207)
		(end 85.431097 1.64371)
		(width 0.188697)
		(layer "In7.Cu")
		(net "DDR0_32A_A4")
	)
	(segment
		(start 82.65099 7.391121)
		(end 82.245276 6.985406)
		(width 0.12065)
		(layer "In7.Cu")
		(net "DDR0_32A_A4")
	)
	(segment
		(start 84.561528 3.922497)
		(end 84.547024 3.937)
		(width 0.188697)
		(layer "In7.Cu")
		(net "DDR0_32A_A4")
	)
	(segment
		(start 70.857008 10.041992)
		(end 66.462808 10.041992)
		(width 0.188697)
		(layer "In7.Cu")
		(net "DDR0_32A_A4")
	)
	(segment
		(start 64.237006 11.04199)
		(end 63.737007 11.541989)
		(width 0.188697)
		(layer "In7.Cu")
		(net "DDR0_32A_A4")
	)
	(segment
		(start 71.247 8.926728)
		(end 71.174407 8.999322)
		(width 0.188697)
		(layer "In7.Cu")
		(net "DDR0_32A_A4")
	)
	(segment
		(start 71.247 5.461)
		(end 71.247 8.926728)
		(width 0.188697)
		(layer "In7.Cu")
		(net "DDR0_32A_A4")
	)
	(segment
		(start 71.174407 9.724593)
		(end 70.857008 10.041992)
		(width 0.188697)
		(layer "In7.Cu")
		(net "DDR0_32A_A4")
	)
	(segment
		(start 66.2178 10.287)
		(end 66.2178 10.86419)
		(width 0.188697)
		(layer "In7.Cu")
		(net "DDR0_32A_A4")
	)
	(segment
		(start 85.177097 3.900703)
		(end 84.994725 3.900703)
		(width 0.188697)
		(layer "In7.Cu")
		(net "DDR0_32A_A4")
	)
	(segment
		(start 66.462808 10.041992)
		(end 66.2178 10.287)
		(width 0.188697)
		(layer "In7.Cu")
		(net "DDR0_32A_A4")
	)
	(segment
		(start 85.4202 3.475355)
		(end 85.4202 3.6576)
		(width 0.188697)
		(layer "In7.Cu")
		(net "DDR0_32A_A4")
	)
	(segment
		(start 71.628 5.08)
		(end 71.247 5.461)
		(width 0.188697)
		(layer "In7.Cu")
		(net "DDR0_32A_A4")
	)
	(segment
		(start 81.7626 4.2926)
		(end 78.232 4.2926)
		(width 0.188697)
		(layer "In7.Cu")
		(net "DDR0_32A_A4")
	)
	(segment
		(start 66.04 11.04199)
		(end 64.237006 11.04199)
		(width 0.188697)
		(layer "In7.Cu")
		(net "DDR0_32A_A4")
	)
	(segment
		(start 82.1182 3.937)
		(end 81.7626 4.2926)
		(width 0.188697)
		(layer "In7.Cu")
		(net "DDR0_32A_A4")
	)
	(segment
		(start 85.431097 1.64371)
		(end 85.431097 3.464458)
		(width 0.188697)
		(layer "In7.Cu")
		(net "DDR0_32A_A4")
	)
	(segment
		(start 71.174407 8.999322)
		(end 71.174407 9.724593)
		(width 0.188697)
		(layer "In7.Cu")
		(net "DDR0_32A_A4")
	)
	(segment
		(start 86.222103 1.995703)
		(end 86.211207 1.984807)
		(width 0.188697)
		(layer "In7.Cu")
		(net "DDR0_32A_A4")
	)
	(segment
		(start 78.0288 4.8768)
		(end 77.8256 5.08)
		(width 0.188697)
		(layer "In7.Cu")
		(net "DDR0_32A_A4")
	)
	(segment
		(start 83.199503 5.395697)
		(end 84.543417 5.395697)
		(width 0.188697)
		(layer "In7.Cu")
		(net "DDR0_32A_A4")
	)
	(segment
		(start 84.547024 3.937)
		(end 82.1182 3.937)
		(width 0.188697)
		(layer "In7.Cu")
		(net "DDR0_32A_A4")
	)
	(segment
		(start 84.994725 3.900703)
		(end 84.972931 3.922497)
		(width 0.188697)
		(layer "In7.Cu")
		(net "DDR0_32A_A4")
	)
	(segment
		(start 82.245276 6.349924)
		(end 83.199503 5.395697)
		(width 0.188697)
		(layer "In7.Cu")
		(net "DDR0_32A_A4")
	)
	(segment
		(start 85.431097 3.464458)
		(end 85.4202 3.475355)
		(width 0.188697)
		(layer "In7.Cu")
		(net "DDR0_32A_A4")
	)
	(segment
		(start 86.02251 1.375207)
		(end 85.6996 1.375207)
		(width 0.188697)
		(layer "In7.Cu")
		(net "DDR0_32A_A4")
	)
	(segment
		(start 78.0288 4.4958)
		(end 78.0288 4.8768)
		(width 0.188697)
		(layer "In7.Cu")
		(net "DDR0_32A_A4")
	)
	(segment
		(start 77.8256 5.08)
		(end 71.628 5.08)
		(width 0.188697)
		(layer "In7.Cu")
		(net "DDR0_32A_A4")
	)
	(segment
		(start 86.211207 1.984807)
		(end 86.211207 1.563903)
		(width 0.188697)
		(layer "In7.Cu")
		(net "DDR0_32A_A4")
	)
	(segment
		(start 82.245276 6.985406)
		(end 82.245276 6.349924)
		(width 0.12065)
		(layer "In7.Cu")
		(net "DDR0_32A_A4")
	)
	(segment
		(start 86.222103 4.786097)
		(end 86.222103 1.995703)
		(width 0.188697)
		(layer "In7.Cu")
		(net "DDR0_32A_A4")
	)
	(segment
		(start 66.2178 10.86419)
		(end 66.04 11.04199)
		(width 0.188697)
		(layer "In7.Cu")
		(net "DDR0_32A_A4")
	)
	(segment
		(start 78.232 4.2926)
		(end 78.0288 4.4958)
		(width 0.188697)
		(layer "In7.Cu")
		(net "DDR0_32A_A4")
	)
	(segment
		(start 84.572424 5.424703)
		(end 85.583497 5.424703)
		(width 0.188697)
		(layer "In7.Cu")
		(net "DDR0_32A_A4")
	)
	(segment
		(start 85.4202 3.6576)
		(end 85.177097 3.900703)
		(width 0.188697)
		(layer "In7.Cu")
		(net "DDR0_32A_A4")
	)
	(segment
		(start 86.211207 1.563903)
		(end 86.02251 1.375207)
		(width 0.188697)
		(layer "In7.Cu")
		(net "DDR0_32A_A4")
	)
	(segment
		(start 82.65099 7.498994)
		(end 82.65099 7.391121)
		(width 0.12065)
		(layer "In7.Cu")
		(net "DDR0_32A_A4")
	)
	(segment
		(start 85.583497 5.424703)
		(end 86.222103 4.786097)
		(width 0.188697)
		(layer "In7.Cu")
		(net "DDR0_32A_A4")
	)
	(segment
		(start 84.543417 5.395697)
		(end 84.572424 5.424703)
		(width 0.188697)
		(layer "In7.Cu")
		(net "DDR0_32A_A4")
	)
	(segment
		(start 63.737007 19.541998)
		(end 63.237008 19.041999)
		(width 0.233528)
		(layer "F.Cu")
		(net "DDR0_32A_A3")
	)
	(segment
		(start 82.7278 23.4061)
		(end 82.55 23.495)
		(width 0.14732)
		(layer "F.Cu")
		(net "DDR0_32A_A3")
	)
	(segment
		(start 82.241034 23.803966)
		(end 82.241034 24.622963)
		(width 0.14732)
		(layer "F.Cu")
		(net "DDR0_32A_A3")
	)
	(segment
		(start 82.55 23.495)
		(end 82.241034 23.803966)
		(width 0.14732)
		(layer "F.Cu")
		(net "DDR0_32A_A3")
	)
	(segment
		(start 82.241034 24.622963)
		(end 81.850992 25.013006)
		(width 0.14732)
		(layer "F.Cu")
		(net "DDR0_32A_A3")
	)
	(via
		(at 63.737007 19.541998)
		(size 0.4826)
		(drill 0.25654)
		(layers "F.Cu" "B.Cu")
		(net "DDR0_32A_A3")
	)
	(segment
		(start 81.450993 13.856005)
		(end 81.850992 13.456006)
		(width 0.14732)
		(layer "B.Cu")
		(net "DDR0_32A_A3")
	)
	(segment
		(start 81.450993 25.413005)
		(end 81.850992 25.013006)
		(width 0.14732)
		(layer "B.Cu")
		(net "DDR0_32A_A3")
	)
	(segment
		(start 81.450993 2.299005)
		(end 81.850992 1.899006)
		(width 0.14732)
		(layer "B.Cu")
		(net "DDR0_32A_A3")
	)
	(segment
		(start 81.850992 25.013006)
		(end 81.456708 24.618721)
		(width 0.12065)
		(layer "In6.Cu")
		(net "DDR0_32A_A3")
	)
	(segment
		(start 81.692928 2.05707)
		(end 81.850992 1.899006)
		(width 0.12065)
		(layer "In6.Cu")
		(net "DDR0_32A_A3")
	)
	(segment
		(start 81.456708 13.85029)
		(end 81.850992 13.456006)
		(width 0.12065)
		(layer "In6.Cu")
		(net "DDR0_32A_A3")
	)
	(segment
		(start 81.456708 2.401164)
		(end 81.692928 2.164944)
		(width 0.12065)
		(layer "In6.Cu")
		(net "DDR0_32A_A3")
	)
	(segment
		(start 81.850992 13.456006)
		(end 81.456708 13.061721)
		(width 0.12065)
		(layer "In6.Cu")
		(net "DDR0_32A_A3")
	)
	(segment
		(start 81.456708 24.618721)
		(end 81.456708 13.85029)
		(width 0.12065)
		(layer "In6.Cu")
		(net "DDR0_32A_A3")
	)
	(segment
		(start 81.692928 2.164944)
		(end 81.692928 2.05707)
		(width 0.12065)
		(layer "In6.Cu")
		(net "DDR0_32A_A3")
	)
	(segment
		(start 81.456708 13.061721)
		(end 81.456708 2.401164)
		(width 0.12065)
		(layer "In6.Cu")
		(net "DDR0_32A_A3")
	)
	(segment
		(start 66.04 6.985)
		(end 67.945 6.985)
		(width 0.188697)
		(layer "In7.Cu")
		(net "DDR0_32A_A3")
	)
	(segment
		(start 81.456708 2.29329)
		(end 81.850992 1.899006)
		(width 0.12065)
		(layer "In7.Cu")
		(net "DDR0_32A_A3")
	)
	(segment
		(start 72.009 3.937)
		(end 74.01875 3.937)
		(width 0.188697)
		(layer "In7.Cu")
		(net "DDR0_32A_A3")
	)
	(segment
		(start 63.17427 9.715398)
		(end 63.299746 9.589922)
		(width 0.188697)
		(layer "In7.Cu")
		(net "DDR0_32A_A3")
	)
	(segment
		(start 62.910415 9.979254)
		(end 62.918137 9.979254)
		(width 0.188697)
		(layer "In7.Cu")
		(net "DDR0_32A_A3")
	)
	(segment
		(start 63.55588 9.104732)
		(end 63.920268 9.104732)
		(width 0.188697)
		(layer "In7.Cu")
		(net "DDR0_32A_A3")
	)
	(segment
		(start 74.279328 3.676421)
		(end 74.279328 3.321583)
		(width 0.188697)
		(layer "In7.Cu")
		(net "DDR0_32A_A3")
	)
	(segment
		(start 71.5518 1.057148)
		(end 71.7296 1.234948)
		(width 0.188697)
		(layer "In7.Cu")
		(net "DDR0_32A_A3")
	)
	(segment
		(start 81.456708 2.9972)
		(end 81.456708 2.29329)
		(width 0.12065)
		(layer "In7.Cu")
		(net "DDR0_32A_A3")
	)
	(segment
		(start 63.299746 9.360865)
		(end 63.55588 9.104732)
		(width 0.188697)
		(layer "In7.Cu")
		(net "DDR0_32A_A3")
	)
	(segment
		(start 77.597 2.64033)
		(end 77.72273 2.5146)
		(width 0.188697)
		(layer "In7.Cu")
		(net "DDR0_32A_A3")
	)
	(segment
		(start 78.1812 2.644191)
		(end 78.1812 3.0734)
		(width 0.188697)
		(layer "In7.Cu")
		(net "DDR0_32A_A3")
	)
	(segment
		(start 74.01875 3.937)
		(end 74.279328 3.676421)
		(width 0.188697)
		(layer "In7.Cu")
		(net "DDR0_32A_A3")
	)
	(segment
		(start 75.009324 3.127324)
		(end 75.819 3.937)
		(width 0.188697)
		(layer "In7.Cu")
		(net "DDR0_32A_A3")
	)
	(segment
		(start 63.920268 9.104732)
		(end 66.04 6.985)
		(width 0.188697)
		(layer "In7.Cu")
		(net "DDR0_32A_A3")
	)
	(segment
		(start 63.737007 19.414007)
		(end 62.23 17.907)
		(width 0.188697)
		(layer "In7.Cu")
		(net "DDR0_32A_A3")
	)
	(segment
		(start 76.708 3.4544)
		(end 76.8858 3.2766)
		(width 0.188697)
		(layer "In7.Cu")
		(net "DDR0_32A_A3")
	)
	(segment
		(start 63.737007 19.541998)
		(end 63.737007 19.414007)
		(width 0.188697)
		(layer "In7.Cu")
		(net "DDR0_32A_A3")
	)
	(segment
		(start 69.95221 3.7084)
		(end 70.7898 2.87081)
		(width 0.188697)
		(layer "In7.Cu")
		(net "DDR0_32A_A3")
	)
	(segment
		(start 62.299748 10.360863)
		(end 62.555882 10.10473)
		(width 0.188697)
		(layer "In7.Cu")
		(net "DDR0_32A_A3")
	)
	(segment
		(start 81.278908 3.175)
		(end 81.456708 2.9972)
		(width 0.188697)
		(layer "In7.Cu")
		(net "DDR0_32A_A3")
	)
	(segment
		(start 62.555882 10.10473)
		(end 62.784939 10.10473)
		(width 0.188697)
		(layer "In7.Cu")
		(net "DDR0_32A_A3")
	)
	(segment
		(start 68.199 6.731)
		(end 68.199 5.08)
		(width 0.188697)
		(layer "In7.Cu")
		(net "DDR0_32A_A3")
	)
	(segment
		(start 76.8858 3.2766)
		(end 77.2668 3.2766)
		(width 0.188697)
		(layer "In7.Cu")
		(net "DDR0_32A_A3")
	)
	(segment
		(start 70.7898 2.87081)
		(end 70.7898 1.1938)
		(width 0.188697)
		(layer "In7.Cu")
		(net "DDR0_32A_A3")
	)
	(segment
		(start 62.918137 9.979254)
		(end 63.17427 9.72312)
		(width 0.188697)
		(layer "In7.Cu")
		(net "DDR0_32A_A3")
	)
	(segment
		(start 74.473587 3.127324)
		(end 75.009324 3.127324)
		(width 0.188697)
		(layer "In7.Cu")
		(net "DDR0_32A_A3")
	)
	(segment
		(start 63.299746 9.589922)
		(end 63.299746 9.360865)
		(width 0.188697)
		(layer "In7.Cu")
		(net "DDR0_32A_A3")
	)
	(segment
		(start 77.597 2.9464)
		(end 77.597 2.64033)
		(width 0.188697)
		(layer "In7.Cu")
		(net "DDR0_32A_A3")
	)
	(segment
		(start 76.5302 3.937)
		(end 76.708 3.7592)
		(width 0.188697)
		(layer "In7.Cu")
		(net "DDR0_32A_A3")
	)
	(segment
		(start 63.17427 9.72312)
		(end 63.17427 9.715398)
		(width 0.188697)
		(layer "In7.Cu")
		(net "DDR0_32A_A3")
	)
	(segment
		(start 78.1812 3.0734)
		(end 78.2828 3.175)
		(width 0.188697)
		(layer "In7.Cu")
		(net "DDR0_32A_A3")
	)
	(segment
		(start 62.23 10.438333)
		(end 62.299748 10.368585)
		(width 0.188697)
		(layer "In7.Cu")
		(net "DDR0_32A_A3")
	)
	(segment
		(start 78.2828 3.175)
		(end 81.278908 3.175)
		(width 0.188697)
		(layer "In7.Cu")
		(net "DDR0_32A_A3")
	)
	(segment
		(start 69.5706 3.7084)
		(end 69.95221 3.7084)
		(width 0.188697)
		(layer "In7.Cu")
		(net "DDR0_32A_A3")
	)
	(segment
		(start 77.2668 3.2766)
		(end 77.597 2.9464)
		(width 0.188697)
		(layer "In7.Cu")
		(net "DDR0_32A_A3")
	)
	(segment
		(start 70.7898 1.1938)
		(end 70.926452 1.057148)
		(width 0.188697)
		(layer "In7.Cu")
		(net "DDR0_32A_A3")
	)
	(segment
		(start 74.279328 3.321583)
		(end 74.473587 3.127324)
		(width 0.188697)
		(layer "In7.Cu")
		(net "DDR0_32A_A3")
	)
	(segment
		(start 68.199 5.08)
		(end 69.5706 3.7084)
		(width 0.188697)
		(layer "In7.Cu")
		(net "DDR0_32A_A3")
	)
	(segment
		(start 67.945 6.985)
		(end 68.199 6.731)
		(width 0.188697)
		(layer "In7.Cu")
		(net "DDR0_32A_A3")
	)
	(segment
		(start 75.819 3.937)
		(end 76.5302 3.937)
		(width 0.188697)
		(layer "In7.Cu")
		(net "DDR0_32A_A3")
	)
	(segment
		(start 62.299748 10.368585)
		(end 62.299748 10.360863)
		(width 0.188697)
		(layer "In7.Cu")
		(net "DDR0_32A_A3")
	)
	(segment
		(start 78.051609 2.5146)
		(end 78.1812 2.644191)
		(width 0.188697)
		(layer "In7.Cu")
		(net "DDR0_32A_A3")
	)
	(segment
		(start 71.7296 1.234948)
		(end 71.7296 3.6576)
		(width 0.188697)
		(layer "In7.Cu")
		(net "DDR0_32A_A3")
	)
	(segment
		(start 70.926452 1.057148)
		(end 71.5518 1.057148)
		(width 0.188697)
		(layer "In7.Cu")
		(net "DDR0_32A_A3")
	)
	(segment
		(start 62.23 17.907)
		(end 62.23 10.438333)
		(width 0.188697)
		(layer "In7.Cu")
		(net "DDR0_32A_A3")
	)
	(segment
		(start 76.708 3.7592)
		(end 76.708 3.4544)
		(width 0.188697)
		(layer "In7.Cu")
		(net "DDR0_32A_A3")
	)
	(segment
		(start 62.784939 10.10473)
		(end 62.910415 9.979254)
		(width 0.188697)
		(layer "In7.Cu")
		(net "DDR0_32A_A3")
	)
	(segment
		(start 71.7296 3.6576)
		(end 72.009 3.937)
		(width 0.188697)
		(layer "In7.Cu")
		(net "DDR0_32A_A3")
	)
	(segment
		(start 77.72273 2.5146)
		(end 78.051609 2.5146)
		(width 0.188697)
		(layer "In7.Cu")
		(net "DDR0_32A_A3")
	)
	(segment
		(start 82.65099 26.35189)
		(end 82.65099 25.813004)
		(width 0.14732)
		(layer "F.Cu")
		(net "DDR0_32A_A2")
	)
	(segment
		(start 62.737009 10.541991)
		(end 62.23701 11.04199)
		(width 0.233528)
		(layer "F.Cu")
		(net "DDR0_32A_A2")
	)
	(segment
		(start 82.804 26.5049)
		(end 82.65099 26.35189)
		(width 0.14732)
		(layer "F.Cu")
		(net "DDR0_32A_A2")
	)
	(via
		(at 62.737009 10.541991)
		(size 0.4826)
		(drill 0.20574)
		(layers "F.Cu" "B.Cu")
		(net "DDR0_32A_A2")
	)
	(segment
		(start 82.250991 14.656003)
		(end 82.65099 14.256004)
		(width 0.14732)
		(layer "B.Cu")
		(net "DDR0_32A_A2")
	)
	(segment
		(start 82.250991 3.099003)
		(end 82.65099 2.699004)
		(width 0.14732)
		(layer "B.Cu")
		(net "DDR0_32A_A2")
	)
	(segment
		(start 82.250991 26.213003)
		(end 82.65099 25.813004)
		(width 0.14732)
		(layer "B.Cu")
		(net "DDR0_32A_A2")
	)
	(segment
		(start 82.65099 14.256004)
		(end 82.256706 13.86172)
		(width 0.12065)
		(layer "In3.Cu")
		(net "DDR0_32A_A2")
	)
	(segment
		(start 82.256706 14.650288)
		(end 82.65099 14.256004)
		(width 0.12065)
		(layer "In3.Cu")
		(net "DDR0_32A_A2")
	)
	(segment
		(start 82.65099 25.813004)
		(end 82.256706 25.41872)
		(width 0.12065)
		(layer "In3.Cu")
		(net "DDR0_32A_A2")
	)
	(segment
		(start 82.256706 25.41872)
		(end 82.256706 14.650288)
		(width 0.12065)
		(layer "In3.Cu")
		(net "DDR0_32A_A2")
	)
	(segment
		(start 82.256706 13.86172)
		(end 82.256706 3.093288)
		(width 0.12065)
		(layer "In3.Cu")
		(net "DDR0_32A_A2")
	)
	(segment
		(start 82.256706 3.093288)
		(end 82.65099 2.699004)
		(width 0.12065)
		(layer "In3.Cu")
		(net "DDR0_32A_A2")
	)
	(segment
		(start 64.007009 10.541991)
		(end 62.737009 10.541991)
		(width 0.188697)
		(layer "In6.Cu")
		(net "DDR0_32A_A2")
	)
	(segment
		(start 84.074 0.508)
		(end 84.292846 0.289154)
		(width 0.188697)
		(layer "In6.Cu")
		(net "DDR0_32A_A2")
	)
	(segment
		(start 63.9826 -0.674243)
		(end 64.549807 -0.107036)
		(width 0.188697)
		(layer "In6.Cu")
		(net "DDR0_32A_A2")
	)
	(segment
		(start 82.809055 2.298573)
		(end 83.045275 2.062353)
		(width 0.12065)
		(layer "In6.Cu")
		(net "DDR0_32A_A2")
	)
	(segment
		(start 82.65099 2.699004)
		(end 82.809055 2.54094)
		(width 0.12065)
		(layer "In6.Cu")
		(net "DDR0_32A_A2")
	)
	(segment
		(start 64.549807 3.539007)
		(end 65.278 4.2672)
		(width 0.188697)
		(layer "In6.Cu")
		(net "DDR0_32A_A2")
	)
	(segment
		(start 65.490344 -1.6002)
		(end 64.1604 -1.6002)
		(width 0.188697)
		(layer "In6.Cu")
		(net "DDR0_32A_A2")
	)
	(segment
		(start 64.516 10.033)
		(end 64.007009 10.541991)
		(width 0.188697)
		(layer "In6.Cu")
		(net "DDR0_32A_A2")
	)
	(segment
		(start 65.278 4.2672)
		(end 65.278 9.652)
		(width 0.188697)
		(layer "In6.Cu")
		(net "DDR0_32A_A2")
	)
	(segment
		(start 82.809055 2.54094)
		(end 82.809055 2.298573)
		(width 0.12065)
		(layer "In6.Cu")
		(net "DDR0_32A_A2")
	)
	(segment
		(start 64.897 10.033)
		(end 64.516 10.033)
		(width 0.188697)
		(layer "In6.Cu")
		(net "DDR0_32A_A2")
	)
	(segment
		(start 64.1604 -1.6002)
		(end 63.9826 -1.4224)
		(width 0.188697)
		(layer "In6.Cu")
		(net "DDR0_32A_A2")
	)
	(segment
		(start 64.549807 -0.107036)
		(end 64.549807 3.539007)
		(width 0.188697)
		(layer "In6.Cu")
		(net "DDR0_32A_A2")
	)
	(segment
		(start 83.286549 0.508)
		(end 84.074 0.508)
		(width 0.188697)
		(layer "In6.Cu")
		(net "DDR0_32A_A2")
	)
	(segment
		(start 83.045275 2.062353)
		(end 83.045275 0.749275)
		(width 0.12065)
		(layer "In6.Cu")
		(net "DDR0_32A_A2")
	)
	(segment
		(start 84.113903 -1.611097)
		(end 65.501241 -1.611097)
		(width 0.188697)
		(layer "In6.Cu")
		(net "DDR0_32A_A2")
	)
	(segment
		(start 83.045275 0.749275)
		(end 83.286549 0.508)
		(width 0.188697)
		(layer "In6.Cu")
		(net "DDR0_32A_A2")
	)
	(segment
		(start 63.9826 -1.4224)
		(end 63.9826 -0.674243)
		(width 0.188697)
		(layer "In6.Cu")
		(net "DDR0_32A_A2")
	)
	(segment
		(start 84.292846 0.289154)
		(end 84.292846 -1.432154)
		(width 0.188697)
		(layer "In6.Cu")
		(net "DDR0_32A_A2")
	)
	(segment
		(start 84.292846 -1.432154)
		(end 84.113903 -1.611097)
		(width 0.188697)
		(layer "In6.Cu")
		(net "DDR0_32A_A2")
	)
	(segment
		(start 65.278 9.652)
		(end 64.897 10.033)
		(width 0.188697)
		(layer "In6.Cu")
		(net "DDR0_32A_A2")
	)
	(segment
		(start 65.501241 -1.611097)
		(end 65.490344 -1.6002)
		(width 0.188697)
		(layer "In6.Cu")
		(net "DDR0_32A_A2")
	)
	(segment
		(start 82.65099 29.27411)
		(end 82.65099 29.812996)
		(width 0.14732)
		(layer "F.Cu")
		(net "DDR0_32A_A1")
	)
	(segment
		(start 64.737005 19.541998)
		(end 64.237006 19.041999)
		(width 0.233528)
		(layer "F.Cu")
		(net "DDR0_32A_A1")
	)
	(segment
		(start 82.804 29.1211)
		(end 82.65099 29.27411)
		(width 0.14732)
		(layer "F.Cu")
		(net "DDR0_32A_A1")
	)
	(via
		(at 64.737005 19.541998)
		(size 0.4826)
		(drill 0.25654)
		(layers "F.Cu" "B.Cu")
		(net "DDR0_32A_A1")
	)
	(segment
		(start 82.250991 29.412997)
		(end 82.65099 29.812996)
		(width 0.14732)
		(layer "B.Cu")
		(net "DDR0_32A_A1")
	)
	(segment
		(start 82.250991 6.298997)
		(end 82.65099 6.698996)
		(width 0.14732)
		(layer "B.Cu")
		(net "DDR0_32A_A1")
	)
	(segment
		(start 82.250991 17.855997)
		(end 82.65099 18.255996)
		(width 0.14732)
		(layer "B.Cu")
		(net "DDR0_32A_A1")
	)
	(segment
		(start 83.045275 17.861712)
		(end 83.045275 7.09328)
		(width 0.12065)
		(layer "In3.Cu")
		(net "DDR0_32A_A1")
	)
	(segment
		(start 83.045275 7.09328)
		(end 82.65099 6.698996)
		(width 0.12065)
		(layer "In3.Cu")
		(net "DDR0_32A_A1")
	)
	(segment
		(start 83.045275 18.65028)
		(end 82.65099 18.255996)
		(width 0.12065)
		(layer "In3.Cu")
		(net "DDR0_32A_A1")
	)
	(segment
		(start 83.045275 29.418712)
		(end 83.045275 18.65028)
		(width 0.12065)
		(layer "In3.Cu")
		(net "DDR0_32A_A1")
	)
	(segment
		(start 82.65099 18.255996)
		(end 83.045275 17.861712)
		(width 0.12065)
		(layer "In3.Cu")
		(net "DDR0_32A_A1")
	)
	(segment
		(start 82.65099 29.812996)
		(end 83.045275 29.418712)
		(width 0.12065)
		(layer "In3.Cu")
		(net "DDR0_32A_A1")
	)
	(segment
		(start 71.628 16.129)
		(end 74.8792 16.129)
		(width 0.188697)
		(layer "In7.Cu")
		(net "DDR0_32A_A1")
	)
	(segment
		(start 85.9536 17.018)
		(end 86.1822 16.7894)
		(width 0.188697)
		(layer "In7.Cu")
		(net "DDR0_32A_A1")
	)
	(segment
		(start 86.0298 7.7978)
		(end 85.232418 7.7978)
		(width 0.188697)
		(layer "In7.Cu")
		(net "DDR0_32A_A1")
	)
	(segment
		(start 71.191298 17.750765)
		(end 71.191298 17.017009)
		(width 0.188697)
		(layer "In7.Cu")
		(net "DDR0_32A_A1")
	)
	(segment
		(start 74.8792 16.129)
		(end 75.2348 16.4846)
		(width 0.188697)
		(layer "In7.Cu")
		(net "DDR0_32A_A1")
	)
	(segment
		(start 84.922182 8.8392)
		(end 83.158305 8.8392)
		(width 0.188697)
		(layer "In7.Cu")
		(net "DDR0_32A_A1")
	)
	(segment
		(start 82.65099 6.941363)
		(end 82.65099 6.698996)
		(width 0.12065)
		(layer "In7.Cu")
		(net "DDR0_32A_A1")
	)
	(segment
		(start 71.207655 16.610863)
		(end 71.218552 16.599967)
		(width 0.188697)
		(layer "In7.Cu")
		(net "DDR0_32A_A1")
	)
	(segment
		(start 85.0646 8.696782)
		(end 84.922182 8.8392)
		(width 0.188697)
		(layer "In7.Cu")
		(net "DDR0_32A_A1")
	)
	(segment
		(start 71.207655 17.000652)
		(end 71.207655 16.610863)
		(width 0.188697)
		(layer "In7.Cu")
		(net "DDR0_32A_A1")
	)
	(segment
		(start 64.914831 18.034)
		(end 70.908062 18.034)
		(width 0.188697)
		(layer "In7.Cu")
		(net "DDR0_32A_A1")
	)
	(segment
		(start 64.737005 19.541998)
		(end 64.737005 18.211825)
		(width 0.188697)
		(layer "In7.Cu")
		(net "DDR0_32A_A1")
	)
	(segment
		(start 64.737005 18.211825)
		(end 64.914831 18.034)
		(width 0.188697)
		(layer "In7.Cu")
		(net "DDR0_32A_A1")
	)
	(segment
		(start 85.0646 7.965618)
		(end 85.0646 8.696782)
		(width 0.188697)
		(layer "In7.Cu")
		(net "DDR0_32A_A1")
	)
	(segment
		(start 86.1822 16.7894)
		(end 86.1822 7.9502)
		(width 0.188697)
		(layer "In7.Cu")
		(net "DDR0_32A_A1")
	)
	(segment
		(start 75.4126 17.018)
		(end 85.9536 17.018)
		(width 0.188697)
		(layer "In7.Cu")
		(net "DDR0_32A_A1")
	)
	(segment
		(start 75.2348 16.4846)
		(end 75.2348 16.8402)
		(width 0.188697)
		(layer "In7.Cu")
		(net "DDR0_32A_A1")
	)
	(segment
		(start 83.158305 8.8392)
		(end 83.056705 8.7376)
		(width 0.188697)
		(layer "In7.Cu")
		(net "DDR0_32A_A1")
	)
	(segment
		(start 71.218552 16.599967)
		(end 71.218552 16.538448)
		(width 0.188697)
		(layer "In7.Cu")
		(net "DDR0_32A_A1")
	)
	(segment
		(start 70.908062 18.034)
		(end 71.191298 17.750765)
		(width 0.188697)
		(layer "In7.Cu")
		(net "DDR0_32A_A1")
	)
	(segment
		(start 71.218552 16.538448)
		(end 71.628 16.129)
		(width 0.188697)
		(layer "In7.Cu")
		(net "DDR0_32A_A1")
	)
	(segment
		(start 75.2348 16.8402)
		(end 75.4126 17.018)
		(width 0.188697)
		(layer "In7.Cu")
		(net "DDR0_32A_A1")
	)
	(segment
		(start 83.056705 7.347077)
		(end 82.65099 6.941363)
		(width 0.12065)
		(layer "In7.Cu")
		(net "DDR0_32A_A1")
	)
	(segment
		(start 83.056705 8.7376)
		(end 83.056705 7.347077)
		(width 0.12065)
		(layer "In7.Cu")
		(net "DDR0_32A_A1")
	)
	(segment
		(start 86.1822 7.9502)
		(end 86.0298 7.7978)
		(width 0.188697)
		(layer "In7.Cu")
		(net "DDR0_32A_A1")
	)
	(segment
		(start 85.232418 7.7978)
		(end 85.0646 7.965618)
		(width 0.188697)
		(layer "In7.Cu")
		(net "DDR0_32A_A1")
	)
	(segment
		(start 71.191298 17.017009)
		(end 71.207655 17.000652)
		(width 0.188697)
		(layer "In7.Cu")
		(net "DDR0_32A_A1")
	)
	(segment
		(start 81.850992 26.440892)
		(end 81.850992 25.813004)
		(width 0.14732)
		(layer "F.Cu")
		(net "DDR0_32A_A0")
	)
	(segment
		(start 81.915 26.5049)
		(end 81.850992 26.440892)
		(width 0.14732)
		(layer "F.Cu")
		(net "DDR0_32A_A0")
	)
	(segment
		(start 62.737009 11.541989)
		(end 63.237008 11.04199)
		(width 0.233528)
		(layer "F.Cu")
		(net "DDR0_32A_A0")
	)
	(via
		(at 62.737009 11.541989)
		(size 0.4826)
		(drill 0.20574)
		(layers "F.Cu" "B.Cu")
		(net "DDR0_32A_A0")
	)
	(segment
		(start 81.450993 3.099003)
		(end 81.850992 2.699004)
		(width 0.14732)
		(layer "B.Cu")
		(net "DDR0_32A_A0")
	)
	(segment
		(start 81.450993 26.213003)
		(end 81.850992 25.813004)
		(width 0.14732)
		(layer "B.Cu")
		(net "DDR0_32A_A0")
	)
	(segment
		(start 81.450993 14.656003)
		(end 81.850992 14.256004)
		(width 0.14732)
		(layer "B.Cu")
		(net "DDR0_32A_A0")
	)
	(segment
		(start 81.850992 25.813004)
		(end 81.456708 25.41872)
		(width 0.12065)
		(layer "In3.Cu")
		(net "DDR0_32A_A0")
	)
	(segment
		(start 81.456708 25.41872)
		(end 81.456708 14.650288)
		(width 0.12065)
		(layer "In3.Cu")
		(net "DDR0_32A_A0")
	)
	(segment
		(start 81.456708 13.86172)
		(end 81.456708 3.093288)
		(width 0.12065)
		(layer "In3.Cu")
		(net "DDR0_32A_A0")
	)
	(segment
		(start 81.850992 14.256004)
		(end 81.456708 13.86172)
		(width 0.12065)
		(layer "In3.Cu")
		(net "DDR0_32A_A0")
	)
	(segment
		(start 81.456708 14.650288)
		(end 81.850992 14.256004)
		(width 0.12065)
		(layer "In3.Cu")
		(net "DDR0_32A_A0")
	)
	(segment
		(start 81.456708 3.093288)
		(end 81.850992 2.699004)
		(width 0.12065)
		(layer "In3.Cu")
		(net "DDR0_32A_A0")
	)
	(segment
		(start 65.317903 -1.208303)
		(end 65.652675 -1.208303)
		(width 0.188697)
		(layer "In6.Cu")
		(net "DDR0_32A_A0")
	)
	(segment
		(start 83.693 0.192303)
		(end 82.433998 0.192303)
		(width 0.188697)
		(layer "In6.Cu")
		(net "DDR0_32A_A0")
	)
	(segment
		(start 83.69775 -1.2192)
		(end 83.90095 -1.016)
		(width 0.188697)
		(layer "In6.Cu")
		(net "DDR0_32A_A0")
	)
	(segment
		(start 66.294 4.445)
		(end 65.125575 3.276575)
		(width 0.188697)
		(layer "In6.Cu")
		(net "DDR0_32A_A0")
	)
	(segment
		(start 65.652675 -1.208303)
		(end 65.663572 -1.2192)
		(width 0.188697)
		(layer "In6.Cu")
		(net "DDR0_32A_A0")
	)
	(segment
		(start 62.737009 11.541989)
		(end 63.229998 11.049)
		(width 0.188697)
		(layer "In6.Cu")
		(net "DDR0_32A_A0")
	)
	(segment
		(start 83.90095 -1.016)
		(end 83.90095 -0.015646)
		(width 0.188697)
		(layer "In6.Cu")
		(net "DDR0_32A_A0")
	)
	(segment
		(start 65.913 10.033)
		(end 66.294 9.652)
		(width 0.188697)
		(layer "In6.Cu")
		(net "DDR0_32A_A0")
	)
	(segment
		(start 81.850992 2.456637)
		(end 81.850992 2.699004)
		(width 0.12065)
		(layer "In6.Cu")
		(net "DDR0_32A_A0")
	)
	(segment
		(start 82.433998 0.192303)
		(end 82.245276 0.381025)
		(width 0.188697)
		(layer "In6.Cu")
		(net "DDR0_32A_A0")
	)
	(segment
		(start 65.024 11.049)
		(end 65.237004 10.835996)
		(width 0.188697)
		(layer "In6.Cu")
		(net "DDR0_32A_A0")
	)
	(segment
		(start 65.125575 3.276575)
		(end 65.125575 -1.015975)
		(width 0.188697)
		(layer "In6.Cu")
		(net "DDR0_32A_A0")
	)
	(segment
		(start 65.663572 -1.2192)
		(end 83.69775 -1.2192)
		(width 0.188697)
		(layer "In6.Cu")
		(net "DDR0_32A_A0")
	)
	(segment
		(start 65.125575 -1.015975)
		(end 65.317903 -1.208303)
		(width 0.188697)
		(layer "In6.Cu")
		(net "DDR0_32A_A0")
	)
	(segment
		(start 82.245276 2.062353)
		(end 81.850992 2.456637)
		(width 0.12065)
		(layer "In6.Cu")
		(net "DDR0_32A_A0")
	)
	(segment
		(start 82.245276 0.381025)
		(end 82.245276 2.062353)
		(width 0.12065)
		(layer "In6.Cu")
		(net "DDR0_32A_A0")
	)
	(segment
		(start 65.237004 10.327996)
		(end 65.532 10.033)
		(width 0.188697)
		(layer "In6.Cu")
		(net "DDR0_32A_A0")
	)
	(segment
		(start 83.90095 -0.015646)
		(end 83.693 0.192303)
		(width 0.188697)
		(layer "In6.Cu")
		(net "DDR0_32A_A0")
	)
	(segment
		(start 65.237004 10.835996)
		(end 65.237004 10.327996)
		(width 0.188697)
		(layer "In6.Cu")
		(net "DDR0_32A_A0")
	)
	(segment
		(start 66.294 9.652)
		(end 66.294 4.445)
		(width 0.188697)
		(layer "In6.Cu")
		(net "DDR0_32A_A0")
	)
	(segment
		(start 65.532 10.033)
		(end 65.913 10.033)
		(width 0.188697)
		(layer "In6.Cu")
		(net "DDR0_32A_A0")
	)
	(segment
		(start 63.229998 11.049)
		(end 65.024 11.049)
		(width 0.188697)
		(layer "In6.Cu")
		(net "DDR0_32A_A0")
	)
	(segment
		(start 33.746008 25.048388)
		(end 33.57692 24.8793)
		(width 0.127)
		(layer "F.Cu")
		(net "CPLD_NIC_MEZZ_ID1")
	)
	(segment
		(start 16.97703 23.9649)
		(end 17.78 23.9649)
		(width 0.14732)
		(layer "F.Cu")
		(net "CPLD_NIC_MEZZ_ID1")
	)
	(segment
		(start 33.57692 24.8793)
		(end 32.7279 24.8793)
		(width 0.127)
		(layer "F.Cu")
		(net "CPLD_NIC_MEZZ_ID1")
	)
	(segment
		(start 16.90337 24.03856)
		(end 16.97703 23.9649)
		(width 0.14732)
		(layer "F.Cu")
		(net "CPLD_NIC_MEZZ_ID1")
	)
	(segment
		(start 14.81074 24.03856)
		(end 16.90337 24.03856)
		(width 0.14732)
		(layer "F.Cu")
		(net "CPLD_NIC_MEZZ_ID1")
	)
	(segment
		(start 14.1224 24.7269)
		(end 14.81074 24.03856)
		(width 0.14732)
		(layer "F.Cu")
		(net "CPLD_NIC_MEZZ_ID1")
	)
	(segment
		(start 32.7279 24.8793)
		(end 32.3342 25.273)
		(width 0.127)
		(layer "F.Cu")
		(net "CPLD_NIC_MEZZ_ID1")
	)
	(via
		(at 14.1224 24.7269)
		(size 0.762)
		(drill 0.2667)
		(layers "F.Cu" "B.Cu")
		(net "CPLD_NIC_MEZZ_ID1")
	)
	(via
		(at 32.3342 25.273)
		(size 0.4572)
		(drill 0.20574)
		(layers "F.Cu" "B.Cu")
		(net "CPLD_NIC_MEZZ_ID1")
	)
	(segment
		(start 14.7574 25.3619)
		(end 14.1224 24.7269)
		(width 0.254)
		(layer "B.Cu")
		(net "CPLD_NIC_MEZZ_ID1")
	)
	(segment
		(start 14.1224 24.7269)
		(end 14.563725 25.168225)
		(width 0.12065)
		(layer "In3.Cu")
		(net "CPLD_NIC_MEZZ_ID1")
	)
	(segment
		(start 30.845404 25.689941)
		(end 30.891886 25.643459)
		(width 0.12065)
		(layer "In3.Cu")
		(net "CPLD_NIC_MEZZ_ID1")
	)
	(segment
		(start 26.532459 24.119459)
		(end 26.532459 24.500459)
		(width 0.12065)
		(layer "In3.Cu")
		(net "CPLD_NIC_MEZZ_ID1")
	)
	(segment
		(start 28.437459 25.643459)
		(end 29.687114 25.643459)
		(width 0.12065)
		(layer "In3.Cu")
		(net "CPLD_NIC_MEZZ_ID1")
	)
	(segment
		(start 18.933846 25.654)
		(end 18.994171 25.593675)
		(width 0.12065)
		(layer "In3.Cu")
		(net "CPLD_NIC_MEZZ_ID1")
	)
	(segment
		(start 31.963741 25.643459)
		(end 32.3342 25.273)
		(width 0.12065)
		(layer "In3.Cu")
		(net "CPLD_NIC_MEZZ_ID1")
	)
	(segment
		(start 26.797 24.765)
		(end 27.559 24.765)
		(width 0.12065)
		(layer "In3.Cu")
		(net "CPLD_NIC_MEZZ_ID1")
	)
	(segment
		(start 26.532459 24.500459)
		(end 26.797 24.765)
		(width 0.12065)
		(layer "In3.Cu")
		(net "CPLD_NIC_MEZZ_ID1")
	)
	(segment
		(start 29.733596 25.689941)
		(end 30.845404 25.689941)
		(width 0.12065)
		(layer "In3.Cu")
		(net "CPLD_NIC_MEZZ_ID1")
	)
	(segment
		(start 19.359829 25.593675)
		(end 19.420154 25.654)
		(width 0.12065)
		(layer "In3.Cu")
		(net "CPLD_NIC_MEZZ_ID1")
	)
	(segment
		(start 25.938455 23.876)
		(end 25.948996 23.886541)
		(width 0.12065)
		(layer "In3.Cu")
		(net "CPLD_NIC_MEZZ_ID1")
	)
	(segment
		(start 27.559 24.765)
		(end 28.437459 25.643459)
		(width 0.12065)
		(layer "In3.Cu")
		(net "CPLD_NIC_MEZZ_ID1")
	)
	(segment
		(start 17.802225 25.168225)
		(end 18.288 25.654)
		(width 0.12065)
		(layer "In3.Cu")
		(net "CPLD_NIC_MEZZ_ID1")
	)
	(segment
		(start 19.420154 25.654)
		(end 22.987 25.654)
		(width 0.12065)
		(layer "In3.Cu")
		(net "CPLD_NIC_MEZZ_ID1")
	)
	(segment
		(start 24.765 23.876)
		(end 25.938455 23.876)
		(width 0.12065)
		(layer "In3.Cu")
		(net "CPLD_NIC_MEZZ_ID1")
	)
	(segment
		(start 22.987 25.654)
		(end 24.765 23.876)
		(width 0.12065)
		(layer "In3.Cu")
		(net "CPLD_NIC_MEZZ_ID1")
	)
	(segment
		(start 30.891886 25.643459)
		(end 31.963741 25.643459)
		(width 0.12065)
		(layer "In3.Cu")
		(net "CPLD_NIC_MEZZ_ID1")
	)
	(segment
		(start 14.563725 25.168225)
		(end 17.802225 25.168225)
		(width 0.12065)
		(layer "In3.Cu")
		(net "CPLD_NIC_MEZZ_ID1")
	)
	(segment
		(start 18.288 25.654)
		(end 18.933846 25.654)
		(width 0.12065)
		(layer "In3.Cu")
		(net "CPLD_NIC_MEZZ_ID1")
	)
	(segment
		(start 29.687114 25.643459)
		(end 29.733596 25.689941)
		(width 0.12065)
		(layer "In3.Cu")
		(net "CPLD_NIC_MEZZ_ID1")
	)
	(segment
		(start 18.994171 25.593675)
		(end 19.359829 25.593675)
		(width 0.12065)
		(layer "In3.Cu")
		(net "CPLD_NIC_MEZZ_ID1")
	)
	(segment
		(start 26.299541 23.886541)
		(end 26.532459 24.119459)
		(width 0.12065)
		(layer "In3.Cu")
		(net "CPLD_NIC_MEZZ_ID1")
	)
	(segment
		(start 25.948996 23.886541)
		(end 26.299541 23.886541)
		(width 0.12065)
		(layer "In3.Cu")
		(net "CPLD_NIC_MEZZ_ID1")
	)
	(via
		(at 16.383 1.8161)
		(size 0.508)
		(drill 0.254)
		(layers "F.Cu" "B.Cu")
		(net "CPLD_NIC_MEZZ_ID0")
	)
	(via
		(at 29.464 21.1074)
		(size 0.4572)
		(drill 0.20574)
		(layers "F.Cu" "B.Cu")
		(net "CPLD_NIC_MEZZ_ID0")
	)
	(via
		(at 18.669 10.287)
		(size 0.762)
		(drill 0.2667)
		(layers "F.Cu" "B.Cu")
		(net "CPLD_NIC_MEZZ_ID0")
	)
	(segment
		(start 15.6591 2.54)
		(end 12.573 2.54)
		(width 0.14732)
		(layer "B.Cu")
		(net "CPLD_NIC_MEZZ_ID0")
	)
	(segment
		(start 12.573 2.54)
		(end 12.2174 2.8956)
		(width 0.14732)
		(layer "B.Cu")
		(net "CPLD_NIC_MEZZ_ID0")
	)
	(segment
		(start 12.2174 2.8956)
		(end 12.2174 3.7719)
		(width 0.14732)
		(layer "B.Cu")
		(net "CPLD_NIC_MEZZ_ID0")
	)
	(segment
		(start 16.383 1.8161)
		(end 15.6591 2.54)
		(width 0.14732)
		(layer "B.Cu")
		(net "CPLD_NIC_MEZZ_ID0")
	)
	(segment
		(start 29.245992 22.548393)
		(end 29.245992 21.325408)
		(width 0.127)
		(layer "In1.Cu")
		(net "CPLD_NIC_MEZZ_ID0")
	)
	(segment
		(start 29.245992 21.325408)
		(end 29.464 21.1074)
		(width 0.127)
		(layer "In1.Cu")
		(net "CPLD_NIC_MEZZ_ID0")
	)
	(segment
		(start 20.193 17.145)
		(end 20.193 18.669)
		(width 0.12065)
		(layer "In3.Cu")
		(net "CPLD_NIC_MEZZ_ID0")
	)
	(segment
		(start 20.066 22.225)
		(end 21.717 22.225)
		(width 0.12065)
		(layer "In3.Cu")
		(net "CPLD_NIC_MEZZ_ID0")
	)
	(segment
		(start 20.500975 16.806266)
		(end 20.393025 16.914216)
		(width 0.12065)
		(layer "In3.Cu")
		(net "CPLD_NIC_MEZZ_ID0")
	)
	(segment
		(start 23.114 20.066)
		(end 27.813 20.066)
		(width 0.12065)
		(layer "In3.Cu")
		(net "CPLD_NIC_MEZZ_ID0")
	)
	(segment
		(start 27.813 20.066)
		(end 28.448 20.701)
		(width 0.12065)
		(layer "In3.Cu")
		(net "CPLD_NIC_MEZZ_ID0")
	)
	(segment
		(start 28.448 20.701)
		(end 29.0576 20.701)
		(width 0.12065)
		(layer "In3.Cu")
		(net "CPLD_NIC_MEZZ_ID0")
	)
	(segment
		(start 20.393025 16.944975)
		(end 20.193 17.145)
		(width 0.12065)
		(layer "In3.Cu")
		(net "CPLD_NIC_MEZZ_ID0")
	)
	(segment
		(start 20.393025 16.914216)
		(end 20.393025 16.944975)
		(width 0.12065)
		(layer "In3.Cu")
		(net "CPLD_NIC_MEZZ_ID0")
	)
	(segment
		(start 29.0576 20.701)
		(end 29.464 21.1074)
		(width 0.12065)
		(layer "In3.Cu")
		(net "CPLD_NIC_MEZZ_ID0")
	)
	(segment
		(start 22.479 21.463)
		(end 22.479 20.701)
		(width 0.12065)
		(layer "In3.Cu")
		(net "CPLD_NIC_MEZZ_ID0")
	)
	(segment
		(start 19.431 21.59)
		(end 20.066 22.225)
		(width 0.12065)
		(layer "In3.Cu")
		(net "CPLD_NIC_MEZZ_ID0")
	)
	(segment
		(start 19.624675 11.242675)
		(end 19.624675 15.179675)
		(width 0.12065)
		(layer "In3.Cu")
		(net "CPLD_NIC_MEZZ_ID0")
	)
	(segment
		(start 20.193 18.669)
		(end 19.431 19.431)
		(width 0.12065)
		(layer "In3.Cu")
		(net "CPLD_NIC_MEZZ_ID0")
	)
	(segment
		(start 20.500975 16.055975)
		(end 20.500975 16.806266)
		(width 0.12065)
		(layer "In3.Cu")
		(net "CPLD_NIC_MEZZ_ID0")
	)
	(segment
		(start 22.479 20.701)
		(end 23.114 20.066)
		(width 0.12065)
		(layer "In3.Cu")
		(net "CPLD_NIC_MEZZ_ID0")
	)
	(segment
		(start 19.431 19.431)
		(end 19.431 21.59)
		(width 0.12065)
		(layer "In3.Cu")
		(net "CPLD_NIC_MEZZ_ID0")
	)
	(segment
		(start 18.669 10.287)
		(end 19.624675 11.242675)
		(width 0.12065)
		(layer "In3.Cu")
		(net "CPLD_NIC_MEZZ_ID0")
	)
	(segment
		(start 21.717 22.225)
		(end 22.479 21.463)
		(width 0.12065)
		(layer "In3.Cu")
		(net "CPLD_NIC_MEZZ_ID0")
	)
	(segment
		(start 19.624675 15.179675)
		(end 20.500975 16.055975)
		(width 0.12065)
		(layer "In3.Cu")
		(net "CPLD_NIC_MEZZ_ID0")
	)
	(segment
		(start 17.605375 9.223375)
		(end 17.605375 9.096273)
		(width 0.12065)
		(layer "In6.Cu")
		(net "CPLD_NIC_MEZZ_ID0")
	)
	(segment
		(start 18.669 10.287)
		(end 17.605375 9.223375)
		(width 0.12065)
		(layer "In6.Cu")
		(net "CPLD_NIC_MEZZ_ID0")
	)
	(segment
		(start 17.272 8.762898)
		(end 17.272 2.7051)
		(width 0.12065)
		(layer "In6.Cu")
		(net "CPLD_NIC_MEZZ_ID0")
	)
	(segment
		(start 17.605375 9.096273)
		(end 17.272 8.762898)
		(width 0.12065)
		(layer "In6.Cu")
		(net "CPLD_NIC_MEZZ_ID0")
	)
	(segment
		(start 17.272 2.7051)
		(end 16.383 1.8161)
		(width 0.12065)
		(layer "In6.Cu")
		(net "CPLD_NIC_MEZZ_ID0")
	)
	(via
		(at 35.433 24.8412)
		(size 0.4572)
		(drill 0.20574)
		(layers "F.Cu" "B.Cu")
		(net "CNTRL_SPI_SCK")
	)
	(via
		(at 35.179 48.26)
		(size 0.508)
		(drill 0.25654)
		(layers "F.Cu" "B.Cu")
		(net "CNTRL_SPI_SCK")
	)
	(via
		(at 20.32 48.9585)
		(size 0.508)
		(drill 0.25654)
		(layers "F.Cu" "B.Cu")
		(net "CNTRL_SPI_SCK")
	)
	(segment
		(start 35.433 24.8412)
		(end 35.190989 24.548389)
		(width 0.127)
		(layer "In1.Cu")
		(net "CNTRL_SPI_SCK")
	)
	(segment
		(start 35.190989 24.548389)
		(end 34.246007 24.548389)
		(width 0.127)
		(layer "In1.Cu")
		(net "CNTRL_SPI_SCK")
	)
	(segment
		(start 33.696529 47.729927)
		(end 34.226602 48.26)
		(width 0.12065)
		(layer "In6.Cu")
		(net "CNTRL_SPI_SCK")
	)
	(segment
		(start 32.462953 48.079025)
		(end 32.81205 47.729927)
		(width 0.12065)
		(layer "In6.Cu")
		(net "CNTRL_SPI_SCK")
	)
	(segment
		(start 20.904073 48.374427)
		(end 22.110471 48.374427)
		(width 0.12065)
		(layer "In6.Cu")
		(net "CNTRL_SPI_SCK")
	)
	(segment
		(start 32.81205 47.729927)
		(end 33.696529 47.729927)
		(width 0.12065)
		(layer "In6.Cu")
		(net "CNTRL_SPI_SCK")
	)
	(segment
		(start 29.981627 48.440975)
		(end 30.343577 48.079025)
		(width 0.12065)
		(layer "In6.Cu")
		(net "CNTRL_SPI_SCK")
	)
	(segment
		(start 22.469373 48.015525)
		(end 25.771323 48.015525)
		(width 0.12065)
		(layer "In6.Cu")
		(net "CNTRL_SPI_SCK")
	)
	(segment
		(start 29.05158 48.440975)
		(end 29.981627 48.440975)
		(width 0.12065)
		(layer "In6.Cu")
		(net "CNTRL_SPI_SCK")
	)
	(segment
		(start 28.30863 47.698025)
		(end 29.05158 48.440975)
		(width 0.12065)
		(layer "In6.Cu")
		(net "CNTRL_SPI_SCK")
	)
	(segment
		(start 30.343577 48.079025)
		(end 32.462953 48.079025)
		(width 0.12065)
		(layer "In6.Cu")
		(net "CNTRL_SPI_SCK")
	)
	(segment
		(start 25.771323 48.015525)
		(end 26.088823 47.698025)
		(width 0.12065)
		(layer "In6.Cu")
		(net "CNTRL_SPI_SCK")
	)
	(segment
		(start 26.088823 47.698025)
		(end 28.30863 47.698025)
		(width 0.12065)
		(layer "In6.Cu")
		(net "CNTRL_SPI_SCK")
	)
	(segment
		(start 20.32 48.9585)
		(end 20.904073 48.374427)
		(width 0.12065)
		(layer "In6.Cu")
		(net "CNTRL_SPI_SCK")
	)
	(segment
		(start 34.226602 48.26)
		(end 35.179 48.26)
		(width 0.12065)
		(layer "In6.Cu")
		(net "CNTRL_SPI_SCK")
	)
	(segment
		(start 22.110471 48.374427)
		(end 22.469373 48.015525)
		(width 0.12065)
		(layer "In6.Cu")
		(net "CNTRL_SPI_SCK")
	)
	(segment
		(start 35.179 37.459158)
		(end 35.179 37.310746)
		(width 0.12065)
		(layer "In7.Cu")
		(net "CNTRL_SPI_SCK")
	)
	(segment
		(start 35.786746 36.703)
		(end 36.195025 36.703)
		(width 0.12065)
		(layer "In7.Cu")
		(net "CNTRL_SPI_SCK")
	)
	(segment
		(start 35.179 48.26)
		(end 35.123476 48.258374)
		(width 0.12065)
		(layer "In7.Cu")
		(net "CNTRL_SPI_SCK")
	)
	(segment
		(start 33.683448 40.103552)
		(end 34.236025 39.550975)
		(width 0.12065)
		(layer "In7.Cu")
		(net "CNTRL_SPI_SCK")
	)
	(segment
		(start 36.322 34.491346)
		(end 36.322 32.740498)
		(width 0.12065)
		(layer "In7.Cu")
		(net "CNTRL_SPI_SCK")
	)
	(segment
		(start 33.899805 42.027805)
		(end 33.861375 41.989375)
		(width 0.12065)
		(layer "In7.Cu")
		(net "CNTRL_SPI_SCK")
	)
	(segment
		(start 36.963223 26.890751)
		(end 36.963223 26.475411)
		(width 0.12065)
		(layer "In7.Cu")
		(net "CNTRL_SPI_SCK")
	)
	(segment
		(start 34.236025 38.979373)
		(end 34.470975 38.744423)
		(width 0.12065)
		(layer "In7.Cu")
		(net "CNTRL_SPI_SCK")
	)
	(segment
		(start 35.8648 25.273)
		(end 35.433 24.8412)
		(width 0.12065)
		(layer "In7.Cu")
		(net "CNTRL_SPI_SCK")
	)
	(segment
		(start 34.236025 39.550975)
		(end 34.236025 38.979373)
		(width 0.12065)
		(layer "In7.Cu")
		(net "CNTRL_SPI_SCK")
	)
	(segment
		(start 36.344225 36.5538)
		(end 36.344225 35.582225)
		(width 0.12065)
		(layer "In7.Cu")
		(net "CNTRL_SPI_SCK")
	)
	(segment
		(start 36.963223 26.475411)
		(end 37.023675 26.414959)
		(width 0.12065)
		(layer "In7.Cu")
		(net "CNTRL_SPI_SCK")
	)
	(segment
		(start 36.393145 25.273)
		(end 35.8648 25.273)
		(width 0.12065)
		(layer "In7.Cu")
		(net "CNTRL_SPI_SCK")
	)
	(segment
		(start 34.236025 43.253127)
		(end 33.982025 42.999127)
		(width 0.12065)
		(layer "In7.Cu")
		(net "CNTRL_SPI_SCK")
	)
	(segment
		(start 35.179 37.310746)
		(end 35.786746 36.703)
		(width 0.12065)
		(layer "In7.Cu")
		(net "CNTRL_SPI_SCK")
	)
	(segment
		(start 34.470975 38.744423)
		(end 34.470975 38.167183)
		(width 0.12065)
		(layer "In7.Cu")
		(net "CNTRL_SPI_SCK")
	)
	(segment
		(start 33.093025 40.655773)
		(end 33.645246 40.103552)
		(width 0.12065)
		(layer "In7.Cu")
		(net "CNTRL_SPI_SCK")
	)
	(segment
		(start 34.236025 47.371)
		(end 34.236025 43.253127)
		(width 0.12065)
		(layer "In7.Cu")
		(net "CNTRL_SPI_SCK")
	)
	(segment
		(start 36.344225 35.582225)
		(end 36.071175 35.309175)
		(width 0.12065)
		(layer "In7.Cu")
		(net "CNTRL_SPI_SCK")
	)
	(segment
		(start 33.982025 42.217899)
		(end 33.899805 42.027805)
		(width 0.12065)
		(layer "In7.Cu")
		(net "CNTRL_SPI_SCK")
	)
	(segment
		(start 34.470975 38.167183)
		(end 35.179 37.459158)
		(width 0.12065)
		(layer "In7.Cu")
		(net "CNTRL_SPI_SCK")
	)
	(segment
		(start 35.123476 48.258374)
		(end 34.236025 47.371)
		(width 0.12065)
		(layer "In7.Cu")
		(net "CNTRL_SPI_SCK")
	)
	(segment
		(start 36.195025 36.703)
		(end 36.344225 36.5538)
		(width 0.12065)
		(layer "In7.Cu")
		(net "CNTRL_SPI_SCK")
	)
	(segment
		(start 33.093025 41.437027)
		(end 33.093025 40.655773)
		(width 0.12065)
		(layer "In7.Cu")
		(net "CNTRL_SPI_SCK")
	)
	(segment
		(start 36.071175 35.309175)
		(end 36.071175 34.742171)
		(width 0.12065)
		(layer "In7.Cu")
		(net "CNTRL_SPI_SCK")
	)
	(segment
		(start 37.023675 32.038823)
		(end 37.023675 26.951203)
		(width 0.12065)
		(layer "In7.Cu")
		(net "CNTRL_SPI_SCK")
	)
	(segment
		(start 36.322 32.740498)
		(end 37.023675 32.038823)
		(width 0.12065)
		(layer "In7.Cu")
		(net "CNTRL_SPI_SCK")
	)
	(segment
		(start 33.982025 42.999127)
		(end 33.982025 42.217899)
		(width 0.12065)
		(layer "In7.Cu")
		(net "CNTRL_SPI_SCK")
	)
	(segment
		(start 33.645246 40.103552)
		(end 33.683448 40.103552)
		(width 0.12065)
		(layer "In7.Cu")
		(net "CNTRL_SPI_SCK")
	)
	(segment
		(start 33.645373 41.989375)
		(end 33.093025 41.437027)
		(width 0.12065)
		(layer "In7.Cu")
		(net "CNTRL_SPI_SCK")
	)
	(segment
		(start 37.023675 25.90353)
		(end 36.393145 25.273)
		(width 0.12065)
		(layer "In7.Cu")
		(net "CNTRL_SPI_SCK")
	)
	(segment
		(start 37.023675 26.951203)
		(end 36.963223 26.890751)
		(width 0.12065)
		(layer "In7.Cu")
		(net "CNTRL_SPI_SCK")
	)
	(segment
		(start 36.071175 34.742171)
		(end 36.322 34.491346)
		(width 0.12065)
		(layer "In7.Cu")
		(net "CNTRL_SPI_SCK")
	)
	(segment
		(start 37.023675 26.414959)
		(end 37.023675 25.90353)
		(width 0.12065)
		(layer "In7.Cu")
		(net "CNTRL_SPI_SCK")
	)
	(segment
		(start 33.861375 41.989375)
		(end 33.645373 41.989375)
		(width 0.12065)
		(layer "In7.Cu")
		(net "CNTRL_SPI_SCK")
	)
	(segment
		(start 34.746006 24.04839)
		(end 35.139655 24.04839)
		(width 0.127)
		(layer "F.Cu")
		(net "CNTRL_SPI_MOSI")
	)
	(segment
		(start 35.139655 24.04839)
		(end 35.259366 24.1681)
		(width 0.127)
		(layer "F.Cu")
		(net "CNTRL_SPI_MOSI")
	)
	(segment
		(start 35.8521 23.922634)
		(end 35.8521 23.9141)
		(width 0.127)
		(layer "F.Cu")
		(net "CNTRL_SPI_MOSI")
	)
	(segment
		(start 35.606634 24.1681)
		(end 35.8521 23.922634)
		(width 0.127)
		(layer "F.Cu")
		(net "CNTRL_SPI_MOSI")
	)
	(segment
		(start 36.0807 23.9141)
		(end 36.2458 23.749)
		(width 0.127)
		(layer "F.Cu")
		(net "CNTRL_SPI_MOSI")
	)
	(segment
		(start 35.259366 24.1681)
		(end 35.606634 24.1681)
		(width 0.127)
		(layer "F.Cu")
		(net "CNTRL_SPI_MOSI")
	)
	(segment
		(start 35.8521 23.9141)
		(end 36.0807 23.9141)
		(width 0.127)
		(layer "F.Cu")
		(net "CNTRL_SPI_MOSI")
	)
	(via
		(at 21.59 48.9585)
		(size 0.508)
		(drill 0.25654)
		(layers "F.Cu" "B.Cu")
		(net "CNTRL_SPI_MOSI")
	)
	(via
		(at 36.703 48.641)
		(size 0.508)
		(drill 0.25654)
		(layers "F.Cu" "B.Cu")
		(net "CNTRL_SPI_MOSI")
	)
	(via
		(at 36.2458 23.749)
		(size 0.4572)
		(drill 0.20574)
		(layers "F.Cu" "B.Cu")
		(net "CNTRL_SPI_MOSI")
	)
	(segment
		(start 33.051902 48.199675)
		(end 32.670902 48.580675)
		(width 0.12065)
		(layer "In6.Cu")
		(net "CNTRL_SPI_MOSI")
	)
	(segment
		(start 28.645028 48.688625)
		(end 28.210053 48.25365)
		(width 0.12065)
		(layer "In6.Cu")
		(net "CNTRL_SPI_MOSI")
	)
	(segment
		(start 31.586221 48.688625)
		(end 28.645028 48.688625)
		(width 0.12065)
		(layer "In6.Cu")
		(net "CNTRL_SPI_MOSI")
	)
	(segment
		(start 28.210053 48.25365)
		(end 26.242797 48.25365)
		(width 0.12065)
		(layer "In6.Cu")
		(net "CNTRL_SPI_MOSI")
	)
	(segment
		(start 33.456829 48.199675)
		(end 33.051902 48.199675)
		(width 0.12065)
		(layer "In6.Cu")
		(net "CNTRL_SPI_MOSI")
	)
	(segment
		(start 36.703 48.641)
		(end 36.642675 48.701325)
		(width 0.12065)
		(layer "In6.Cu")
		(net "CNTRL_SPI_MOSI")
	)
	(segment
		(start 26.242797 48.25365)
		(end 25.979272 48.517175)
		(width 0.12065)
		(layer "In6.Cu")
		(net "CNTRL_SPI_MOSI")
	)
	(segment
		(start 31.694171 48.580675)
		(end 31.586221 48.688625)
		(width 0.12065)
		(layer "In6.Cu")
		(net "CNTRL_SPI_MOSI")
	)
	(segment
		(start 22.235846 48.9585)
		(end 21.59 48.9585)
		(width 0.12065)
		(layer "In6.Cu")
		(net "CNTRL_SPI_MOSI")
	)
	(segment
		(start 32.670902 48.580675)
		(end 31.694171 48.580675)
		(width 0.12065)
		(layer "In6.Cu")
		(net "CNTRL_SPI_MOSI")
	)
	(segment
		(start 36.642675 48.701325)
		(end 33.958479 48.701325)
		(width 0.12065)
		(layer "In6.Cu")
		(net "CNTRL_SPI_MOSI")
	)
	(segment
		(start 33.958479 48.701325)
		(end 33.456829 48.199675)
		(width 0.12065)
		(layer "In6.Cu")
		(net "CNTRL_SPI_MOSI")
	)
	(segment
		(start 22.677171 48.517175)
		(end 22.235846 48.9585)
		(width 0.12065)
		(layer "In6.Cu")
		(net "CNTRL_SPI_MOSI")
	)
	(segment
		(start 25.979272 48.517175)
		(end 22.677171 48.517175)
		(width 0.12065)
		(layer "In6.Cu")
		(net "CNTRL_SPI_MOSI")
	)
	(segment
		(start 34.748622 39.747825)
		(end 33.891372 40.605075)
		(width 0.12065)
		(layer "In7.Cu")
		(net "CNTRL_SPI_MOSI")
	)
	(segment
		(start 36.680775 33.091171)
		(end 36.680775 33.456829)
		(width 0.12065)
		(layer "In7.Cu")
		(net "CNTRL_SPI_MOSI")
	)
	(segment
		(start 34.737675 46.277479)
		(end 34.737675 46.918829)
		(width 0.12065)
		(layer "In7.Cu")
		(net "CNTRL_SPI_MOSI")
	)
	(segment
		(start 34.792869 44.201715)
		(end 35.620325 45.029171)
		(width 0.12065)
		(layer "In7.Cu")
		(net "CNTRL_SPI_MOSI")
	)
	(segment
		(start 37.525325 32.520534)
		(end 37.213184 32.832675)
		(width 0.12065)
		(layer "In7.Cu")
		(net "CNTRL_SPI_MOSI")
	)
	(segment
		(start 36.82365 34.28365)
		(end 37.084 34.544)
		(width 0.12065)
		(layer "In7.Cu")
		(net "CNTRL_SPI_MOSI")
	)
	(segment
		(start 36.449 48.641)
		(end 36.703 48.641)
		(width 0.12065)
		(layer "In7.Cu")
		(net "CNTRL_SPI_MOSI")
	)
	(segment
		(start 36.2458 24.287455)
		(end 36.637341 24.678996)
		(width 0.12065)
		(layer "In7.Cu")
		(net "CNTRL_SPI_MOSI")
	)
	(segment
		(start 36.923929 38.554025)
		(end 36.558271 38.554025)
		(width 0.12065)
		(layer "In7.Cu")
		(net "CNTRL_SPI_MOSI")
	)
	(segment
		(start 33.594675 41.229229)
		(end 33.853171 41.487725)
		(width 0.12065)
		(layer "In7.Cu")
		(net "CNTRL_SPI_MOSI")
	)
	(segment
		(start 35.620325 39.489329)
		(end 35.361829 39.747825)
		(width 0.12065)
		(layer "In7.Cu")
		(net "CNTRL_SPI_MOSI")
	)
	(segment
		(start 33.853171 41.487725)
		(end 34.069172 41.487725)
		(width 0.12065)
		(layer "In7.Cu")
		(net "CNTRL_SPI_MOSI")
	)
	(segment
		(start 36.545571 38.541325)
		(end 35.880675 38.541325)
		(width 0.12065)
		(layer "In7.Cu")
		(net "CNTRL_SPI_MOSI")
	)
	(segment
		(start 38.033325 28.884829)
		(end 37.973 28.945154)
		(width 0.12065)
		(layer "In7.Cu")
		(net "CNTRL_SPI_MOSI")
	)
	(segment
		(start 37.084 35.306)
		(end 37.267769 35.489769)
		(width 0.12065)
		(layer "In7.Cu")
		(net "CNTRL_SPI_MOSI")
	)
	(segment
		(start 35.620325 45.029171)
		(end 35.620325 45.394829)
		(width 0.12065)
		(layer "In7.Cu")
		(net "CNTRL_SPI_MOSI")
	)
	(segment
		(start 36.680775 33.456829)
		(end 36.82365 33.599704)
		(width 0.12065)
		(layer "In7.Cu")
		(net "CNTRL_SPI_MOSI")
	)
	(segment
		(start 34.79165 46.98365)
		(end 36.449 48.641)
		(width 0.12065)
		(layer "In7.Cu")
		(net "CNTRL_SPI_MOSI")
	)
	(segment
		(start 33.853171 40.605075)
		(end 33.594675 40.863571)
		(width 0.12065)
		(layer "In7.Cu")
		(net "CNTRL_SPI_MOSI")
	)
	(segment
		(start 36.82365 33.599704)
		(end 36.82365 34.28365)
		(width 0.12065)
		(layer "In7.Cu")
		(net "CNTRL_SPI_MOSI")
	)
	(segment
		(start 34.737675 46.918829)
		(end 34.79165 46.972804)
		(width 0.12065)
		(layer "In7.Cu")
		(net "CNTRL_SPI_MOSI")
	)
	(segment
		(start 37.213184 32.832675)
		(end 36.939271 32.832675)
		(width 0.12065)
		(layer "In7.Cu")
		(net "CNTRL_SPI_MOSI")
	)
	(segment
		(start 35.620325 38.801675)
		(end 35.620325 39.489329)
		(width 0.12065)
		(layer "In7.Cu")
		(net "CNTRL_SPI_MOSI")
	)
	(segment
		(start 34.792869 43.100523)
		(end 34.792869 44.201715)
		(width 0.12065)
		(layer "In7.Cu")
		(net "CNTRL_SPI_MOSI")
	)
	(segment
		(start 35.361829 39.747825)
		(end 34.748622 39.747825)
		(width 0.12065)
		(layer "In7.Cu")
		(net "CNTRL_SPI_MOSI")
	)
	(segment
		(start 36.939271 32.832675)
		(end 36.680775 33.091171)
		(width 0.12065)
		(layer "In7.Cu")
		(net "CNTRL_SPI_MOSI")
	)
	(segment
		(start 34.069172 41.487725)
		(end 34.483675 41.902228)
		(width 0.12065)
		(layer "In7.Cu")
		(net "CNTRL_SPI_MOSI")
	)
	(segment
		(start 36.2458 23.749)
		(end 36.2458 24.287455)
		(width 0.12065)
		(layer "In7.Cu")
		(net "CNTRL_SPI_MOSI")
	)
	(segment
		(start 36.558271 38.554025)
		(end 36.545571 38.541325)
		(width 0.12065)
		(layer "In7.Cu")
		(net "CNTRL_SPI_MOSI")
	)
	(segment
		(start 34.483675 42.791329)
		(end 34.792869 43.100523)
		(width 0.12065)
		(layer "In7.Cu")
		(net "CNTRL_SPI_MOSI")
	)
	(segment
		(start 36.637341 24.678996)
		(end 36.637341 24.699341)
		(width 0.12065)
		(layer "In7.Cu")
		(net "CNTRL_SPI_MOSI")
	)
	(segment
		(start 34.483675 41.902228)
		(end 34.483675 42.791329)
		(width 0.12065)
		(layer "In7.Cu")
		(net "CNTRL_SPI_MOSI")
	)
	(segment
		(start 37.973 31.877)
		(end 37.525325 32.324675)
		(width 0.12065)
		(layer "In7.Cu")
		(net "CNTRL_SPI_MOSI")
	)
	(segment
		(start 37.525325 32.324675)
		(end 37.525325 32.520534)
		(width 0.12065)
		(layer "In7.Cu")
		(net "CNTRL_SPI_MOSI")
	)
	(segment
		(start 38.033325 27.251406)
		(end 38.033325 28.884829)
		(width 0.12065)
		(layer "In7.Cu")
		(net "CNTRL_SPI_MOSI")
	)
	(segment
		(start 37.973 28.945154)
		(end 37.973 31.877)
		(width 0.12065)
		(layer "In7.Cu")
		(net "CNTRL_SPI_MOSI")
	)
	(segment
		(start 33.594675 40.863571)
		(end 33.594675 41.229229)
		(width 0.12065)
		(layer "In7.Cu")
		(net "CNTRL_SPI_MOSI")
	)
	(segment
		(start 34.79165 46.972804)
		(end 34.79165 46.98365)
		(width 0.12065)
		(layer "In7.Cu")
		(net "CNTRL_SPI_MOSI")
	)
	(segment
		(start 36.637341 24.699341)
		(end 37.451919 25.513919)
		(width 0.12065)
		(layer "In7.Cu")
		(net "CNTRL_SPI_MOSI")
	)
	(segment
		(start 35.880675 38.541325)
		(end 35.620325 38.801675)
		(width 0.12065)
		(layer "In7.Cu")
		(net "CNTRL_SPI_MOSI")
	)
	(segment
		(start 37.267769 35.489769)
		(end 37.267769 38.210185)
		(width 0.12065)
		(layer "In7.Cu")
		(net "CNTRL_SPI_MOSI")
	)
	(segment
		(start 37.084 34.544)
		(end 37.084 35.306)
		(width 0.12065)
		(layer "In7.Cu")
		(net "CNTRL_SPI_MOSI")
	)
	(segment
		(start 37.267769 38.210185)
		(end 36.923929 38.554025)
		(width 0.12065)
		(layer "In7.Cu")
		(net "CNTRL_SPI_MOSI")
	)
	(segment
		(start 37.451919 26.67)
		(end 38.033325 27.251406)
		(width 0.12065)
		(layer "In7.Cu")
		(net "CNTRL_SPI_MOSI")
	)
	(segment
		(start 37.451919 25.513919)
		(end 37.451919 26.67)
		(width 0.12065)
		(layer "In7.Cu")
		(net "CNTRL_SPI_MOSI")
	)
	(segment
		(start 35.620325 45.394829)
		(end 34.737675 46.277479)
		(width 0.12065)
		(layer "In7.Cu")
		(net "CNTRL_SPI_MOSI")
	)
	(segment
		(start 33.891372 40.605075)
		(end 33.853171 40.605075)
		(width 0.12065)
		(layer "In7.Cu")
		(net "CNTRL_SPI_MOSI")
	)
	(segment
		(start 33.147 24.4602)
		(end 33.235189 24.548389)
		(width 0.14732)
		(layer "F.Cu")
		(net "CNTRL_SPI_MISO")
	)
	(segment
		(start 33.235189 24.548389)
		(end 33.746008 24.548389)
		(width 0.14732)
		(layer "F.Cu")
		(net "CNTRL_SPI_MISO")
	)
	(via
		(at 29.337 47.752)
		(size 0.508)
		(drill 0.254)
		(layers "F.Cu" "B.Cu")
		(net "CNTRL_SPI_MISO")
	)
	(via
		(at 38.989 48.641)
		(size 0.508)
		(drill 0.25654)
		(layers "F.Cu" "B.Cu")
		(net "CNTRL_SPI_MISO")
	)
	(via
		(at 33.147 24.4602)
		(size 0.4572)
		(drill 0.20574)
		(layers "F.Cu" "B.Cu")
		(net "CNTRL_SPI_MISO")
	)
	(via
		(at 22.86 48.9585)
		(size 0.508)
		(drill 0.25654)
		(layers "F.Cu" "B.Cu")
		(net "CNTRL_SPI_MISO")
	)
	(segment
		(start 29.464 48.514)
		(end 23.3045 48.514)
		(width 0.12065)
		(layer "In2.Cu")
		(net "CNTRL_SPI_MISO")
	)
	(segment
		(start 36.957 48.133)
		(end 35.930154 48.133)
		(width 0.12065)
		(layer "In2.Cu")
		(net "CNTRL_SPI_MISO")
	)
	(segment
		(start 33.908975 48.133)
		(end 29.845 48.133)
		(width 0.12065)
		(layer "In2.Cu")
		(net "CNTRL_SPI_MISO")
	)
	(segment
		(start 37.719 48.895)
		(end 36.957 48.133)
		(width 0.12065)
		(layer "In2.Cu")
		(net "CNTRL_SPI_MISO")
	)
	(segment
		(start 38.735 48.387)
		(end 38.989 48.641)
		(width 0.12065)
		(layer "In2.Cu")
		(net "CNTRL_SPI_MISO")
	)
	(segment
		(start 38.989 48.641)
		(end 38.735 48.895)
		(width 0.12065)
		(layer "In2.Cu")
		(net "CNTRL_SPI_MISO")
	)
	(segment
		(start 37.719 47.752)
		(end 38.354 48.387)
		(width 0.12065)
		(layer "In2.Cu")
		(net "CNTRL_SPI_MISO")
	)
	(segment
		(start 29.337 47.752)
		(end 37.719 47.752)
		(width 0.12065)
		(layer "In2.Cu")
		(net "CNTRL_SPI_MISO")
	)
	(segment
		(start 35.930154 48.133)
		(end 35.361829 48.701325)
		(width 0.12065)
		(layer "In2.Cu")
		(net "CNTRL_SPI_MISO")
	)
	(segment
		(start 23.3045 48.514)
		(end 22.86 48.9585)
		(width 0.12065)
		(layer "In2.Cu")
		(net "CNTRL_SPI_MISO")
	)
	(segment
		(start 29.845 48.133)
		(end 29.464 48.514)
		(width 0.12065)
		(layer "In2.Cu")
		(net "CNTRL_SPI_MISO")
	)
	(segment
		(start 35.361829 48.701325)
		(end 34.4773 48.701325)
		(width 0.12065)
		(layer "In2.Cu")
		(net "CNTRL_SPI_MISO")
	)
	(segment
		(start 34.4773 48.701325)
		(end 33.908975 48.133)
		(width 0.12065)
		(layer "In2.Cu")
		(net "CNTRL_SPI_MISO")
	)
	(segment
		(start 38.354 48.387)
		(end 38.735 48.387)
		(width 0.12065)
		(layer "In2.Cu")
		(net "CNTRL_SPI_MISO")
	)
	(segment
		(start 38.735 48.895)
		(end 37.719 48.895)
		(width 0.12065)
		(layer "In2.Cu")
		(net "CNTRL_SPI_MISO")
	)
	(segment
		(start 30.91114 38.877875)
		(end 30.48 39.309015)
		(width 0.12065)
		(layer "In7.Cu")
		(net "CNTRL_SPI_MISO")
	)
	(segment
		(start 31.03311 38.877875)
		(end 30.91114 38.877875)
		(width 0.12065)
		(layer "In7.Cu")
		(net "CNTRL_SPI_MISO")
	)
	(segment
		(start 31.75 38.160985)
		(end 31.03311 38.877875)
		(width 0.12065)
		(layer "In7.Cu")
		(net "CNTRL_SPI_MISO")
	)
	(segment
		(start 33.949259 30.834584)
		(end 34.096325 30.98165)
		(width 0.12065)
		(layer "In7.Cu")
		(net "CNTRL_SPI_MISO")
	)
	(segment
		(start 33.02 33.401)
		(end 33.02 35.179)
		(width 0.12065)
		(layer "In7.Cu")
		(net "CNTRL_SPI_MISO")
	)
	(segment
		(start 33.147 24.4602)
		(end 33.284947 24.4602)
		(width 0.12065)
		(layer "In7.Cu")
		(net "CNTRL_SPI_MISO")
	)
	(segment
		(start 31.75 36.449)
		(end 31.75 38.160985)
		(width 0.12065)
		(layer "In7.Cu")
		(net "CNTRL_SPI_MISO")
	)
	(segment
		(start 30.48 39.497)
		(end 28.832175 41.144825)
		(width 0.12065)
		(layer "In7.Cu")
		(net "CNTRL_SPI_MISO")
	)
	(segment
		(start 33.949259 25.124512)
		(end 33.949259 30.834584)
		(width 0.12065)
		(layer "In7.Cu")
		(net "CNTRL_SPI_MISO")
	)
	(segment
		(start 33.284947 24.4602)
		(end 33.949259 25.124512)
		(width 0.12065)
		(layer "In7.Cu")
		(net "CNTRL_SPI_MISO")
	)
	(segment
		(start 28.832175 41.144825)
		(end 28.832175 47.247175)
		(width 0.12065)
		(layer "In7.Cu")
		(net "CNTRL_SPI_MISO")
	)
	(segment
		(start 34.096325 30.98165)
		(end 34.096325 32.324675)
		(width 0.12065)
		(layer "In7.Cu")
		(net "CNTRL_SPI_MISO")
	)
	(segment
		(start 30.48 39.309015)
		(end 30.48 39.497)
		(width 0.12065)
		(layer "In7.Cu")
		(net "CNTRL_SPI_MISO")
	)
	(segment
		(start 33.02 35.179)
		(end 31.75 36.449)
		(width 0.12065)
		(layer "In7.Cu")
		(net "CNTRL_SPI_MISO")
	)
	(segment
		(start 34.096325 32.324675)
		(end 33.02 33.401)
		(width 0.12065)
		(layer "In7.Cu")
		(net "CNTRL_SPI_MISO")
	)
	(segment
		(start 28.832175 47.247175)
		(end 29.337 47.752)
		(width 0.12065)
		(layer "In7.Cu")
		(net "CNTRL_SPI_MISO")
	)
	(via
		(at 40.894 48.641)
		(size 0.508)
		(drill 0.25654)
		(layers "F.Cu" "B.Cu")
		(net "CNTRL_SPI_CS")
	)
	(via
		(at 35.433 23.749)
		(size 0.4572)
		(drill 0.20574)
		(layers "F.Cu" "B.Cu")
		(net "CNTRL_SPI_CS")
	)
	(via
		(at 24.13 48.9585)
		(size 0.508)
		(drill 0.25654)
		(layers "F.Cu" "B.Cu")
		(net "CNTRL_SPI_CS")
	)
	(via
		(at 31.877 49.022)
		(size 0.508)
		(drill 0.254)
		(layers "F.Cu" "B.Cu")
		(net "CNTRL_SPI_CS")
	)
	(segment
		(start 35.13361 24.04839)
		(end 35.433 23.749)
		(width 0.127)
		(layer "In1.Cu")
		(net "CNTRL_SPI_CS")
	)
	(segment
		(start 34.246007 24.04839)
		(end 35.13361 24.04839)
		(width 0.127)
		(layer "In1.Cu")
		(net "CNTRL_SPI_CS")
	)
	(segment
		(start 32.119672 49.264672)
		(end 31.877 49.022)
		(width 0.12065)
		(layer "In6.Cu")
		(net "CNTRL_SPI_CS")
	)
	(segment
		(start 28.122804 48.517175)
		(end 26.412825 48.517175)
		(width 0.12065)
		(layer "In6.Cu")
		(net "CNTRL_SPI_CS")
	)
	(segment
		(start 26.412825 48.517175)
		(end 25.9715 48.9585)
		(width 0.12065)
		(layer "In6.Cu")
		(net "CNTRL_SPI_CS")
	)
	(segment
		(start 31.877 49.022)
		(end 28.627629 49.022)
		(width 0.12065)
		(layer "In6.Cu")
		(net "CNTRL_SPI_CS")
	)
	(segment
		(start 25.9715 48.9585)
		(end 24.13 48.9585)
		(width 0.12065)
		(layer "In6.Cu")
		(net "CNTRL_SPI_CS")
	)
	(segment
		(start 38.354 49.403)
		(end 38.215672 49.264672)
		(width 0.12065)
		(layer "In6.Cu")
		(net "CNTRL_SPI_CS")
	)
	(segment
		(start 40.894 48.641)
		(end 40.132 49.403)
		(width 0.12065)
		(layer "In6.Cu")
		(net "CNTRL_SPI_CS")
	)
	(segment
		(start 38.215672 49.264672)
		(end 32.119672 49.264672)
		(width 0.12065)
		(layer "In6.Cu")
		(net "CNTRL_SPI_CS")
	)
	(segment
		(start 28.627629 49.022)
		(end 28.122804 48.517175)
		(width 0.12065)
		(layer "In6.Cu")
		(net "CNTRL_SPI_CS")
	)
	(segment
		(start 40.132 49.403)
		(end 38.354 49.403)
		(width 0.12065)
		(layer "In6.Cu")
		(net "CNTRL_SPI_CS")
	)
	(segment
		(start 35.874325 31.424829)
		(end 35.520579 31.778575)
		(width 0.12065)
		(layer "In7.Cu")
		(net "CNTRL_SPI_CS")
	)
	(segment
		(start 32.343598 40.550694)
		(end 32.343598 40.966034)
		(width 0.12065)
		(layer "In7.Cu")
		(net "CNTRL_SPI_CS")
	)
	(segment
		(start 35.052 34.544)
		(end 33.782 35.814)
		(width 0.12065)
		(layer "In7.Cu")
		(net "CNTRL_SPI_CS")
	)
	(segment
		(start 32.766 48.133)
		(end 31.877 49.022)
		(width 0.12065)
		(layer "In7.Cu")
		(net "CNTRL_SPI_CS")
	)
	(segment
		(start 35.041459 24.678996)
		(end 35.041459 28.483204)
		(width 0.12065)
		(layer "In7.Cu")
		(net "CNTRL_SPI_CS")
	)
	(segment
		(start 34.991675 32.402729)
		(end 35.052 32.463054)
		(width 0.12065)
		(layer "In7.Cu")
		(net "CNTRL_SPI_CS")
	)
	(segment
		(start 32.343725 41.747491)
		(end 32.385 41.788766)
		(width 0.12065)
		(layer "In7.Cu")
		(net "CNTRL_SPI_CS")
	)
	(segment
		(start 32.343547 40.550643)
		(end 32.343598 40.550694)
		(width 0.12065)
		(layer "In7.Cu")
		(net "CNTRL_SPI_CS")
	)
	(segment
		(start 35.520579 31.778575)
		(end 35.250171 31.778575)
		(width 0.12065)
		(layer "In7.Cu")
		(net "CNTRL_SPI_CS")
	)
	(segment
		(start 33.721675 38.434035)
		(end 33.486725 38.668985)
		(width 0.12065)
		(layer "In7.Cu")
		(net "CNTRL_SPI_CS")
	)
	(segment
		(start 32.343598 40.966034)
		(end 32.343725 40.966161)
		(width 0.12065)
		(layer "In7.Cu")
		(net "CNTRL_SPI_CS")
	)
	(segment
		(start 35.250171 31.778575)
		(end 34.991675 32.037071)
		(width 0.12065)
		(layer "In7.Cu")
		(net "CNTRL_SPI_CS")
	)
	(segment
		(start 35.941 29.591)
		(end 35.941 30.861)
		(width 0.12065)
		(layer "In7.Cu")
		(net "CNTRL_SPI_CS")
	)
	(segment
		(start 35.041459 28.483204)
		(end 35.052 28.493745)
		(width 0.12065)
		(layer "In7.Cu")
		(net "CNTRL_SPI_CS")
	)
	(segment
		(start 33.486725 39.202385)
		(end 32.343547 40.345563)
		(width 0.12065)
		(layer "In7.Cu")
		(net "CNTRL_SPI_CS")
	)
	(segment
		(start 35.874325 30.927675)
		(end 35.874325 31.424829)
		(width 0.12065)
		(layer "In7.Cu")
		(net "CNTRL_SPI_CS")
	)
	(segment
		(start 34.991675 32.037071)
		(end 34.991675 32.402729)
		(width 0.12065)
		(layer "In7.Cu")
		(net "CNTRL_SPI_CS")
	)
	(segment
		(start 32.343725 40.966161)
		(end 32.343725 41.747491)
		(width 0.12065)
		(layer "In7.Cu")
		(net "CNTRL_SPI_CS")
	)
	(segment
		(start 35.941 30.861)
		(end 35.874325 30.927675)
		(width 0.12065)
		(layer "In7.Cu")
		(net "CNTRL_SPI_CS")
	)
	(segment
		(start 35.433 23.749)
		(end 35.052 24.13)
		(width 0.12065)
		(layer "In7.Cu")
		(net "CNTRL_SPI_CS")
	)
	(segment
		(start 35.052 24.13)
		(end 35.052 24.668455)
		(width 0.12065)
		(layer "In7.Cu")
		(net "CNTRL_SPI_CS")
	)
	(segment
		(start 35.052 28.702)
		(end 35.941 29.591)
		(width 0.12065)
		(layer "In7.Cu")
		(net "CNTRL_SPI_CS")
	)
	(segment
		(start 33.782 35.814)
		(end 33.782 37.796318)
		(width 0.12065)
		(layer "In7.Cu")
		(net "CNTRL_SPI_CS")
	)
	(segment
		(start 35.052 24.668455)
		(end 35.041459 24.678996)
		(width 0.12065)
		(layer "In7.Cu")
		(net "CNTRL_SPI_CS")
	)
	(segment
		(start 32.343547 40.345563)
		(end 32.343547 40.550643)
		(width 0.12065)
		(layer "In7.Cu")
		(net "CNTRL_SPI_CS")
	)
	(segment
		(start 32.385 41.788766)
		(end 32.385 42.926)
		(width 0.12065)
		(layer "In7.Cu")
		(net "CNTRL_SPI_CS")
	)
	(segment
		(start 33.782 37.796318)
		(end 33.721675 37.856643)
		(width 0.12065)
		(layer "In7.Cu")
		(net "CNTRL_SPI_CS")
	)
	(segment
		(start 32.766 43.307)
		(end 32.766 48.133)
		(width 0.12065)
		(layer "In7.Cu")
		(net "CNTRL_SPI_CS")
	)
	(segment
		(start 33.486725 38.668985)
		(end 33.486725 39.202385)
		(width 0.12065)
		(layer "In7.Cu")
		(net "CNTRL_SPI_CS")
	)
	(segment
		(start 35.052 28.493745)
		(end 35.052 28.702)
		(width 0.12065)
		(layer "In7.Cu")
		(net "CNTRL_SPI_CS")
	)
	(segment
		(start 32.385 42.926)
		(end 32.766 43.307)
		(width 0.12065)
		(layer "In7.Cu")
		(net "CNTRL_SPI_CS")
	)
	(segment
		(start 33.721675 37.856643)
		(end 33.721675 38.434035)
		(width 0.12065)
		(layer "In7.Cu")
		(net "CNTRL_SPI_CS")
	)
	(segment
		(start 35.052 32.463054)
		(end 35.052 34.544)
		(width 0.12065)
		(layer "In7.Cu")
		(net "CNTRL_SPI_CS")
	)
	(segment
		(start 61.737011 25.542011)
		(end 61.237012 25.042012)
		(width 0.13208)
		(layer "F.Cu")
		(net "A_DZQ1")
	)
	(via
		(at 61.737011 25.542011)
		(size 0.4826)
		(drill 0.20574)
		(layers "F.Cu" "B.Cu")
		(net "A_DZQ1")
	)
	(via
		(at 61.737011 26.400989)
		(size 0.762)
		(drill 0.381)
		(layers "F.Cu" "B.Cu")
		(net "A_DZQ1")
	)
	(segment
		(start 61.737011 25.542011)
		(end 61.737011 26.400989)
		(width 0.14732)
		(layer "B.Cu")
		(net "A_DZQ1")
	)
	(segment
		(start 61.737011 25.542011)
		(end 62.237036 25.041987)
		(width 0.14732)
		(layer "B.Cu")
		(net "A_DZQ1")
	)
	(segment
		(start 62.237036 25.041987)
		(end 62.237112 25.041987)
		(width 0.14732)
		(layer "B.Cu")
		(net "A_DZQ1")
	)
	(segment
		(start 61.737011 22.541992)
		(end 61.237012 22.041993)
		(width 0.13208)
		(layer "F.Cu")
		(net "A_DZQ0")
	)
	(via
		(at 61.737011 22.541992)
		(size 0.4826)
		(drill 0.20574)
		(layers "F.Cu" "B.Cu")
		(net "A_DZQ0")
	)
	(via
		(at 61.737011 23.479989)
		(size 0.762)
		(drill 0.381)
		(layers "F.Cu" "B.Cu")
		(net "A_DZQ0")
	)
	(segment
		(start 62.23701 22.041993)
		(end 62.237112 22.041993)
		(width 0.14732)
		(layer "B.Cu")
		(net "A_DZQ0")
	)
	(segment
		(start 61.737011 22.541992)
		(end 61.737011 23.479989)
		(width 0.14732)
		(layer "B.Cu")
		(net "A_DZQ0")
	)
	(segment
		(start 61.737011 22.541992)
		(end 62.23701 22.041993)
		(width 0.14732)
		(layer "B.Cu")
		(net "A_DZQ0")
	)
	(segment
		(start 62.737009 13.54201)
		(end 62.23701 14.042009)
		(width 0.13208)
		(layer "F.Cu")
		(net "A_AZQ")
	)
	(via
		(at 64.737005 16.542004)
		(size 0.4826)
		(drill 0.25654)
		(layers "F.Cu" "B.Cu")
		(net "A_AZQ")
	)
	(via
		(at 62.737009 13.54201)
		(size 0.4826)
		(drill 0.20574)
		(layers "F.Cu" "B.Cu")
		(net "A_AZQ")
	)
	(segment
		(start 62.236858 13.042011)
		(end 62.23701 13.042011)
		(width 0.254)
		(layer "B.Cu")
		(net "A_AZQ")
	)
	(segment
		(start 62.23701 13.042011)
		(end 62.737009 13.54201)
		(width 0.254)
		(layer "B.Cu")
		(net "A_AZQ")
	)
	(segment
		(start 63.119 14.923999)
		(end 63.119 14.097)
		(width 0.127)
		(layer "In6.Cu")
		(net "A_AZQ")
	)
	(segment
		(start 64.737005 16.542004)
		(end 63.119 14.923999)
		(width 0.127)
		(layer "In6.Cu")
		(net "A_AZQ")
	)
	(segment
		(start 62.737009 13.715009)
		(end 62.737009 13.54201)
		(width 0.127)
		(layer "In6.Cu")
		(net "A_AZQ")
	)
	(segment
		(start 63.119 14.097)
		(end 62.737009 13.715009)
		(width 0.127)
		(layer "In6.Cu")
		(net "A_AZQ")
	)
	(segment
		(start 73.152 27.7749)
		(end 73.147834 27.812771)
		(width 0.14732)
		(layer "F.Cu")
		(net "12N3294")
	)
	(segment
		(start 73.05101 29.712107)
		(end 73.05101 29.812996)
		(width 0.14732)
		(layer "F.Cu")
		(net "12N3294")
	)
	(segment
		(start 72.69734 29.358438)
		(end 73.05101 29.712107)
		(width 0.14732)
		(layer "F.Cu")
		(net "12N3294")
	)
	(segment
		(start 72.69734 28.263266)
		(end 72.69734 29.358438)
		(width 0.14732)
		(layer "F.Cu")
		(net "12N3294")
	)
	(segment
		(start 73.147834 27.812771)
		(end 72.69734 28.263266)
		(width 0.14732)
		(layer "F.Cu")
		(net "12N3294")
	)
	(via
		(at 69.85 28.575)
		(size 0.762)
		(drill 0.381)
		(layers "F.Cu" "B.Cu")
		(net "12N3294")
	)
	(via
		(at 73.05101 29.812996)
		(size 0.4572)
		(drill 0.20574)
		(layers "F.Cu" "B.Cu")
		(net "12N3294")
	)
	(segment
		(start 73.451009 29.001009)
		(end 73.451009 29.412997)
		(width 0.14732)
		(layer "B.Cu")
		(net "12N3294")
	)
	(segment
		(start 69.85 28.575)
		(end 73.025 28.575)
		(width 0.14732)
		(layer "B.Cu")
		(net "12N3294")
	)
	(segment
		(start 73.451009 29.412997)
		(end 73.05101 29.812996)
		(width 0.254)
		(layer "B.Cu")
		(net "12N3294")
	)
	(segment
		(start 73.025 28.575)
		(end 73.451009 29.001009)
		(width 0.14732)
		(layer "B.Cu")
		(net "12N3294")
	)
	(segment
		(start 72.263 29.801007)
		(end 72.251011 29.812996)
		(width 0.14732)
		(layer "F.Cu")
		(net "12N3293")
	)
	(segment
		(start 72.9869 26.797)
		(end 72.263 27.5209)
		(width 0.14732)
		(layer "F.Cu")
		(net "12N3293")
	)
	(segment
		(start 72.263 27.5209)
		(end 72.263 29.801007)
		(width 0.14732)
		(layer "F.Cu")
		(net "12N3293")
	)
	(via
		(at 72.251011 29.812996)
		(size 0.4572)
		(drill 0.20574)
		(layers "F.Cu" "B.Cu")
		(net "12N3293")
	)
	(via
		(at 69.85 29.845)
		(size 0.762)
		(drill 0.381)
		(layers "F.Cu" "B.Cu")
		(net "12N3293")
	)
	(segment
		(start 72.251011 29.812996)
		(end 69.85 29.845)
		(width 0.14732)
		(layer "B.Cu")
		(net "12N3293")
	)
	(segment
		(start 72.65101 29.412997)
		(end 72.251011 29.812996)
		(width 0.254)
		(layer "B.Cu")
		(net "12N3293")
	)
	(segment
		(start 73.152 25.8191)
		(end 73.844912 25.8191)
		(width 0.14732)
		(layer "F.Cu")
		(net "12N3291")
	)
	(segment
		(start 73.844912 25.8191)
		(end 73.851008 25.813004)
		(width 0.14732)
		(layer "F.Cu")
		(net "12N3291")
	)
	(via
		(at 73.851008 25.813004)
		(size 0.4572)
		(drill 0.20574)
		(layers "F.Cu" "B.Cu")
		(net "12N3291")
	)
	(via
		(at 69.596 27.051)
		(size 0.762)
		(drill 0.381)
		(layers "F.Cu" "B.Cu")
		(net "12N3291")
	)
	(segment
		(start 74.251007 26.840993)
		(end 74.251007 26.213003)
		(width 0.14732)
		(layer "B.Cu")
		(net "12N3291")
	)
	(segment
		(start 74.041 27.051)
		(end 74.251007 26.840993)
		(width 0.14732)
		(layer "B.Cu")
		(net "12N3291")
	)
	(segment
		(start 74.251007 26.213003)
		(end 73.851008 25.813004)
		(width 0.254)
		(layer "B.Cu")
		(net "12N3291")
	)
	(segment
		(start 69.596 27.051)
		(end 74.041 27.051)
		(width 0.14732)
		(layer "B.Cu")
		(net "12N3291")
	)
	(segment
		(start 80.137 31.314669)
		(end 80.137 32.157314)
		(width 0.14732)
		(layer "F.Cu")
		(net "12N3220")
	)
	(segment
		(start 80.250995 30.612994)
		(end 80.250995 31.200674)
		(width 0.14732)
		(layer "F.Cu")
		(net "12N3220")
	)
	(segment
		(start 80.250995 31.200674)
		(end 80.137 31.314669)
		(width 0.14732)
		(layer "F.Cu")
		(net "12N3220")
	)
	(via
		(at 80.250995 30.612994)
		(size 0.4572)
		(drill 0.20574)
		(layers "F.Cu" "B.Cu")
		(net "12N3220")
	)
	(via
		(at 80.250995 33.387995)
		(size 0.762)
		(drill 0.381)
		(layers "F.Cu" "B.Cu")
		(net "12N3220")
	)
	(segment
		(start 79.850996 30.212995)
		(end 80.250995 30.612994)
		(width 0.254)
		(layer "B.Cu")
		(net "12N3220")
	)
	(segment
		(start 80.250995 30.612994)
		(end 80.250995 33.387995)
		(width 0.14732)
		(layer "B.Cu")
		(net "12N3220")
	)
	(segment
		(start 79.5401 20.32)
		(end 79.2861 20.574)
		(width 0.14732)
		(layer "F.Cu")
		(net "12N3057")
	)
	(segment
		(start 80.01 19.788124)
		(end 80.01 19.95739)
		(width 0.14732)
		(layer "F.Cu")
		(net "12N3057")
	)
	(segment
		(start 80.01 19.95739)
		(end 79.64739 20.32)
		(width 0.14732)
		(layer "F.Cu")
		(net "12N3057")
	)
	(segment
		(start 80.250995 19.055994)
		(end 80.250995 19.547129)
		(width 0.14732)
		(layer "F.Cu")
		(net "12N3057")
	)
	(segment
		(start 80.250995 19.547129)
		(end 80.01 19.788124)
		(width 0.14732)
		(layer "F.Cu")
		(net "12N3057")
	)
	(segment
		(start 79.64739 20.32)
		(end 79.5401 20.32)
		(width 0.14732)
		(layer "F.Cu")
		(net "12N3057")
	)
	(via
		(at 80.250995 21.957995)
		(size 0.762)
		(drill 0.381)
		(layers "F.Cu" "B.Cu")
		(net "12N3057")
	)
	(via
		(at 80.250995 19.055994)
		(size 0.4572)
		(drill 0.20574)
		(layers "F.Cu" "B.Cu")
		(net "12N3057")
	)
	(segment
		(start 80.250995 19.055994)
		(end 80.250995 21.957995)
		(width 0.14732)
		(layer "B.Cu")
		(net "12N3057")
	)
	(segment
		(start 79.850996 18.655995)
		(end 80.250995 19.055994)
		(width 0.254)
		(layer "B.Cu")
		(net "12N3057")
	)
	(segment
		(start 79.502 9.271)
		(end 80.250995 8.522005)
		(width 0.14732)
		(layer "F.Cu")
		(net "12N2312")
	)
	(segment
		(start 80.250995 8.522005)
		(end 80.250995 7.498994)
		(width 0.14732)
		(layer "F.Cu")
		(net "12N2312")
	)
	(segment
		(start 78.3971 9.271)
		(end 79.502 9.271)
		(width 0.14732)
		(layer "F.Cu")
		(net "12N2312")
	)
	(via
		(at 80.250995 7.498994)
		(size 0.4572)
		(drill 0.20574)
		(layers "F.Cu" "B.Cu")
		(net "12N2312")
	)
	(via
		(at 80.250995 10.527995)
		(size 0.762)
		(drill 0.381)
		(layers "F.Cu" "B.Cu")
		(net "12N2312")
	)
	(segment
		(start 79.850996 7.098995)
		(end 80.250995 7.498994)
		(width 0.254)
		(layer "B.Cu")
		(net "12N2312")
	)
	(segment
		(start 80.250995 7.498994)
		(end 80.250995 10.527995)
		(width 0.14732)
		(layer "B.Cu")
		(net "12N2312")
	)
	(segment
		(start 15.6972 31.496)
		(end 14.478 31.496)
		(width 0.508)
		(layer "F.Cu")
		(net "11N2296")
	)
	(segment
		(start 15.8877 31.3055)
		(end 15.6972 31.496)
		(width 0.508)
		(layer "F.Cu")
		(net "11N2296")
	)
	(segment
		(start 16.256 32.437934)
		(end 16.256 34.500363)
		(width 0.381)
		(layer "F.Cu")
		(net "11N2296")
	)
	(via
		(at 14.478 31.496)
		(size 0.762)
		(drill 0.381)
		(layers "F.Cu" "B.Cu")
		(net "11N2296")
	)
	(segment
		(start 80.772 46.8503)
		(end 80.772 47.7139)
		(width 0.508)
		(layer "F.Cu")
		(net "11N2258")
	)
	(segment
		(start 80.772 47.7139)
		(end 80.8101 47.752)
		(width 0.508)
		(layer "F.Cu")
		(net "11N2258")
	)
	(via
		(at 80.772 46.8503)
		(size 0.508)
		(drill 0.25654)
		(layers "F.Cu" "B.Cu")
		(net "11N2258")
	)
	(via
		(at 83.185 44.831)
		(size 0.762)
		(drill 0.381)
		(layers "F.Cu" "B.Cu")
		(net "11N2253")
	)
	(segment
		(start 79.629 42.545)
		(end 79.845002 42.328998)
		(width 0.14732)
		(layer "F.Cu")
		(net "11N2202")
	)
	(segment
		(start 79.845002 42.328998)
		(end 80.137 42.328998)
		(width 0.14732)
		(layer "F.Cu")
		(net "11N2202")
	)
	(segment
		(start 79.629 43.053)
		(end 79.629 42.545)
		(width 0.14732)
		(layer "F.Cu")
		(net "11N2202")
	)
	(via
		(at 81.661 45.466)
		(size 0.762)
		(drill 0.381)
		(layers "F.Cu" "B.Cu")
		(net "11N2202")
	)
	(via
		(at 79.629 43.053)
		(size 0.508)
		(drill 0.254)
		(layers "F.Cu" "B.Cu")
		(net "11N2202")
	)
	(segment
		(start 79.93634 44.88434)
		(end 79.93634 44.94497)
		(width 0.14732)
		(layer "B.Cu")
		(net "11N2202")
	)
	(segment
		(start 79.629 44.419926)
		(end 79.629 44.577)
		(width 0.14732)
		(layer "B.Cu")
		(net "11N2202")
	)
	(segment
		(start 80.457345 45.466)
		(end 81.661 45.466)
		(width 0.14732)
		(layer "B.Cu")
		(net "11N2202")
	)
	(segment
		(start 79.93634 44.94497)
		(end 80.457345 45.466)
		(width 0.14732)
		(layer "B.Cu")
		(net "11N2202")
	)
	(segment
		(start 80.01 42.672)
		(end 79.629 43.053)
		(width 0.14732)
		(layer "B.Cu")
		(net "11N2202")
	)
	(segment
		(start 80.01 41.9227)
		(end 80.01 42.672)
		(width 0.14732)
		(layer "B.Cu")
		(net "11N2202")
	)
	(segment
		(start 79.629 43.053)
		(end 79.46644 43.21556)
		(width 0.14732)
		(layer "B.Cu")
		(net "11N2202")
	)
	(segment
		(start 79.46644 43.21556)
		(end 79.46644 44.257366)
		(width 0.14732)
		(layer "B.Cu")
		(net "11N2202")
	)
	(segment
		(start 79.46644 44.257366)
		(end 79.629 44.419926)
		(width 0.14732)
		(layer "B.Cu")
		(net "11N2202")
	)
	(segment
		(start 79.629 44.577)
		(end 79.93634 44.88434)
		(width 0.14732)
		(layer "B.Cu")
		(net "11N2202")
	)
	(segment
		(start 80.137 40.132)
		(end 80.137 40.729002)
		(width 0.14732)
		(layer "F.Cu")
		(net "11N2199")
	)
	(segment
		(start 80.391 38.1)
		(end 80.391 39.878)
		(width 0.14732)
		(layer "F.Cu")
		(net "11N2199")
	)
	(segment
		(start 81.4451 36.83)
		(end 82.169 36.1061)
		(width 0.14732)
		(layer "F.Cu")
		(net "11N2199")
	)
	(segment
		(start 80.391 39.878)
		(end 80.137 40.132)
		(width 0.14732)
		(layer "F.Cu")
		(net "11N2199")
	)
	(segment
		(start 80.391 38.1)
		(end 80.391 37.592)
		(width 0.14732)
		(layer "F.Cu")
		(net "11N2199")
	)
	(segment
		(start 81.153 36.83)
		(end 81.4451 36.83)
		(width 0.14732)
		(layer "F.Cu")
		(net "11N2199")
	)
	(segment
		(start 80.391 37.592)
		(end 81.153 36.83)
		(width 0.14732)
		(layer "F.Cu")
		(net "11N2199")
	)
	(via
		(at 80.391 38.1)
		(size 0.762)
		(drill 0.381)
		(layers "F.Cu" "B.Cu")
		(net "11N2199")
	)
	(segment
		(start 83.439 43.688)
		(end 82.169 43.688)
		(width 0.14732)
		(layer "F.Cu")
		(net "11N2191")
	)
	(segment
		(start 84.201 44.45)
		(end 83.439 43.688)
		(width 0.14732)
		(layer "F.Cu")
		(net "11N2191")
	)
	(segment
		(start 84.455 44.45)
		(end 84.201 44.45)
		(width 0.14732)
		(layer "F.Cu")
		(net "11N2191")
	)
	(segment
		(start 82.035599 43.554599)
		(end 82.035599 43.0276)
		(width 0.14732)
		(layer "F.Cu")
		(net "11N2191")
	)
	(segment
		(start 82.169 43.688)
		(end 82.035599 43.554599)
		(width 0.14732)
		(layer "F.Cu")
		(net "11N2191")
	)
	(via
		(at 81.153 36.1061)
		(size 0.508)
		(drill 0.25654)
		(layers "F.Cu" "B.Cu")
		(net "11N2191")
	)
	(via
		(at 84.455 44.45)
		(size 0.508)
		(drill 0.2667)
		(layers "F.Cu" "B.Cu")
		(net "11N2191")
	)
	(segment
		(start 82.931 42.926)
		(end 82.931 40.64)
		(width 0.12065)
		(layer "In7.Cu")
		(net "11N2191")
	)
	(segment
		(start 84.455 44.45)
		(end 82.931 42.926)
		(width 0.12065)
		(layer "In7.Cu")
		(net "11N2191")
	)
	(segment
		(start 82.931 40.64)
		(end 81.915 39.624)
		(width 0.12065)
		(layer "In7.Cu")
		(net "11N2191")
	)
	(segment
		(start 81.915 36.83)
		(end 81.1911 36.1061)
		(width 0.12065)
		(layer "In7.Cu")
		(net "11N2191")
	)
	(segment
		(start 81.915 39.624)
		(end 81.915 36.83)
		(width 0.12065)
		(layer "In7.Cu")
		(net "11N2191")
	)
	(segment
		(start 81.1911 36.1061)
		(end 81.153 36.1061)
		(width 0.12065)
		(layer "In7.Cu")
		(net "11N2191")
	)
	(segment
		(start 85.725 40.894)
		(end 85.725 41.783)
		(width 0.14732)
		(layer "F.Cu")
		(net "11N2181")
	)
	(segment
		(start 84.8487 40.894)
		(end 84.6836 41.0591)
		(width 0.14732)
		(layer "F.Cu")
		(net "11N2181")
	)
	(segment
		(start 85.725 40.894)
		(end 84.8487 40.894)
		(width 0.14732)
		(layer "F.Cu")
		(net "11N2181")
	)
	(segment
		(start 85.5091 41.9989)
		(end 84.6836 41.9989)
		(width 0.14732)
		(layer "F.Cu")
		(net "11N2181")
	)
	(segment
		(start 85.725 41.783)
		(end 85.5091 41.9989)
		(width 0.14732)
		(layer "F.Cu")
		(net "11N2181")
	)
	(via
		(at 85.725 40.894)
		(size 0.762)
		(drill 0.381)
		(layers "F.Cu" "B.Cu")
		(net "11N2181")
	)
	(segment
		(start 84.7471 40.2209)
		(end 85.09 39.878)
		(width 0.14732)
		(layer "F.Cu")
		(net "11N2179")
	)
	(segment
		(start 85.09 39.243)
		(end 84.455 39.243)
		(width 0.14732)
		(layer "F.Cu")
		(net "11N2179")
	)
	(segment
		(start 84.455 39.243)
		(end 83.947 39.751)
		(width 0.14732)
		(layer "F.Cu")
		(net "11N2179")
	)
	(segment
		(start 83.476998 40.729002)
		(end 83.1342 40.729002)
		(width 0.14732)
		(layer "F.Cu")
		(net "11N2179")
	)
	(segment
		(start 83.947 40.259)
		(end 83.476998 40.729002)
		(width 0.14732)
		(layer "F.Cu")
		(net "11N2179")
	)
	(segment
		(start 85.09 39.878)
		(end 85.09 39.243)
		(width 0.14732)
		(layer "F.Cu")
		(net "11N2179")
	)
	(segment
		(start 83.947 39.751)
		(end 83.947 40.259)
		(width 0.14732)
		(layer "F.Cu")
		(net "11N2179")
	)
	(segment
		(start 84.6836 40.2209)
		(end 84.7471 40.2209)
		(width 0.14732)
		(layer "F.Cu")
		(net "11N2179")
	)
	(via
		(at 85.09 39.243)
		(size 0.762)
		(drill 0.381)
		(layers "F.Cu" "B.Cu")
		(net "11N2179")
	)
	(segment
		(start 85.471 44.45)
		(end 84.455 43.434)
		(width 0.14732)
		(layer "F.Cu")
		(net "11N2177")
	)
	(segment
		(start 85.471 44.45)
		(end 85.471 45.339)
		(width 0.14732)
		(layer "F.Cu")
		(net "11N2177")
	)
	(segment
		(start 84.455 43.434)
		(end 83.693 43.434)
		(width 0.14732)
		(layer "F.Cu")
		(net "11N2177")
	)
	(segment
		(start 85.471 45.339)
		(end 84.7852 46.0248)
		(width 0.14732)
		(layer "F.Cu")
		(net "11N2177")
	)
	(segment
		(start 84.7852 46.0248)
		(end 84.16036 46.0248)
		(width 0.14732)
		(layer "F.Cu")
		(net "11N2177")
	)
	(segment
		(start 83.1342 42.8752)
		(end 83.1342 42.328998)
		(width 0.14732)
		(layer "F.Cu")
		(net "11N2177")
	)
	(segment
		(start 83.693 43.434)
		(end 83.1342 42.8752)
		(width 0.14732)
		(layer "F.Cu")
		(net "11N2177")
	)
	(via
		(at 85.471 44.45)
		(size 0.762)
		(drill 0.381)
		(layers "F.Cu" "B.Cu")
		(net "11N2177")
	)
	(segment
		(start 84.09432 41.783)
		(end 83.84032 41.529)
		(width 0.14732)
		(layer "F.Cu")
		(net "11N2175")
	)
	(segment
		(start 85.471 43.62737)
		(end 85.471 43.6245)
		(width 0.14732)
		(layer "F.Cu")
		(net "11N2175")
	)
	(segment
		(start 84.6836 42.8371)
		(end 84.09432 42.24782)
		(width 0.14732)
		(layer "F.Cu")
		(net "11N2175")
	)
	(segment
		(start 85.471 43.6245)
		(end 84.6836 42.8371)
		(width 0.14732)
		(layer "F.Cu")
		(net "11N2175")
	)
	(segment
		(start 84.09432 42.24782)
		(end 84.09432 41.783)
		(width 0.14732)
		(layer "F.Cu")
		(net "11N2175")
	)
	(segment
		(start 86.614 43.815)
		(end 86.614 47.371)
		(width 0.14732)
		(layer "F.Cu")
		(net "11N2175")
	)
	(segment
		(start 85.65863 43.815)
		(end 85.471 43.62737)
		(width 0.14732)
		(layer "F.Cu")
		(net "11N2175")
	)
	(segment
		(start 86.614 47.371)
		(end 84.7598 49.2252)
		(width 0.14732)
		(layer "F.Cu")
		(net "11N2175")
	)
	(segment
		(start 86.614 43.815)
		(end 85.65863 43.815)
		(width 0.14732)
		(layer "F.Cu")
		(net "11N2175")
	)
	(segment
		(start 83.84032 41.529)
		(end 83.1342 41.529)
		(width 0.14732)
		(layer "F.Cu")
		(net "11N2175")
	)
	(segment
		(start 84.7598 49.2252)
		(end 84.16036 49.2252)
		(width 0.14732)
		(layer "F.Cu")
		(net "11N2175")
	)
	(via
		(at 86.614 43.815)
		(size 0.762)
		(drill 0.381)
		(layers "F.Cu" "B.Cu")
		(net "11N2175")
	)
	(segment
		(start 83.693 49.911)
		(end 83.51012 49.72812)
		(width 0.14732)
		(layer "F.Cu")
		(net "11N2173")
	)
	(segment
		(start 83.8581 41.021)
		(end 83.750099 41.129001)
		(width 0.14732)
		(layer "F.Cu")
		(net "11N2173")
	)
	(segment
		(start 83.985075 41.021)
		(end 83.8581 41.021)
		(width 0.14732)
		(layer "F.Cu")
		(net "11N2173")
	)
	(segment
		(start 84.963 49.911)
		(end 83.693 49.911)
		(width 0.14732)
		(layer "F.Cu")
		(net "11N2173")
	)
	(segment
		(start 83.750099 41.129001)
		(end 83.1342 41.129001)
		(width 0.14732)
		(layer "F.Cu")
		(net "11N2173")
	)
	(segment
		(start 85.344 49.53)
		(end 84.963 49.911)
		(width 0.14732)
		(layer "F.Cu")
		(net "11N2173")
	)
	(segment
		(start 83.51012 49.72812)
		(end 83.51012 49.2252)
		(width 0.14732)
		(layer "F.Cu")
		(net "11N2173")
	)
	(via
		(at 85.344 49.53)
		(size 0.508)
		(drill 0.2667)
		(layers "F.Cu" "B.Cu")
		(net "11N2173")
	)
	(via
		(at 83.985075 41.021)
		(size 0.508)
		(drill 0.254)
		(layers "F.Cu" "B.Cu")
		(net "11N2173")
	)
	(segment
		(start 85.344 42.379925)
		(end 83.985075 41.021)
		(width 0.12065)
		(layer "In7.Cu")
		(net "11N2173")
	)
	(segment
		(start 85.344 49.53)
		(end 85.344 42.379925)
		(width 0.12065)
		(layer "In7.Cu")
		(net "11N2173")
	)
	(segment
		(start 83.711999 41.928999)
		(end 83.1342 41.928999)
		(width 0.14732)
		(layer "F.Cu")
		(net "11N2159")
	)
	(segment
		(start 83.82 42.037)
		(end 83.711999 41.928999)
		(width 0.14732)
		(layer "F.Cu")
		(net "11N2159")
	)
	(segment
		(start 83.82 42.7609)
		(end 83.82 42.037)
		(width 0.14732)
		(layer "F.Cu")
		(net "11N2159")
	)
	(segment
		(start 83.9851 42.926)
		(end 83.82 42.7609)
		(width 0.14732)
		(layer "F.Cu")
		(net "11N2159")
	)
	(via
		(at 84.582 41.91)
		(size 0.762)
		(drill 0.381)
		(layers "F.Cu" "B.Cu")
		(net "11N2159")
	)
	(via
		(at 83.9851 42.926)
		(size 0.508)
		(drill 0.254)
		(layers "F.Cu" "B.Cu")
		(net "11N2159")
	)
	(segment
		(start 83.9851 43.942)
		(end 83.9851 42.926)
		(width 0.14732)
		(layer "B.Cu")
		(net "11N2159")
	)
	(segment
		(start 83.185 44.7421)
		(end 83.9851 43.942)
		(width 0.14732)
		(layer "B.Cu")
		(net "11N2159")
	)
	(segment
		(start 84.201 40.132)
		(end 84.582 40.513)
		(width 0.14732)
		(layer "B.Cu")
		(net "11N2159")
	)
	(segment
		(start 84.582 42.3291)
		(end 83.9851 42.926)
		(width 0.14732)
		(layer "B.Cu")
		(net "11N2159")
	)
	(segment
		(start 84.582 41.91)
		(end 84.582 42.3291)
		(width 0.14732)
		(layer "B.Cu")
		(net "11N2159")
	)
	(segment
		(start 83.3501 40.132)
		(end 84.201 40.132)
		(width 0.14732)
		(layer "B.Cu")
		(net "11N2159")
	)
	(segment
		(start 84.582 40.513)
		(end 84.582 41.91)
		(width 0.14732)
		(layer "B.Cu")
		(net "11N2159")
	)
	(segment
		(start 80.137 43.9039)
		(end 80.137 43.307)
		(width 0.14732)
		(layer "F.Cu")
		(net "11N2152")
	)
	(segment
		(start 80.137 43.307)
		(end 80.4164 43.0276)
		(width 0.14732)
		(layer "F.Cu")
		(net "11N2152")
	)
	(segment
		(start 80.4164 43.0276)
		(end 80.835602 43.0276)
		(width 0.14732)
		(layer "F.Cu")
		(net "11N2152")
	)
	(segment
		(start 79.9719 44.069)
		(end 80.137 43.9039)
		(width 0.14732)
		(layer "F.Cu")
		(net "11N2152")
	)
	(via
		(at 79.9211 44.069)
		(size 0.508)
		(drill 0.25654)
		(layers "F.Cu" "B.Cu")
		(net "11N2152")
	)
	(via
		(at 80.518 44.704)
		(size 0.762)
		(drill 0.381)
		(layers "F.Cu" "B.Cu")
		(net "11N2152")
	)
	(segment
		(start 80.6831 43.307)
		(end 79.9211 44.069)
		(width 0.14732)
		(layer "B.Cu")
		(net "11N2152")
	)
	(segment
		(start 79.9211 44.1071)
		(end 79.9211 44.069)
		(width 0.14732)
		(layer "B.Cu")
		(net "11N2152")
	)
	(segment
		(start 80.518 44.704)
		(end 79.9211 44.1071)
		(width 0.14732)
		(layer "B.Cu")
		(net "11N2152")
	)
	(segment
		(start 80.6831 42.799)
		(end 80.6831 43.307)
		(width 0.14732)
		(layer "B.Cu")
		(net "11N2152")
	)
	(segment
		(start 81.6356 44.0563)
		(end 81.6356 43.0276)
		(width 0.14732)
		(layer "F.Cu")
		(net "11N2146")
	)
	(segment
		(start 81.6229 44.069)
		(end 81.6356 44.0563)
		(width 0.14732)
		(layer "F.Cu")
		(net "11N2146")
	)
	(segment
		(start 80.8101 44.069)
		(end 81.6229 44.069)
		(width 0.14732)
		(layer "F.Cu")
		(net "11N2146")
	)
	(via
		(at 81.6229 44.069)
		(size 0.508)
		(drill 0.25654)
		(layers "F.Cu" "B.Cu")
		(net "11N2146")
	)
	(segment
		(start 82.4357 43.2562)
		(end 81.6229 44.069)
		(width 0.14732)
		(layer "B.Cu")
		(net "11N2146")
	)
	(segment
		(start 82.4357 42.9006)
		(end 82.4357 43.2562)
		(width 0.14732)
		(layer "B.Cu")
		(net "11N2146")
	)
	(segment
		(start 82.931 42.3037)
		(end 82.4357 42.9006)
		(width 0.14732)
		(layer "B.Cu")
		(net "11N2146")
	)
	(segment
		(start 82.931 41.9989)
		(end 82.931 42.3037)
		(width 0.14732)
		(layer "B.Cu")
		(net "11N2146")
	)
	(segment
		(start 81.6356 39.44046)
		(end 81.6356 40.0304)
		(width 0.14732)
		(layer "F.Cu")
		(net "11N2140")
	)
	(segment
		(start 82.795974 38.862)
		(end 82.269609 38.862)
		(width 0.14732)
		(layer "F.Cu")
		(net "11N2140")
	)
	(segment
		(start 83.312 38.3921)
		(end 82.91576 38.78834)
		(width 0.14732)
		(layer "F.Cu")
		(net "11N2140")
	)
	(segment
		(start 82.91576 38.78834)
		(end 82.869634 38.78834)
		(width 0.14732)
		(layer "F.Cu")
		(net "11N2140")
	)
	(segment
		(start 82.269609 38.862)
		(end 82.008624 39.067435)
		(width 0.14732)
		(layer "F.Cu")
		(net "11N2140")
	)
	(segment
		(start 82.008624 39.067435)
		(end 81.6356 39.44046)
		(width 0.14732)
		(layer "F.Cu")
		(net "11N2140")
	)
	(segment
		(start 82.869634 38.78834)
		(end 82.795974 38.862)
		(width 0.14732)
		(layer "F.Cu")
		(net "11N2140")
	)
	(via
		(at 83.312 37.465)
		(size 0.762)
		(drill 0.381)
		(layers "F.Cu" "B.Cu")
		(net "11N2140")
	)
	(via
		(at 83.312 38.3413)
		(size 0.508)
		(drill 0.25654)
		(layers "F.Cu" "B.Cu")
		(net "11N2140")
	)
	(segment
		(start 83.312 38.3413)
		(end 83.312 37.465)
		(width 0.14732)
		(layer "B.Cu")
		(net "11N2140")
	)
	(segment
		(start 81.8261 38.862)
		(end 81.788 38.862)
		(width 0.14732)
		(layer "F.Cu")
		(net "11N2138")
	)
	(segment
		(start 81.788 38.862)
		(end 81.235601 39.414399)
		(width 0.14732)
		(layer "F.Cu")
		(net "11N2138")
	)
	(segment
		(start 81.235601 39.414399)
		(end 81.235601 40.0304)
		(width 0.14732)
		(layer "F.Cu")
		(net "11N2138")
	)
	(segment
		(start 82.423 38.3921)
		(end 81.8261 38.862)
		(width 0.14732)
		(layer "F.Cu")
		(net "11N2138")
	)
	(via
		(at 82.423 38.3921)
		(size 0.508)
		(drill 0.25654)
		(layers "F.Cu" "B.Cu")
		(net "11N2138")
	)
	(segment
		(start 64.061696 46.751596)
		(end 64.061696 47.283116)
		(width 0.14732)
		(layer "F.Cu")
		(net "11N1981")
	)
	(segment
		(start 63.5 46.18736)
		(end 64.061696 46.751596)
		(width 0.14732)
		(layer "F.Cu")
		(net "11N1981")
	)
	(segment
		(start 64.061696 47.283116)
		(end 63.749936 47.594876)
		(width 0.14732)
		(layer "F.Cu")
		(net "11N1981")
	)
	(segment
		(start 63.749936 47.594876)
		(end 63.749936 48.424084)
		(width 0.14732)
		(layer "F.Cu")
		(net "11N1981")
	)
	(via
		(at 63.5 46.18736)
		(size 0.508)
		(drill 0.25654)
		(layers "F.Cu" "B.Cu")
		(net "11N1981")
	)
	(segment
		(start 16.6497 38.0111)
		(end 17.36786 38.0111)
		(width 0.14732)
		(layer "F.Cu")
		(net "11N1979")
	)
	(segment
		(start 17.36786 38.0111)
		(end 17.49359 37.88537)
		(width 0.14732)
		(layer "F.Cu")
		(net "11N1979")
	)
	(segment
		(start 17.49359 37.88537)
		(end 19.97837 37.88537)
		(width 0.14732)
		(layer "F.Cu")
		(net "11N1979")
	)
	(segment
		(start 19.97837 37.88537)
		(end 20.193 38.1)
		(width 0.14732)
		(layer "F.Cu")
		(net "11N1979")
	)
	(segment
		(start 4.191 34.5821)
		(end 4.191 35.306)
		(width 0.14732)
		(layer "F.Cu")
		(net "11N1979")
	)
	(via
		(at 20.193 38.1)
		(size 0.508)
		(drill 0.2667)
		(layers "F.Cu" "B.Cu")
		(net "11N1979")
	)
	(via
		(at 4.191 35.306)
		(size 0.508)
		(drill 0.254)
		(layers "F.Cu" "B.Cu")
		(net "11N1979")
	)
	(segment
		(start 12.573 35.052)
		(end 12.379325 35.245675)
		(width 0.12065)
		(layer "In6.Cu")
		(net "11N1979")
	)
	(segment
		(start 18.796 38.608)
		(end 17.145 38.608)
		(width 0.12065)
		(layer "In6.Cu")
		(net "11N1979")
	)
	(segment
		(start 5.781675 35.747325)
		(end 4.632325 35.747325)
		(width 0.12065)
		(layer "In6.Cu")
		(net "11N1979")
	)
	(segment
		(start 16.002 37.465)
		(end 16.002 35.306)
		(width 0.12065)
		(layer "In6.Cu")
		(net "11N1979")
	)
	(segment
		(start 16.002 35.306)
		(end 15.748 35.052)
		(width 0.12065)
		(layer "In6.Cu")
		(net "11N1979")
	)
	(segment
		(start 12.379325 35.245675)
		(end 7.67146 35.245675)
		(width 0.12065)
		(layer "In6.Cu")
		(net "11N1979")
	)
	(segment
		(start 17.145 38.608)
		(end 16.002 37.465)
		(width 0.12065)
		(layer "In6.Cu")
		(net "11N1979")
	)
	(segment
		(start 4.632325 35.747325)
		(end 4.191 35.306)
		(width 0.12065)
		(layer "In6.Cu")
		(net "11N1979")
	)
	(segment
		(start 7.630185 35.28695)
		(end 6.24205 35.28695)
		(width 0.12065)
		(layer "In6.Cu")
		(net "11N1979")
	)
	(segment
		(start 15.748 35.052)
		(end 12.573 35.052)
		(width 0.12065)
		(layer "In6.Cu")
		(net "11N1979")
	)
	(segment
		(start 19.304 38.1)
		(end 18.796 38.608)
		(width 0.12065)
		(layer "In6.Cu")
		(net "11N1979")
	)
	(segment
		(start 20.193 38.1)
		(end 19.304 38.1)
		(width 0.12065)
		(layer "In6.Cu")
		(net "11N1979")
	)
	(segment
		(start 7.67146 35.245675)
		(end 7.630185 35.28695)
		(width 0.12065)
		(layer "In6.Cu")
		(net "11N1979")
	)
	(segment
		(start 6.24205 35.28695)
		(end 5.781675 35.747325)
		(width 0.12065)
		(layer "In6.Cu")
		(net "11N1979")
	)
	(segment
		(start 16.568217 39.35603)
		(end 17.084751 39.35603)
		(width 0.381)
		(layer "F.Cu")
		(net "11N1971")
	)
	(segment
		(start 18.0594 40.330679)
		(end 18.0594 41.9354)
		(width 0.381)
		(layer "F.Cu")
		(net "11N1971")
	)
	(segment
		(start 18.6436 44.8056)
		(end 18.6436 42.9641)
		(width 0.508)
		(layer "F.Cu")
		(net "11N1971")
	)
	(segment
		(start 18.923 45.085)
		(end 18.6436 44.8056)
		(width 0.508)
		(layer "F.Cu")
		(net "11N1971")
	)
	(segment
		(start 19.558 45.085)
		(end 18.923 45.085)
		(width 0.508)
		(layer "F.Cu")
		(net "11N1971")
	)
	(segment
		(start 17.084751 39.35603)
		(end 18.0594 40.330679)
		(width 0.381)
		(layer "F.Cu")
		(net "11N1971")
	)
	(via
		(at 19.558 45.085)
		(size 0.762)
		(drill 0.381)
		(layers "F.Cu" "B.Cu")
		(net "11N1971")
	)
	(segment
		(start 12.454484 35.06597)
		(end 12.33297 35.06597)
		(width 0.381)
		(layer "F.Cu")
		(net "11N1970")
	)
	(segment
		(start 11.811 34.544)
		(end 11.811 32.639)
		(width 0.381)
		(layer "F.Cu")
		(net "11N1970")
	)
	(segment
		(start 12.33297 35.06597)
		(end 11.811 34.544)
		(width 0.381)
		(layer "F.Cu")
		(net "11N1970")
	)
	(via
		(at 10.922 31.75)
		(size 0.762)
		(drill 0.381)
		(layers "F.Cu" "B.Cu")
		(net "11N1970")
	)
	(segment
		(start 10.922 42.037)
		(end 11.303 41.656)
		(width 0.381)
		(layer "F.Cu")
		(net "11N1968")
	)
	(segment
		(start 11.95197 39.35603)
		(end 11.303 40.005)
		(width 0.381)
		(layer "F.Cu")
		(net "11N1968")
	)
	(segment
		(start 11.303 40.005)
		(end 11.303 41.656)
		(width 0.381)
		(layer "F.Cu")
		(net "11N1968")
	)
	(segment
		(start 12.457557 39.35603)
		(end 11.95197 39.35603)
		(width 0.381)
		(layer "F.Cu")
		(net "11N1968")
	)
	(segment
		(start 10.742371 45.585736)
		(end 10.742371 46.683371)
		(width 0.254)
		(layer "F.Cu")
		(net "11N1968")
	)
	(segment
		(start 10.996371 45.331736)
		(end 10.742371 45.585736)
		(width 0.254)
		(layer "F.Cu")
		(net "11N1968")
	)
	(via
		(at 10.742371 46.683371)
		(size 0.762)
		(drill 0.381)
		(layers "F.Cu" "B.Cu")
		(net "11N1968")
	)
	(segment
		(start 18.923 36.83)
		(end 18.74266 36.64966)
		(width 0.14732)
		(layer "F.Cu")
		(net "11N1966")
	)
	(segment
		(start 17.185767 36.482807)
		(end 17.178807 36.482807)
		(width 0.14732)
		(layer "F.Cu")
		(net "11N1966")
	)
	(segment
		(start 17.1069 36.4109)
		(end 16.6497 36.4109)
		(width 0.14732)
		(layer "F.Cu")
		(net "11N1966")
	)
	(segment
		(start 18.74266 36.64966)
		(end 17.35262 36.64966)
		(width 0.14732)
		(layer "F.Cu")
		(net "11N1966")
	)
	(segment
		(start 17.178807 36.482807)
		(end 17.1069 36.4109)
		(width 0.14732)
		(layer "F.Cu")
		(net "11N1966")
	)
	(segment
		(start 5.08 34.5821)
		(end 5.08 35.306)
		(width 0.14732)
		(layer "F.Cu")
		(net "11N1966")
	)
	(segment
		(start 17.35262 36.64966)
		(end 17.185767 36.482807)
		(width 0.14732)
		(layer "F.Cu")
		(net "11N1966")
	)
	(via
		(at 5.08 35.306)
		(size 0.508)
		(drill 0.2667)
		(layers "F.Cu" "B.Cu")
		(net "11N1966")
	)
	(via
		(at 18.923 36.83)
		(size 0.508)
		(drill 0.254)
		(layers "F.Cu" "B.Cu")
		(net "11N1966")
	)
	(segment
		(start 11.904929 34.858325)
		(end 12.965379 33.797875)
		(width 0.12065)
		(layer "In6.Cu")
		(net "11N1966")
	)
	(segment
		(start 8.448777 34.858325)
		(end 11.904929 34.858325)
		(width 0.12065)
		(layer "In6.Cu")
		(net "11N1966")
	)
	(segment
		(start 15.162479 33.797875)
		(end 16.383 35.018396)
		(width 0.12065)
		(layer "In6.Cu")
		(net "11N1966")
	)
	(segment
		(start 8.388452 34.91865)
		(end 8.448777 34.858325)
		(width 0.12065)
		(layer "In6.Cu")
		(net "11N1966")
	)
	(segment
		(start 7.648245 34.91865)
		(end 8.388452 34.91865)
		(width 0.12065)
		(layer "In6.Cu")
		(net "11N1966")
	)
	(segment
		(start 12.965379 33.797875)
		(end 15.162479 33.797875)
		(width 0.12065)
		(layer "In6.Cu")
		(net "11N1966")
	)
	(segment
		(start 5.3467 35.0393)
		(end 7.527595 35.0393)
		(width 0.12065)
		(layer "In6.Cu")
		(net "11N1966")
	)
	(segment
		(start 18.161 38.227)
		(end 18.923 37.465)
		(width 0.12065)
		(layer "In6.Cu")
		(net "11N1966")
	)
	(segment
		(start 17.272 38.227)
		(end 18.161 38.227)
		(width 0.12065)
		(layer "In6.Cu")
		(net "11N1966")
	)
	(segment
		(start 7.527595 35.0393)
		(end 7.648245 34.91865)
		(width 0.12065)
		(layer "In6.Cu")
		(net "11N1966")
	)
	(segment
		(start 16.383 35.018396)
		(end 16.383 37.338)
		(width 0.12065)
		(layer "In6.Cu")
		(net "11N1966")
	)
	(segment
		(start 16.383 37.338)
		(end 17.272 38.227)
		(width 0.12065)
		(layer "In6.Cu")
		(net "11N1966")
	)
	(segment
		(start 18.923 37.465)
		(end 18.923 36.83)
		(width 0.12065)
		(layer "In6.Cu")
		(net "11N1966")
	)
	(segment
		(start 5.08 35.306)
		(end 5.3467 35.0393)
		(width 0.12065)
		(layer "In6.Cu")
		(net "11N1966")
	)
	(segment
		(start 65.659 47.5361)
		(end 66.167 47.0281)
		(width 0.14732)
		(layer "F.Cu")
		(net "11N1953")
	)
	(segment
		(start 66.5226 47.0281)
		(end 66.548 47.0281)
		(width 0.14732)
		(layer "F.Cu")
		(net "11N1953")
	)
	(segment
		(start 66.167 47.0281)
		(end 66.5226 47.0281)
		(width 0.14732)
		(layer "F.Cu")
		(net "11N1953")
	)
	(segment
		(start 64.859916 50.534062)
		(end 65.025092 50.534062)
		(width 0.14732)
		(layer "F.Cu")
		(net "11N1953")
	)
	(segment
		(start 65.025092 50.534062)
		(end 65.30213 50.257024)
		(width 0.14732)
		(layer "F.Cu")
		(net "11N1953")
	)
	(segment
		(start 65.30213 50.257024)
		(end 65.30213 47.89297)
		(width 0.14732)
		(layer "F.Cu")
		(net "11N1953")
	)
	(segment
		(start 65.30213 47.89297)
		(end 65.659 47.5361)
		(width 0.14732)
		(layer "F.Cu")
		(net "11N1953")
	)
	(via
		(at 66.5226 47.0281)
		(size 0.508)
		(drill 0.25654)
		(layers "F.Cu" "B.Cu")
		(net "11N1953")
	)
	(segment
		(start 63.5 47.02556)
		(end 62.992 47.0281)
		(width 0.254)
		(layer "F.Cu")
		(net "11N1952")
	)
	(segment
		(start 62.742064 47.94824)
		(end 62.749938 47.956114)
		(width 0.254)
		(layer "F.Cu")
		(net "11N1952")
	)
	(segment
		(start 60.1472 49.784)
		(end 58.928 49.784)
		(width 0.14732)
		(layer "F.Cu")
		(net "11N1952")
	)
	(segment
		(start 62.742064 47.278036)
		(end 62.742064 47.94824)
		(width 0.254)
		(layer "F.Cu")
		(net "11N1952")
	)
	(segment
		(start 62.749938 47.956114)
		(end 62.749938 48.424084)
		(width 0.254)
		(layer "F.Cu")
		(net "11N1952")
	)
	(segment
		(start 62.992 47.0281)
		(end 62.742064 47.278036)
		(width 0.254)
		(layer "F.Cu")
		(net "11N1952")
	)
	(via
		(at 58.928 49.784)
		(size 0.508)
		(drill 0.25654)
		(layers "F.Cu" "B.Cu")
		(net "11N1952")
	)
	(segment
		(start 14.478 39.3827)
		(end 14.478 39.878076)
		(width 0.2032)
		(layer "F.Cu")
		(net "11N1937")
	)
	(segment
		(start 14.351 42.046068)
		(end 14.0335 42.363568)
		(width 0.508)
		(layer "F.Cu")
		(net "11N1937")
	)
	(segment
		(start 14.732 40.259)
		(end 14.732 40.330679)
		(width 0.2032)
		(layer "F.Cu")
		(net "11N1937")
	)
	(segment
		(start 14.732 40.330679)
		(end 14.732 41.656)
		(width 0.381)
		(layer "F.Cu")
		(net "11N1937")
	)
	(segment
		(start 14.732 41.656)
		(end 14.351 42.037)
		(width 0.381)
		(layer "F.Cu")
		(net "11N1937")
	)
	(segment
		(start 13.295071 45.632929)
		(end 13.4747 45.4533)
		(width 0.254)
		(layer "F.Cu")
		(net "11N1937")
	)
	(segment
		(start 14.5796 39.979676)
		(end 14.5796 40.1066)
		(width 0.2032)
		(layer "F.Cu")
		(net "11N1937")
	)
	(segment
		(start 14.351 42.037)
		(end 14.351 42.046068)
		(width 0.508)
		(layer "F.Cu")
		(net "11N1937")
	)
	(segment
		(start 14.478 39.878076)
		(end 14.5796 39.979676)
		(width 0.2032)
		(layer "F.Cu")
		(net "11N1937")
	)
	(segment
		(start 13.4747 45.4533)
		(end 13.4747 44.196)
		(width 0.254)
		(layer "F.Cu")
		(net "11N1937")
	)
	(segment
		(start 13.295071 46.696071)
		(end 13.295071 45.632929)
		(width 0.254)
		(layer "F.Cu")
		(net "11N1937")
	)
	(segment
		(start 14.5796 40.1066)
		(end 14.732 40.259)
		(width 0.2032)
		(layer "F.Cu")
		(net "11N1937")
	)
	(via
		(at 13.295071 46.696071)
		(size 0.762)
		(drill 0.381)
		(layers "F.Cu" "B.Cu")
		(net "11N1937")
	)
	(segment
		(start 32.258 43.5229)
		(end 32.1691 43.434)
		(width 0.14732)
		(layer "F.Cu")
		(net "10N2535")
	)
	(segment
		(start 32.1691 43.434)
		(end 32.1691 42.545)
		(width 0.14732)
		(layer "F.Cu")
		(net "10N2535")
	)
	(segment
		(start 32.1691 42.545)
		(end 31.365012 41.740912)
		(width 0.14732)
		(layer "F.Cu")
		(net "10N2535")
	)
	(segment
		(start 31.365012 41.740912)
		(end 31.365012 41.0464)
		(width 0.14732)
		(layer "F.Cu")
		(net "10N2535")
	)
	(via
		(at 32.258 43.5229)
		(size 0.508)
		(drill 0.25654)
		(layers "F.Cu" "B.Cu")
		(net "10N2535")
	)
	(via
		(at 31.75 40.894)
		(size 0.762)
		(drill 0.381)
		(layers "F.Cu" "B.Cu")
		(net "10N2535")
	)
	(segment
		(start 32.258 41.402)
		(end 32.258 43.5229)
		(width 0.14732)
		(layer "B.Cu")
		(net "10N2535")
	)
	(segment
		(start 31.75 40.894)
		(end 32.258 41.402)
		(width 0.14732)
		(layer "B.Cu")
		(net "10N2535")
	)
	(segment
		(start 32.518934 42.09034)
		(end 32.31134 42.09034)
		(width 0.14732)
		(layer "F.Cu")
		(net "10N2528")
	)
	(segment
		(start 31.865011 41.644011)
		(end 31.865011 41.0464)
		(width 0.14732)
		(layer "F.Cu")
		(net "10N2528")
	)
	(segment
		(start 33.1851 42.545)
		(end 32.954366 42.314266)
		(width 0.14732)
		(layer "F.Cu")
		(net "10N2528")
	)
	(segment
		(start 32.954366 42.314266)
		(end 32.742861 42.314266)
		(width 0.14732)
		(layer "F.Cu")
		(net "10N2528")
	)
	(segment
		(start 35.9029 39.878)
		(end 35.8521 40.767)
		(width 0.14732)
		(layer "F.Cu")
		(net "10N2528")
	)
	(segment
		(start 32.31134 42.09034)
		(end 31.865011 41.644011)
		(width 0.14732)
		(layer "F.Cu")
		(net "10N2528")
	)
	(segment
		(start 33.2359 44.2468)
		(end 33.1851 43.434)
		(width 0.14732)
		(layer "F.Cu")
		(net "10N2528")
	)
	(segment
		(start 32.742861 42.314266)
		(end 32.518934 42.09034)
		(width 0.14732)
		(layer "F.Cu")
		(net "10N2528")
	)
	(segment
		(start 33.1851 43.434)
		(end 33.1851 42.545)
		(width 0.14732)
		(layer "F.Cu")
		(net "10N2528")
	)
	(segment
		(start 33.2359 42.545)
		(end 33.1851 42.545)
		(width 0.14732)
		(layer "F.Cu")
		(net "10N2528")
	)
	(segment
		(start 33.3121 44.323)
		(end 33.2359 44.2468)
		(width 0.14732)
		(layer "F.Cu")
		(net "10N2528")
	)
	(via
		(at 35.9029 39.878)
		(size 0.508)
		(drill 0.25654)
		(layers "F.Cu" "B.Cu")
		(net "10N2528")
	)
	(via
		(at 33.2359 42.545)
		(size 0.508)
		(drill 0.25654)
		(layers "F.Cu" "B.Cu")
		(net "10N2528")
	)
	(via
		(at 36.703 40.513)
		(size 0.762)
		(drill 0.381)
		(layers "F.Cu" "B.Cu")
		(net "10N2528")
	)
	(segment
		(start 33.909 42.545)
		(end 34.30016 42.15384)
		(width 0.14732)
		(layer "B.Cu")
		(net "10N2528")
	)
	(segment
		(start 35.9029 39.878)
		(end 36.068 39.878)
		(width 0.14732)
		(layer "B.Cu")
		(net "10N2528")
	)
	(segment
		(start 33.2359 42.545)
		(end 33.909 42.545)
		(width 0.14732)
		(layer "B.Cu")
		(net "10N2528")
	)
	(segment
		(start 34.30016 42.15384)
		(end 35.06216 42.15384)
		(width 0.14732)
		(layer "B.Cu")
		(net "10N2528")
	)
	(segment
		(start 35.56 41.656)
		(end 35.56 40.2209)
		(width 0.14732)
		(layer "B.Cu")
		(net "10N2528")
	)
	(segment
		(start 36.068 39.878)
		(end 36.703 40.513)
		(width 0.14732)
		(layer "B.Cu")
		(net "10N2528")
	)
	(segment
		(start 35.06216 42.15384)
		(end 35.56 41.656)
		(width 0.14732)
		(layer "B.Cu")
		(net "10N2528")
	)
	(segment
		(start 35.56 40.2209)
		(end 35.9029 39.878)
		(width 0.14732)
		(layer "B.Cu")
		(net "10N2528")
	)
	(segment
		(start 27.48534 46.28134)
		(end 27.48534 44.05376)
		(width 0.14732)
		(layer "F.Cu")
		(net "10N2504")
	)
	(segment
		(start 30.3911 43.1038)
		(end 29.591 43.9039)
		(width 0.14732)
		(layer "F.Cu")
		(net "10N2504")
	)
	(segment
		(start 30.86354 41.407436)
		(end 30.864988 41.405988)
		(width 0.14732)
		(layer "F.Cu")
		(net "10N2504")
	)
	(segment
		(start 29.845 45.339)
		(end 29.845 45.6819)
		(width 0.14732)
		(layer "F.Cu")
		(net "10N2504")
	)
	(segment
		(start 30.88132 42.190086)
		(end 30.88132 41.607994)
		(width 0.14732)
		(layer "F.Cu")
		(net "10N2504")
	)
	(segment
		(start 29.591 43.9039)
		(end 29.6418 43.9039)
		(width 0.14732)
		(layer "F.Cu")
		(net "10N2504")
	)
	(segment
		(start 27.48534 44.05376)
		(end 27.559 43.9801)
		(width 0.14732)
		(layer "F.Cu")
		(net "10N2504")
	)
	(segment
		(start 30.88132 41.607994)
		(end 30.86354 41.590214)
		(width 0.14732)
		(layer "F.Cu")
		(net "10N2504")
	)
	(segment
		(start 30.4419 44.7421)
		(end 29.845 45.339)
		(width 0.14732)
		(layer "F.Cu")
		(net "10N2504")
	)
	(segment
		(start 30.48 44.7421)
		(end 30.4419 44.7421)
		(width 0.14732)
		(layer "F.Cu")
		(net "10N2504")
	)
	(segment
		(start 30.86354 42.207866)
		(end 30.88132 42.190086)
		(width 0.14732)
		(layer "F.Cu")
		(net "10N2504")
	)
	(segment
		(start 29.845 45.6819)
		(end 29.8069 45.72)
		(width 0.14732)
		(layer "F.Cu")
		(net "10N2504")
	)
	(segment
		(start 30.3911 42.926)
		(end 30.3911 43.1038)
		(width 0.14732)
		(layer "F.Cu")
		(net "10N2504")
	)
	(segment
		(start 30.864988 41.405988)
		(end 30.864988 41.0464)
		(width 0.14732)
		(layer "F.Cu")
		(net "10N2504")
	)
	(segment
		(start 30.86354 42.45356)
		(end 30.86354 42.207866)
		(width 0.14732)
		(layer "F.Cu")
		(net "10N2504")
	)
	(segment
		(start 29.6418 43.9039)
		(end 30.48 44.7421)
		(width 0.14732)
		(layer "F.Cu")
		(net "10N2504")
	)
	(segment
		(start 29.8069 46.8249)
		(end 28.0289 46.8249)
		(width 0.14732)
		(layer "F.Cu")
		(net "10N2504")
	)
	(segment
		(start 30.86354 41.590214)
		(end 30.86354 41.407436)
		(width 0.14732)
		(layer "F.Cu")
		(net "10N2504")
	)
	(segment
		(start 29.8069 45.72)
		(end 29.8069 46.8249)
		(width 0.14732)
		(layer "F.Cu")
		(net "10N2504")
	)
	(segment
		(start 28.0289 46.8249)
		(end 27.48534 46.28134)
		(width 0.14732)
		(layer "F.Cu")
		(net "10N2504")
	)
	(segment
		(start 30.3911 42.926)
		(end 30.86354 42.45356)
		(width 0.14732)
		(layer "F.Cu")
		(net "10N2504")
	)
	(via
		(at 29.8069 46.8249)
		(size 0.762)
		(drill 0.381)
		(layers "F.Cu" "B.Cu")
		(net "10N2504")
	)
	(segment
		(start 26.08834 42.61866)
		(end 27.946934 42.61866)
		(width 0.14732)
		(layer "F.Cu")
		(net "10N2498")
	)
	(segment
		(start 27.946934 42.61866)
		(end 28.439694 42.1259)
		(width 0.14732)
		(layer "F.Cu")
		(net "10N2498")
	)
	(segment
		(start 25.527 43.561)
		(end 25.527 43.18)
		(width 0.14732)
		(layer "F.Cu")
		(net "10N2498")
	)
	(segment
		(start 29.0449 41.656)
		(end 29.085286 41.656)
		(width 0.14732)
		(layer "F.Cu")
		(net "10N2498")
	)
	(segment
		(start 28.439694 42.1259)
		(end 28.575 42.1259)
		(width 0.14732)
		(layer "F.Cu")
		(net "10N2498")
	)
	(segment
		(start 29.085286 41.656)
		(end 29.364991 41.376295)
		(width 0.14732)
		(layer "F.Cu")
		(net "10N2498")
	)
	(segment
		(start 28.575 42.1259)
		(end 29.0449 41.656)
		(width 0.14732)
		(layer "F.Cu")
		(net "10N2498")
	)
	(segment
		(start 25.527 43.18)
		(end 26.08834 42.61866)
		(width 0.14732)
		(layer "F.Cu")
		(net "10N2498")
	)
	(segment
		(start 29.364991 41.376295)
		(end 29.364991 41.0464)
		(width 0.14732)
		(layer "F.Cu")
		(net "10N2498")
	)
	(via
		(at 25.527 43.561)
		(size 0.762)
		(drill 0.381)
		(layers "F.Cu" "B.Cu")
		(net "10N2498")
	)
	(segment
		(start 27.396008 35.849992)
		(end 27.305 35.77336)
		(width 0.14732)
		(layer "F.Cu")
		(net "10N2412")
	)
	(segment
		(start 28.1686 35.849992)
		(end 27.396008 35.849992)
		(width 0.14732)
		(layer "F.Cu")
		(net "10N2412")
	)
	(via
		(at 27.305 35.77336)
		(size 0.508)
		(drill 0.254)
		(layers "F.Cu" "B.Cu")
		(net "10N2412")
	)
	(via
		(at 24.257 37.592)
		(size 0.508)
		(drill 0.25654)
		(layers "F.Cu" "B.Cu")
		(net "10N2412")
	)
	(segment
		(start 26.035 35.306)
		(end 24.257 37.084)
		(width 0.254)
		(layer "B.Cu")
		(net "10N2412")
	)
	(segment
		(start 27.305 35.77336)
		(end 26.83764 35.306)
		(width 0.254)
		(layer "B.Cu")
		(net "10N2412")
	)
	(segment
		(start 24.257 37.084)
		(end 24.257 37.592)
		(width 0.254)
		(layer "B.Cu")
		(net "10N2412")
	)
	(segment
		(start 26.83764 35.306)
		(end 26.035 35.306)
		(width 0.254)
		(layer "B.Cu")
		(net "10N2412")
	)
	(segment
		(start 27.625091 39.850009)
		(end 28.1686 39.850009)
		(width 0.14732)
		(layer "F.Cu")
		(net "10N2411")
	)
	(segment
		(start 27.0891 40.386)
		(end 27.625091 39.850009)
		(width 0.14732)
		(layer "F.Cu")
		(net "10N2411")
	)
	(via
		(at 27.0891 40.386)
		(size 0.508)
		(drill 0.25654)
		(layers "F.Cu" "B.Cu")
		(net "10N2411")
	)
	(segment
		(start 32.258 44.3611)
		(end 32.1945 44.4246)
		(width 0.14732)
		(layer "F.Cu")
		(net "10N2410")
	)
	(segment
		(start 32.1945 44.4246)
		(end 32.1945 45.085)
		(width 0.14732)
		(layer "F.Cu")
		(net "10N2410")
	)
	(via
		(at 35.8267 42.545)
		(size 0.508)
		(drill 0.25654)
		(layers "F.Cu" "B.Cu")
		(net "10N2410")
	)
	(via
		(at 35.7251 38.1)
		(size 0.508)
		(drill 0.25654)
		(layers "F.Cu" "B.Cu")
		(net "10N2410")
	)
	(via
		(at 32.1945 45.085)
		(size 0.508)
		(drill 0.254)
		(layers "F.Cu" "B.Cu")
		(net "10N2410")
	)
	(segment
		(start 32.385 45.847)
		(end 34.036 45.847)
		(width 0.14732)
		(layer "B.Cu")
		(net "10N2410")
	)
	(segment
		(start 32.1945 45.6565)
		(end 32.385 45.847)
		(width 0.14732)
		(layer "B.Cu")
		(net "10N2410")
	)
	(segment
		(start 35.35934 43.01236)
		(end 35.8267 42.545)
		(width 0.14732)
		(layer "B.Cu")
		(net "10N2410")
	)
	(segment
		(start 34.163 44.069)
		(end 34.417 43.815)
		(width 0.14732)
		(layer "B.Cu")
		(net "10N2410")
	)
	(segment
		(start 34.036 45.847)
		(end 34.163 45.72)
		(width 0.14732)
		(layer "B.Cu")
		(net "10N2410")
	)
	(segment
		(start 35.35934 43.50766)
		(end 35.35934 43.01236)
		(width 0.14732)
		(layer "B.Cu")
		(net "10N2410")
	)
	(segment
		(start 32.1945 45.085)
		(end 32.1945 45.6565)
		(width 0.14732)
		(layer "B.Cu")
		(net "10N2410")
	)
	(segment
		(start 34.163 45.72)
		(end 34.163 44.069)
		(width 0.14732)
		(layer "B.Cu")
		(net "10N2410")
	)
	(segment
		(start 34.417 43.815)
		(end 35.052 43.815)
		(width 0.14732)
		(layer "B.Cu")
		(net "10N2410")
	)
	(segment
		(start 35.052 43.815)
		(end 35.35934 43.50766)
		(width 0.14732)
		(layer "B.Cu")
		(net "10N2410")
	)
	(segment
		(start 35.7251 38.5699)
		(end 35.429825 38.865175)
		(width 0.12065)
		(layer "In6.Cu")
		(net "10N2410")
	)
	(segment
		(start 35.7251 38.1)
		(end 35.7251 38.5699)
		(width 0.12065)
		(layer "In6.Cu")
		(net "10N2410")
	)
	(segment
		(start 35.306 41.91)
		(end 35.8267 42.4307)
		(width 0.12065)
		(layer "In6.Cu")
		(net "10N2410")
	)
	(segment
		(start 34.737675 40.579675)
		(end 35.306 41.148)
		(width 0.12065)
		(layer "In6.Cu")
		(net "10N2410")
	)
	(segment
		(start 35.8267 42.4307)
		(end 35.8267 42.545)
		(width 0.12065)
		(layer "In6.Cu")
		(net "10N2410")
	)
	(segment
		(start 34.996171 38.865175)
		(end 34.737675 39.123671)
		(width 0.12065)
		(layer "In6.Cu")
		(net "10N2410")
	)
	(segment
		(start 35.429825 38.865175)
		(end 34.996171 38.865175)
		(width 0.12065)
		(layer "In6.Cu")
		(net "10N2410")
	)
	(segment
		(start 35.306 41.148)
		(end 35.306 41.91)
		(width 0.12065)
		(layer "In6.Cu")
		(net "10N2410")
	)
	(segment
		(start 34.737675 39.123671)
		(end 34.737675 40.579675)
		(width 0.12065)
		(layer "In6.Cu")
		(net "10N2410")
	)
	(segment
		(start 35.9029 36.195)
		(end 35.87496 36.322)
		(width 0.14732)
		(layer "F.Cu")
		(net "10N2409")
	)
	(segment
		(start 35.36696 36.83)
		(end 35.36696 37.018366)
		(width 0.14732)
		(layer "F.Cu")
		(net "10N2409")
	)
	(segment
		(start 35.36696 37.018366)
		(end 35.035338 37.349989)
		(width 0.14732)
		(layer "F.Cu")
		(net "10N2409")
	)
	(segment
		(start 35.87496 36.322)
		(end 35.36696 36.83)
		(width 0.14732)
		(layer "F.Cu")
		(net "10N2409")
	)
	(segment
		(start 35.035338 37.349989)
		(end 34.0614 37.349989)
		(width 0.14732)
		(layer "F.Cu")
		(net "10N2409")
	)
	(via
		(at 35.9029 36.195)
		(size 0.508)
		(drill 0.25654)
		(layers "F.Cu" "B.Cu")
		(net "10N2409")
	)
	(via
		(at 37.338 36.195)
		(size 0.762)
		(drill 0.381)
		(layers "F.Cu" "B.Cu")
		(net "10N2409")
	)
	(segment
		(start 35.9029 36.195)
		(end 37.338 36.195)
		(width 0.14732)
		(layer "B.Cu")
		(net "10N2409")
	)
	(segment
		(start 23.4061 44.069)
		(end 23.4061 42.6085)
		(width 0.14732)
		(layer "F.Cu")
		(net "10N2407")
	)
	(segment
		(start 25.527 42.291)
		(end 23.399166 42.291)
		(width 0.14732)
		(layer "F.Cu")
		(net "10N2407")
	)
	(segment
		(start 23.4061 42.6085)
		(end 23.2537 42.4434)
		(width 0.14732)
		(layer "F.Cu")
		(net "10N2407")
	)
	(segment
		(start 26.7589 42.164)
		(end 26.6319 42.291)
		(width 0.14732)
		(layer "F.Cu")
		(net "10N2407")
	)
	(segment
		(start 23.399166 42.291)
		(end 23.2537 42.4434)
		(width 0.14732)
		(layer "F.Cu")
		(net "10N2407")
	)
	(segment
		(start 26.6319 42.291)
		(end 25.527 42.291)
		(width 0.14732)
		(layer "F.Cu")
		(net "10N2407")
	)
	(via
		(at 25.527 42.291)
		(size 0.762)
		(drill 0.381)
		(layers "F.Cu" "B.Cu")
		(net "10N2407")
	)
	(segment
		(start 35.263912 37.849988)
		(end 34.0614 37.849988)
		(width 0.14732)
		(layer "F.Cu")
		(net "10N2403")
	)
	(segment
		(start 35.9029 37.211)
		(end 35.263912 37.849988)
		(width 0.14732)
		(layer "F.Cu")
		(net "10N2403")
	)
	(via
		(at 35.9029 37.211)
		(size 0.508)
		(drill 0.25654)
		(layers "F.Cu" "B.Cu")
		(net "10N2403")
	)
	(via
		(at 38.1 37.719)
		(size 0.762)
		(drill 0.381)
		(layers "F.Cu" "B.Cu")
		(net "10N2403")
	)
	(segment
		(start 36.47186 36.64204)
		(end 35.9029 37.211)
		(width 0.14732)
		(layer "B.Cu")
		(net "10N2403")
	)
	(segment
		(start 37.22116 36.908334)
		(end 36.954866 36.64204)
		(width 0.14732)
		(layer "B.Cu")
		(net "10N2403")
	)
	(segment
		(start 37.95268 36.908334)
		(end 37.22116 36.908334)
		(width 0.14732)
		(layer "B.Cu")
		(net "10N2403")
	)
	(segment
		(start 38.1 37.055654)
		(end 37.95268 36.908334)
		(width 0.14732)
		(layer "B.Cu")
		(net "10N2403")
	)
	(segment
		(start 36.954866 36.64204)
		(end 36.47186 36.64204)
		(width 0.14732)
		(layer "B.Cu")
		(net "10N2403")
	)
	(segment
		(start 38.1 37.719)
		(end 38.1 37.055654)
		(width 0.14732)
		(layer "B.Cu")
		(net "10N2403")
	)
	(segment
		(start 27.4701 40.894)
		(end 27.0891 41.275)
		(width 0.14732)
		(layer "F.Cu")
		(net "10N2399")
	)
	(segment
		(start 28.1686 40.350008)
		(end 27.975966 40.350008)
		(width 0.14732)
		(layer "F.Cu")
		(net "10N2399")
	)
	(segment
		(start 27.540407 40.894)
		(end 27.4701 40.894)
		(width 0.14732)
		(layer "F.Cu")
		(net "10N2399")
	)
	(segment
		(start 27.975966 40.350008)
		(end 27.814727 40.511247)
		(width 0.14732)
		(layer "F.Cu")
		(net "10N2399")
	)
	(segment
		(start 27.814727 40.511247)
		(end 27.814727 40.61968)
		(width 0.14732)
		(layer "F.Cu")
		(net "10N2399")
	)
	(segment
		(start 27.814727 40.61968)
		(end 27.540407 40.894)
		(width 0.14732)
		(layer "F.Cu")
		(net "10N2399")
	)
	(via
		(at 27.813 38.989)
		(size 0.762)
		(drill 0.381)
		(layers "F.Cu" "B.Cu")
		(net "10N2399")
	)
	(via
		(at 27.0891 41.275)
		(size 0.508)
		(drill 0.25654)
		(layers "F.Cu" "B.Cu")
		(net "10N2399")
	)
	(segment
		(start 27.813 40.621407)
		(end 27.548434 40.885974)
		(width 0.14732)
		(layer "B.Cu")
		(net "10N2399")
	)
	(segment
		(start 27.305 41.275)
		(end 27.0891 41.275)
		(width 0.14732)
		(layer "B.Cu")
		(net "10N2399")
	)
	(segment
		(start 27.813 38.989)
		(end 27.813 40.621407)
		(width 0.14732)
		(layer "B.Cu")
		(net "10N2399")
	)
	(segment
		(start 27.548434 40.885974)
		(end 27.548434 41.031566)
		(width 0.14732)
		(layer "B.Cu")
		(net "10N2399")
	)
	(segment
		(start 27.548434 41.031566)
		(end 27.305 41.275)
		(width 0.14732)
		(layer "B.Cu")
		(net "10N2399")
	)
	(segment
		(start 28.003094 41.07434)
		(end 27.5971 41.609874)
		(width 0.14732)
		(layer "F.Cu")
		(net "10N2397")
	)
	(segment
		(start 28.26766 41.07434)
		(end 28.003094 41.07434)
		(width 0.14732)
		(layer "F.Cu")
		(net "10N2397")
	)
	(segment
		(start 27.5971 41.609874)
		(end 27.5971 42.164)
		(width 0.14732)
		(layer "F.Cu")
		(net "10N2397")
	)
	(segment
		(start 28.2956 41.0464)
		(end 28.26766 41.07434)
		(width 0.14732)
		(layer "F.Cu")
		(net "10N2397")
	)
	(segment
		(start 28.864992 41.0464)
		(end 28.2956 41.0464)
		(width 0.14732)
		(layer "F.Cu")
		(net "10N2397")
	)
	(via
		(at 29.083 38.735)
		(size 0.762)
		(drill 0.381)
		(layers "F.Cu" "B.Cu")
		(net "10N2397")
	)
	(via
		(at 28.003094 41.07434)
		(size 0.508)
		(drill 0.254)
		(layers "F.Cu" "B.Cu")
		(net "10N2397")
	)
	(segment
		(start 29.083 38.735)
		(end 28.194 39.624)
		(width 0.14732)
		(layer "B.Cu")
		(net "10N2397")
	)
	(segment
		(start 28.194 39.624)
		(end 28.194 40.767)
		(width 0.14732)
		(layer "B.Cu")
		(net "10N2397")
	)
	(segment
		(start 28.194 40.767)
		(end 28.003094 40.957906)
		(width 0.14732)
		(layer "B.Cu")
		(net "10N2397")
	)
	(segment
		(start 28.003094 40.957906)
		(end 28.003094 41.07434)
		(width 0.14732)
		(layer "B.Cu")
		(net "10N2397")
	)
	(segment
		(start 28.702 44.7421)
		(end 29.591 44.7421)
		(width 0.14732)
		(layer "F.Cu")
		(net "10N2386")
	)
	(segment
		(start 28.702 44.7421)
		(end 28.702 45.847)
		(width 0.14732)
		(layer "F.Cu")
		(net "10N2386")
	)
	(via
		(at 28.702 45.847)
		(size 0.762)
		(drill 0.381)
		(layers "F.Cu" "B.Cu")
		(net "10N2386")
	)
	(segment
		(start 31.369 43.5229)
		(end 30.861 43.5229)
		(width 0.14732)
		(layer "F.Cu")
		(net "10N2385")
	)
	(segment
		(start 30.861 43.5229)
		(end 30.48 43.9039)
		(width 0.14732)
		(layer "F.Cu")
		(net "10N2385")
	)
	(via
		(at 30.48 43.9039)
		(size 0.508)
		(drill 0.25654)
		(layers "F.Cu" "B.Cu")
		(net "10N2385")
	)
	(via
		(at 30.48 40.894)
		(size 0.762)
		(drill 0.381)
		(layers "F.Cu" "B.Cu")
		(net "10N2385")
	)
	(segment
		(start 30.48 42.799)
		(end 30.48 43.9039)
		(width 0.14732)
		(layer "B.Cu")
		(net "10N2385")
	)
	(segment
		(start 30.48 40.894)
		(end 30.734 41.148)
		(width 0.14732)
		(layer "B.Cu")
		(net "10N2385")
	)
	(segment
		(start 30.734 42.545)
		(end 30.48 42.799)
		(width 0.14732)
		(layer "B.Cu")
		(net "10N2385")
	)
	(segment
		(start 30.734 41.148)
		(end 30.734 42.545)
		(width 0.14732)
		(layer "B.Cu")
		(net "10N2385")
	)
	(segment
		(start 30.58922 42.116146)
		(end 30.58922 42.094226)
		(width 0.14732)
		(layer "F.Cu")
		(net "10N2384")
	)
	(segment
		(start 30.607 42.076446)
		(end 30.607 41.721634)
		(width 0.14732)
		(layer "F.Cu")
		(net "10N2384")
	)
	(segment
		(start 28.702 43.8023)
		(end 29.5529 42.9514)
		(width 0.14732)
		(layer "F.Cu")
		(net "10N2384")
	)
	(segment
		(start 30.58922 42.094226)
		(end 30.607 42.076446)
		(width 0.14732)
		(layer "F.Cu")
		(net "10N2384")
	)
	(segment
		(start 30.364989 41.413989)
		(end 30.364989 41.0464)
		(width 0.14732)
		(layer "F.Cu")
		(net "10N2384")
	)
	(segment
		(start 30.58922 41.63822)
		(end 30.364989 41.413989)
		(width 0.14732)
		(layer "F.Cu")
		(net "10N2384")
	)
	(segment
		(start 30.340706 42.36466)
		(end 30.58922 42.116146)
		(width 0.14732)
		(layer "F.Cu")
		(net "10N2384")
	)
	(segment
		(start 28.702 43.9039)
		(end 28.702 43.8023)
		(width 0.14732)
		(layer "F.Cu")
		(net "10N2384")
	)
	(segment
		(start 29.5529 42.926)
		(end 30.11424 42.36466)
		(width 0.14732)
		(layer "F.Cu")
		(net "10N2384")
	)
	(segment
		(start 29.5529 42.9514)
		(end 29.5529 42.926)
		(width 0.14732)
		(layer "F.Cu")
		(net "10N2384")
	)
	(segment
		(start 30.607 41.721634)
		(end 30.58922 41.703854)
		(width 0.14732)
		(layer "F.Cu")
		(net "10N2384")
	)
	(segment
		(start 30.11424 42.36466)
		(end 30.340706 42.36466)
		(width 0.14732)
		(layer "F.Cu")
		(net "10N2384")
	)
	(segment
		(start 30.58922 41.703854)
		(end 30.58922 41.63822)
		(width 0.14732)
		(layer "F.Cu")
		(net "10N2384")
	)
	(via
		(at 33.02 40.894)
		(size 0.762)
		(drill 0.381)
		(layers "F.Cu" "B.Cu")
		(net "10N2384")
	)
	(via
		(at 29.5529 42.9514)
		(size 0.508)
		(drill 0.25654)
		(layers "F.Cu" "B.Cu")
		(net "10N2384")
	)
	(segment
		(start 30.099 44.45)
		(end 29.60116 43.95216)
		(width 0.14732)
		(layer "B.Cu")
		(net "10N2384")
	)
	(segment
		(start 32.131 44.45)
		(end 30.099 44.45)
		(width 0.14732)
		(layer "B.Cu")
		(net "10N2384")
	)
	(segment
		(start 32.766 41.148)
		(end 32.766 43.815)
		(width 0.14732)
		(layer "B.Cu")
		(net "10N2384")
	)
	(segment
		(start 32.555866 43.99534)
		(end 32.43834 44.112866)
		(width 0.14732)
		(layer "B.Cu")
		(net "10N2384")
	)
	(segment
		(start 32.43834 44.112866)
		(end 32.43834 44.14266)
		(width 0.14732)
		(layer "B.Cu")
		(net "10N2384")
	)
	(segment
		(start 33.02 40.894)
		(end 32.766 41.148)
		(width 0.14732)
		(layer "B.Cu")
		(net "10N2384")
	)
	(segment
		(start 32.58566 43.99534)
		(end 32.555866 43.99534)
		(width 0.14732)
		(layer "B.Cu")
		(net "10N2384")
	)
	(segment
		(start 29.60116 43.361762)
		(end 29.5529 43.313502)
		(width 0.14732)
		(layer "B.Cu")
		(net "10N2384")
	)
	(segment
		(start 32.766 43.815)
		(end 32.58566 43.99534)
		(width 0.14732)
		(layer "B.Cu")
		(net "10N2384")
	)
	(segment
		(start 32.43834 44.14266)
		(end 32.131 44.45)
		(width 0.14732)
		(layer "B.Cu")
		(net "10N2384")
	)
	(segment
		(start 29.60116 43.95216)
		(end 29.60116 43.361762)
		(width 0.14732)
		(layer "B.Cu")
		(net "10N2384")
	)
	(segment
		(start 29.5529 43.313502)
		(end 29.5529 42.9514)
		(width 0.14732)
		(layer "B.Cu")
		(net "10N2384")
	)
	(segment
		(start 25.908 45.212)
		(end 26.162 44.958)
		(width 0.14732)
		(layer "F.Cu")
		(net "10N2383")
	)
	(segment
		(start 27.559 43.1419)
		(end 27.7368 42.9641)
		(width 0.14732)
		(layer "F.Cu")
		(net "10N2383")
	)
	(segment
		(start 26.67 43.1419)
		(end 27.559 43.1419)
		(width 0.14732)
		(layer "F.Cu")
		(net "10N2383")
	)
	(segment
		(start 24.935942 45.212)
		(end 25.908 45.212)
		(width 0.14732)
		(layer "F.Cu")
		(net "10N2383")
	)
	(segment
		(start 27.7368 42.9641)
		(end 28.575 42.9641)
		(width 0.14732)
		(layer "F.Cu")
		(net "10N2383")
	)
	(segment
		(start 26.5811 43.1419)
		(end 26.67 43.1419)
		(width 0.14732)
		(layer "F.Cu")
		(net "10N2383")
	)
	(segment
		(start 24.579377 45.568565)
		(end 24.935942 45.212)
		(width 0.14732)
		(layer "F.Cu")
		(net "10N2383")
	)
	(segment
		(start 26.162 43.561)
		(end 26.5811 43.1419)
		(width 0.14732)
		(layer "F.Cu")
		(net "10N2383")
	)
	(segment
		(start 26.162 44.958)
		(end 26.162 43.561)
		(width 0.14732)
		(layer "F.Cu")
		(net "10N2383")
	)
	(via
		(at 24.579377 45.568565)
		(size 0.762)
		(drill 0.381)
		(layers "F.Cu" "B.Cu")
		(net "10N2383")
	)
	(segment
		(start 32.865009 41.529)
		(end 32.865009 41.0464)
		(width 0.14732)
		(layer "F.Cu")
		(net "10N2381")
	)
	(segment
		(start 34.925 42.6085)
		(end 34.925 42.591406)
		(width 0.14732)
		(layer "F.Cu")
		(net "10N2381")
	)
	(segment
		(start 33.989594 41.656)
		(end 32.992009 41.656)
		(width 0.14732)
		(layer "F.Cu")
		(net "10N2381")
	)
	(segment
		(start 34.925 42.591406)
		(end 33.989594 41.656)
		(width 0.14732)
		(layer "F.Cu")
		(net "10N2381")
	)
	(segment
		(start 32.992009 41.656)
		(end 32.865009 41.529)
		(width 0.14732)
		(layer "F.Cu")
		(net "10N2381")
	)
	(via
		(at 34.925 42.6085)
		(size 0.508)
		(drill 0.25654)
		(layers "F.Cu" "B.Cu")
		(net "10N2381")
	)
	(via
		(at 34.417 43.18)
		(size 0.762)
		(drill 0.381)
		(layers "F.Cu" "B.Cu")
		(net "10N2381")
	)
	(segment
		(start 34.925 42.672)
		(end 34.417 43.18)
		(width 0.14732)
		(layer "B.Cu")
		(net "10N2381")
	)
	(segment
		(start 34.925 42.6085)
		(end 34.925 42.672)
		(width 0.14732)
		(layer "B.Cu")
		(net "10N2381")
	)
	(via
		(at 72.009 35.814)
		(size 0.762)
		(drill 0.381)
		(layers "F.Cu" "B.Cu")
		(net "10N2262")
	)
	(segment
		(start 69.13626 36.195)
		(end 69.00926 36.322)
		(width 0.14732)
		(layer "B.Cu")
		(net "10N2262")
	)
	(segment
		(start 68.568011 37.349989)
		(end 68.568011 37.6936)
		(width 0.14732)
		(layer "B.Cu")
		(net "10N2262")
	)
	(segment
		(start 69.00926 36.322)
		(end 69.00926 36.891366)
		(width 0.14732)
		(layer "B.Cu")
		(net "10N2262")
	)
	(segment
		(start 71.628 36.195)
		(end 69.13626 36.195)
		(width 0.14732)
		(layer "B.Cu")
		(net "10N2262")
	)
	(segment
		(start 68.961 36.939626)
		(end 68.961 36.957)
		(width 0.14732)
		(layer "B.Cu")
		(net "10N2262")
	)
	(segment
		(start 71.628 36.195)
		(end 72.009 35.814)
		(width 0.14732)
		(layer "B.Cu")
		(net "10N2262")
	)
	(segment
		(start 69.00926 36.891366)
		(end 68.961 36.939626)
		(width 0.14732)
		(layer "B.Cu")
		(net "10N2262")
	)
	(segment
		(start 74.9681 35.052)
		(end 74.2061 35.814)
		(width 0.14732)
		(layer "B.Cu")
		(net "10N2262")
	)
	(segment
		(start 74.2061 35.814)
		(end 72.009 35.814)
		(width 0.14732)
		(layer "B.Cu")
		(net "10N2262")
	)
	(segment
		(start 68.961 36.957)
		(end 68.568011 37.349989)
		(width 0.14732)
		(layer "B.Cu")
		(net "10N2262")
	)
	(via
		(at 55.626 37.338)
		(size 0.762)
		(drill 0.381)
		(layers "F.Cu" "B.Cu")
		(net "10N2259")
	)
	(segment
		(start 49.3649 36.322)
		(end 49.3649 36.957)
		(width 0.14732)
		(layer "B.Cu")
		(net "10N2259")
	)
	(segment
		(start 49.4919 36.195)
		(end 49.3649 36.322)
		(width 0.14732)
		(layer "B.Cu")
		(net "10N2259")
	)
	(segment
		(start 52.74818 35.41776)
		(end 51.943 36.195)
		(width 0.14732)
		(layer "B.Cu")
		(net "10N2259")
	)
	(segment
		(start 55.28056 36.99256)
		(end 55.626 37.338)
		(width 0.14732)
		(layer "B.Cu")
		(net "10N2259")
	)
	(segment
		(start 51.943 36.195)
		(end 49.4919 36.195)
		(width 0.14732)
		(layer "B.Cu")
		(net "10N2259")
	)
	(segment
		(start 48.971911 37.349989)
		(end 48.971911 37.6936)
		(width 0.14732)
		(layer "B.Cu")
		(net "10N2259")
	)
	(segment
		(start 55.28056 35.932262)
		(end 55.28056 36.99256)
		(width 0.14732)
		(layer "B.Cu")
		(net "10N2259")
	)
	(segment
		(start 52.74818 35.41776)
		(end 54.766058 35.41776)
		(width 0.14732)
		(layer "B.Cu")
		(net "10N2259")
	)
	(segment
		(start 49.3649 36.957)
		(end 48.971911 37.349989)
		(width 0.14732)
		(layer "B.Cu")
		(net "10N2259")
	)
	(segment
		(start 54.766058 35.41776)
		(end 55.28056 35.932262)
		(width 0.14732)
		(layer "B.Cu")
		(net "10N2259")
	)
	(via
		(at 44.196 35.306)
		(size 0.762)
		(drill 0.381)
		(layers "F.Cu" "B.Cu")
		(net "10N2256")
	)
	(segment
		(start 45.3009 36.1061)
		(end 45.3009 36.83)
		(width 0.14732)
		(layer "B.Cu")
		(net "10N2256")
	)
	(segment
		(start 45.971892 37.500992)
		(end 45.971892 37.6936)
		(width 0.14732)
		(layer "B.Cu")
		(net "10N2256")
	)
	(segment
		(start 45.3009 36.83)
		(end 45.971892 37.500992)
		(width 0.14732)
		(layer "B.Cu")
		(net "10N2256")
	)
	(segment
		(start 45.3009 36.1061)
		(end 44.9961 36.1061)
		(width 0.14732)
		(layer "B.Cu")
		(net "10N2256")
	)
	(segment
		(start 44.9961 36.1061)
		(end 44.196 35.306)
		(width 0.14732)
		(layer "B.Cu")
		(net "10N2256")
	)
	(via
		(at 63.8429 35.56)
		(size 0.762)
		(drill 0.381)
		(layers "F.Cu" "B.Cu")
		(net "10N2253")
	)
	(segment
		(start 64.389 36.1061)
		(end 64.897 36.1061)
		(width 0.14732)
		(layer "B.Cu")
		(net "10N2253")
	)
	(segment
		(start 63.8429 35.56)
		(end 64.389 36.1061)
		(width 0.14732)
		(layer "B.Cu")
		(net "10N2253")
	)
	(segment
		(start 64.897 36.195)
		(end 65.05956 36.35756)
		(width 0.14732)
		(layer "B.Cu")
		(net "10N2253")
	)
	(segment
		(start 65.567992 37.500992)
		(end 65.567992 37.6936)
		(width 0.14732)
		(layer "B.Cu")
		(net "10N2253")
	)
	(segment
		(start 65.05956 36.99256)
		(end 65.567992 37.500992)
		(width 0.14732)
		(layer "B.Cu")
		(net "10N2253")
	)
	(segment
		(start 65.05956 36.35756)
		(end 65.05956 36.99256)
		(width 0.14732)
		(layer "B.Cu")
		(net "10N2253")
	)
	(segment
		(start 64.897 36.1061)
		(end 64.897 36.195)
		(width 0.14732)
		(layer "B.Cu")
		(net "10N2253")
	)
	(via
		(at 41.656 36.703)
		(size 0.762)
		(drill 0.381)
		(layers "F.Cu" "B.Cu")
		(net "10N2235")
	)
	(segment
		(start 41.656 36.703)
		(end 42.291 36.703)
		(width 0.14732)
		(layer "B.Cu")
		(net "10N2235")
	)
	(segment
		(start 44.45 36.449)
		(end 44.45 38.608)
		(width 0.14732)
		(layer "B.Cu")
		(net "10N2235")
	)
	(segment
		(start 44.45 38.608)
		(end 44.731991 38.889991)
		(width 0.14732)
		(layer "B.Cu")
		(net "10N2235")
	)
	(segment
		(start 41.656 36.703)
		(end 41.783 35.7251)
		(width 0.14732)
		(layer "B.Cu")
		(net "10N2235")
	)
	(segment
		(start 43.942 35.941)
		(end 44.45 36.449)
		(width 0.14732)
		(layer "B.Cu")
		(net "10N2235")
	)
	(segment
		(start 44.731991 38.889991)
		(end 45.2755 38.889991)
		(width 0.14732)
		(layer "B.Cu")
		(net "10N2235")
	)
	(segment
		(start 42.291 36.703)
		(end 43.053 35.941)
		(width 0.14732)
		(layer "B.Cu")
		(net "10N2235")
	)
	(segment
		(start 43.053 35.941)
		(end 43.942 35.941)
		(width 0.14732)
		(layer "B.Cu")
		(net "10N2235")
	)
	(via
		(at 43.815 31.496)
		(size 0.762)
		(drill 0.381)
		(layers "F.Cu" "B.Cu")
		(net "10N2233")
	)
	(segment
		(start 49.178972 32.358889)
		(end 49.178972 34.827972)
		(width 0.14732)
		(layer "B.Cu")
		(net "10N2233")
	)
	(segment
		(start 46.178953 31.358891)
		(end 46.178953 31.60903)
		(width 0.14732)
		(layer "B.Cu")
		(net "10N2233")
	)
	(segment
		(start 46.178953 31.60903)
		(end 46.553882 31.983959)
		(width 0.14732)
		(layer "B.Cu")
		(net "10N2233")
	)
	(segment
		(start 43.942 31.496)
		(end 44.337961 31.100039)
		(width 0.14732)
		(layer "B.Cu")
		(net "10N2233")
	)
	(segment
		(start 44.337961 31.100039)
		(end 45.920101 31.100039)
		(width 0.14732)
		(layer "B.Cu")
		(net "10N2233")
	)
	(segment
		(start 49.784 35.433)
		(end 49.80178 35.433)
		(width 0.14732)
		(layer "B.Cu")
		(net "10N2233")
	)
	(segment
		(start 43.815 31.496)
		(end 43.942 31.496)
		(width 0.14732)
		(layer "B.Cu")
		(net "10N2233")
	)
	(segment
		(start 45.920101 31.100039)
		(end 46.178953 31.358891)
		(width 0.14732)
		(layer "B.Cu")
		(net "10N2233")
	)
	(segment
		(start 46.553882 31.983959)
		(end 48.804043 31.983959)
		(width 0.14732)
		(layer "B.Cu")
		(net "10N2233")
	)
	(segment
		(start 49.80178 35.433)
		(end 51.14798 35.41776)
		(width 0.14732)
		(layer "B.Cu")
		(net "10N2233")
	)
	(segment
		(start 48.804043 31.983959)
		(end 49.178972 32.358889)
		(width 0.14732)
		(layer "B.Cu")
		(net "10N2233")
	)
	(segment
		(start 49.178972 34.827972)
		(end 49.784 35.433)
		(width 0.14732)
		(layer "B.Cu")
		(net "10N2233")
	)
	(segment
		(start 43.053 37.465)
		(end 43.18 37.338)
		(width 0.14732)
		(layer "F.Cu")
		(net "10N2232")
	)
	(segment
		(start 43.18 37.338)
		(end 43.688 37.338)
		(width 0.14732)
		(layer "F.Cu")
		(net "10N2232")
	)
	(segment
		(start 44.323 36.703)
		(end 47.9679 36.703)
		(width 0.14732)
		(layer "F.Cu")
		(net "10N2232")
	)
	(segment
		(start 43.688 37.338)
		(end 44.323 36.703)
		(width 0.14732)
		(layer "F.Cu")
		(net "10N2232")
	)
	(via
		(at 43.053 37.465)
		(size 0.762)
		(drill 0.381)
		(layers "F.Cu" "B.Cu")
		(net "10N2232")
	)
	(via
		(at 47.9679 36.703)
		(size 0.508)
		(drill 0.254)
		(layers "F.Cu" "B.Cu")
		(net "10N2232")
	)
	(segment
		(start 48.20158 35.433)
		(end 48.1838 36.4871)
		(width 0.14732)
		(layer "B.Cu")
		(net "10N2232")
	)
	(segment
		(start 48.1838 36.4871)
		(end 47.9679 36.703)
		(width 0.14732)
		(layer "B.Cu")
		(net "10N2232")
	)
	(segment
		(start 47.9679 36.703)
		(end 47.471889 37.199011)
		(width 0.14732)
		(layer "B.Cu")
		(net "10N2232")
	)
	(segment
		(start 47.471889 37.199011)
		(end 47.471889 37.6936)
		(width 0.14732)
		(layer "B.Cu")
		(net "10N2232")
	)
	(via
		(at 62.605945 31.655537)
		(size 0.762)
		(drill 0.381)
		(layers "F.Cu" "B.Cu")
		(net "10N2230")
	)
	(segment
		(start 62.484 33.02)
		(end 62.992 33.02)
		(width 0.14732)
		(layer "B.Cu")
		(net "10N2230")
	)
	(segment
		(start 64.416991 38.889991)
		(end 64.8716 38.889991)
		(width 0.14732)
		(layer "B.Cu")
		(net "10N2230")
	)
	(segment
		(start 62.243741 32.017741)
		(end 62.243741 32.779741)
		(width 0.14732)
		(layer "B.Cu")
		(net "10N2230")
	)
	(segment
		(start 62.243741 32.779741)
		(end 62.484 33.02)
		(width 0.14732)
		(layer "B.Cu")
		(net "10N2230")
	)
	(segment
		(start 63.246 34.050732)
		(end 63.246 35.814)
		(width 0.14732)
		(layer "B.Cu")
		(net "10N2230")
	)
	(segment
		(start 62.992 33.02)
		(end 63.237364 33.265364)
		(width 0.14732)
		(layer "B.Cu")
		(net "10N2230")
	)
	(segment
		(start 63.246 35.814)
		(end 64.135 36.703)
		(width 0.14732)
		(layer "B.Cu")
		(net "10N2230")
	)
	(segment
		(start 63.237364 33.265364)
		(end 63.237364 34.042096)
		(width 0.14732)
		(layer "B.Cu")
		(net "10N2230")
	)
	(segment
		(start 63.237364 34.042096)
		(end 63.246 34.050732)
		(width 0.14732)
		(layer "B.Cu")
		(net "10N2230")
	)
	(segment
		(start 62.605945 31.655537)
		(end 62.243741 32.017741)
		(width 0.14732)
		(layer "B.Cu")
		(net "10N2230")
	)
	(segment
		(start 64.135 36.703)
		(end 64.135 38.608)
		(width 0.14732)
		(layer "B.Cu")
		(net "10N2230")
	)
	(segment
		(start 64.135 38.608)
		(end 64.416991 38.889991)
		(width 0.14732)
		(layer "B.Cu")
		(net "10N2230")
	)
	(via
		(at 72.009 33.147)
		(size 0.762)
		(drill 0.381)
		(layers "F.Cu" "B.Cu")
		(net "10N2229")
	)
	(segment
		(start 67.675506 36.98748)
		(end 67.287546 36.98748)
		(width 0.14732)
		(layer "B.Cu")
		(net "10N2229")
	)
	(segment
		(start 68.961 35.56)
		(end 68.10248 36.41852)
		(width 0.14732)
		(layer "B.Cu")
		(net "10N2229")
	)
	(segment
		(start 72.009 33.147)
		(end 71.055967 34.100033)
		(width 0.14732)
		(layer "B.Cu")
		(net "10N2229")
	)
	(segment
		(start 68.10248 36.560506)
		(end 67.675506 36.98748)
		(width 0.14732)
		(layer "B.Cu")
		(net "10N2229")
	)
	(segment
		(start 68.10248 36.41852)
		(end 68.10248 36.560506)
		(width 0.14732)
		(layer "B.Cu")
		(net "10N2229")
	)
	(segment
		(start 67.067989 37.207038)
		(end 67.067989 37.6936)
		(width 0.14732)
		(layer "B.Cu")
		(net "10N2229")
	)
	(segment
		(start 69.553887 34.100033)
		(end 69.295035 34.358885)
		(width 0.14732)
		(layer "B.Cu")
		(net "10N2229")
	)
	(segment
		(start 69.0499 35.56)
		(end 68.961 35.56)
		(width 0.14732)
		(layer "B.Cu")
		(net "10N2229")
	)
	(segment
		(start 69.0499 34.854159)
		(end 69.0499 35.56)
		(width 0.14732)
		(layer "B.Cu")
		(net "10N2229")
	)
	(segment
		(start 71.055967 34.100033)
		(end 69.553887 34.100033)
		(width 0.14732)
		(layer "B.Cu")
		(net "10N2229")
	)
	(segment
		(start 69.295035 34.358885)
		(end 69.295035 34.609024)
		(width 0.14732)
		(layer "B.Cu")
		(net "10N2229")
	)
	(segment
		(start 67.287546 36.98748)
		(end 67.067989 37.207038)
		(width 0.14732)
		(layer "B.Cu")
		(net "10N2229")
	)
	(segment
		(start 69.295035 34.609024)
		(end 69.0499 34.854159)
		(width 0.14732)
		(layer "B.Cu")
		(net "10N2229")
	)
	(via
		(at 72.009 34.544)
		(size 0.762)
		(drill 0.381)
		(layers "F.Cu" "B.Cu")
		(net "10N2228")
	)
	(segment
		(start 70.866 34.544)
		(end 70.6501 34.7599)
		(width 0.14732)
		(layer "B.Cu")
		(net "10N2228")
	)
	(segment
		(start 70.6501 34.7599)
		(end 70.6501 35.56)
		(width 0.14732)
		(layer "B.Cu")
		(net "10N2228")
	)
	(segment
		(start 72.009 34.544)
		(end 72.8599 34.544)
		(width 0.14732)
		(layer "B.Cu")
		(net "10N2228")
	)
	(segment
		(start 72.8599 34.544)
		(end 73.3679 35.052)
		(width 0.14732)
		(layer "B.Cu")
		(net "10N2228")
	)
	(segment
		(start 72.009 34.544)
		(end 70.866 34.544)
		(width 0.14732)
		(layer "B.Cu")
		(net "10N2228")
	)
	(via
		(at 67.692651 35.428733)
		(size 0.762)
		(drill 0.381)
		(layers "F.Cu" "B.Cu")
		(net "10N2227")
	)
	(segment
		(start 67.173907 36.71316)
		(end 66.56799 37.319077)
		(width 0.14732)
		(layer "B.Cu")
		(net "10N2227")
	)
	(segment
		(start 67.82816 35.637394)
		(end 67.82816 36.446866)
		(width 0.14732)
		(layer "B.Cu")
		(net "10N2227")
	)
	(segment
		(start 67.692651 35.428733)
		(end 67.692651 35.501885)
		(width 0.14732)
		(layer "B.Cu")
		(net "10N2227")
	)
	(segment
		(start 66.56799 37.319077)
		(end 66.56799 37.6936)
		(width 0.14732)
		(layer "B.Cu")
		(net "10N2227")
	)
	(segment
		(start 67.692651 35.501885)
		(end 67.82816 35.637394)
		(width 0.14732)
		(layer "B.Cu")
		(net "10N2227")
	)
	(segment
		(start 67.561866 36.71316)
		(end 67.173907 36.71316)
		(width 0.14732)
		(layer "B.Cu")
		(net "10N2227")
	)
	(segment
		(start 67.82816 36.446866)
		(end 67.561866 36.71316)
		(width 0.14732)
		(layer "B.Cu")
		(net "10N2227")
	)
	(via
		(at 43.815 32.766)
		(size 0.762)
		(drill 0.381)
		(layers "F.Cu" "B.Cu")
		(net "10N2225")
	)
	(segment
		(start 47.244 33.274)
		(end 46.946337 32.976337)
		(width 0.13208)
		(layer "B.Cu")
		(net "10N2225")
	)
	(segment
		(start 45.916926 32.107657)
		(end 44.473343 32.107657)
		(width 0.13208)
		(layer "B.Cu")
		(net "10N2225")
	)
	(segment
		(start 46.97189 37.6936)
		(end 46.97189 37.032235)
		(width 0.13208)
		(layer "B.Cu")
		(net "10N2225")
	)
	(segment
		(start 46.97189 37.032235)
		(end 47.52594 36.478185)
		(width 0.13208)
		(layer "B.Cu")
		(net "10N2225")
	)
	(segment
		(start 46.946337 32.976337)
		(end 46.557057 32.976337)
		(width 0.13208)
		(layer "B.Cu")
		(net "10N2225")
	)
	(segment
		(start 46.557057 32.976337)
		(end 46.171333 32.590613)
		(width 0.13208)
		(layer "B.Cu")
		(net "10N2225")
	)
	(segment
		(start 47.244 34.544)
		(end 47.244 33.274)
		(width 0.13208)
		(layer "B.Cu")
		(net "10N2225")
	)
	(segment
		(start 47.302649 34.602649)
		(end 47.244 34.544)
		(width 0.13208)
		(layer "B.Cu")
		(net "10N2225")
	)
	(segment
		(start 47.52594 34.945218)
		(end 47.302649 34.721927)
		(width 0.13208)
		(layer "B.Cu")
		(net "10N2225")
	)
	(segment
		(start 46.171333 32.590613)
		(end 46.171333 32.362064)
		(width 0.13208)
		(layer "B.Cu")
		(net "10N2225")
	)
	(segment
		(start 47.302649 34.721927)
		(end 47.302649 34.602649)
		(width 0.13208)
		(layer "B.Cu")
		(net "10N2225")
	)
	(segment
		(start 47.52594 36.478185)
		(end 47.52594 34.945218)
		(width 0.13208)
		(layer "B.Cu")
		(net "10N2225")
	)
	(segment
		(start 46.171333 32.362064)
		(end 45.916926 32.107657)
		(width 0.13208)
		(layer "B.Cu")
		(net "10N2225")
	)
	(segment
		(start 44.473343 32.107657)
		(end 43.815 32.766)
		(width 0.13208)
		(layer "B.Cu")
		(net "10N2225")
	)
	(via
		(at 62.2173 35.463328)
		(size 0.762)
		(drill 0.381)
		(layers "F.Cu" "B.Cu")
		(net "10N2224")
	)
	(segment
		(start 61.77534 37.022634)
		(end 62.2173 36.580674)
		(width 0.14732)
		(layer "B.Cu")
		(net "10N2224")
	)
	(segment
		(start 62.66434 38.53434)
		(end 61.77534 37.64534)
		(width 0.14732)
		(layer "B.Cu")
		(net "10N2224")
	)
	(segment
		(start 62.66434 38.665734)
		(end 62.66434 38.53434)
		(width 0.14732)
		(layer "B.Cu")
		(net "10N2224")
	)
	(segment
		(start 62.2173 36.580674)
		(end 62.2173 35.463328)
		(width 0.14732)
		(layer "B.Cu")
		(net "10N2224")
	)
	(segment
		(start 63.119 39.1541)
		(end 63.119 39.120394)
		(width 0.14732)
		(layer "B.Cu")
		(net "10N2224")
	)
	(segment
		(start 63.119 39.120394)
		(end 62.66434 38.665734)
		(width 0.14732)
		(layer "B.Cu")
		(net "10N2224")
	)
	(segment
		(start 63.119 39.1541)
		(end 63.119 40.2844)
		(width 0.508)
		(layer "B.Cu")
		(net "10N2224")
	)
	(segment
		(start 61.77534 37.64534)
		(end 61.77534 37.022634)
		(width 0.14732)
		(layer "B.Cu")
		(net "10N2224")
	)
	(via
		(at 42.037 41.402)
		(size 0.762)
		(drill 0.381)
		(layers "F.Cu" "B.Cu")
		(net "10N2223")
	)
	(segment
		(start 43.5229 39.1541)
		(end 43.5229 40.2844)
		(width 0.508)
		(layer "B.Cu")
		(net "10N2223")
	)
	(segment
		(start 42.926 40.894)
		(end 43.5229 40.2971)
		(width 0.14732)
		(layer "B.Cu")
		(net "10N2223")
	)
	(segment
		(start 43.5229 40.2971)
		(end 43.5229 40.2844)
		(width 0.14732)
		(layer "B.Cu")
		(net "10N2223")
	)
	(segment
		(start 42.037 41.402)
		(end 42.545 40.894)
		(width 0.14732)
		(layer "B.Cu")
		(net "10N2223")
	)
	(segment
		(start 42.545 40.894)
		(end 42.926 40.894)
		(width 0.14732)
		(layer "B.Cu")
		(net "10N2223")
	)
	(segment
		(start 9.017 0.254)
		(end 9.017 0.9144)
		(width 0.14732)
		(layer "F.Cu")
		(net "9N2152")
	)
	(segment
		(start 9.017 0.9144)
		(end 8.7884 1.143)
		(width 0.14732)
		(layer "F.Cu")
		(net "9N2152")
	)
	(segment
		(start 8.7884 1.143)
		(end 8.7884 2.6416)
		(width 0.14732)
		(layer "F.Cu")
		(net "9N2152")
	)
	(via
		(at 9.017 0.254)
		(size 0.762)
		(drill 0.2667)
		(layers "F.Cu" "B.Cu")
		(net "9N2152")
	)
	(segment
		(start 9.017 1.1811)
		(end 5.4991 4.699)
		(width 0.14732)
		(layer "B.Cu")
		(net "9N2152")
	)
	(segment
		(start 9.017 0.254)
		(end 9.017 1.1811)
		(width 0.14732)
		(layer "B.Cu")
		(net "9N2152")
	)
	(segment
		(start 7.2898 0.8382)
		(end 7.874 0.254)
		(width 0.14732)
		(layer "F.Cu")
		(net "9N2141")
	)
	(segment
		(start 7.874 0.254)
		(end 7.874 -1.016)
		(width 0.14732)
		(layer "F.Cu")
		(net "9N2141")
	)
	(segment
		(start 7.2898 3.0861)
		(end 7.2898 0.8382)
		(width 0.14732)
		(layer "F.Cu")
		(net "9N2141")
	)
	(via
		(at 7.874 0.254)
		(size 0.508)
		(drill 0.254)
		(layers "F.Cu" "B.Cu")
		(net "9N2141")
	)
	(via
		(at 7.874 -1.016)
		(size 0.762)
		(drill 0.381)
		(layers "F.Cu" "B.Cu")
		(net "9N2141")
	)
	(segment
		(start 7.874 0.254)
		(end 7.874 1.4351)
		(width 0.14732)
		(layer "B.Cu")
		(net "9N2141")
	)
	(segment
		(start 7.874 1.4351)
		(end 5.4991 3.81)
		(width 0.14732)
		(layer "B.Cu")
		(net "9N2141")
	)
	(segment
		(start 24.4348 34.0868)
		(end 24.511 34.163)
		(width 0.14732)
		(layer "F.Cu")
		(net "9N2032")
	)
	(segment
		(start 23.85601 34.0868)
		(end 24.4348 34.0868)
		(width 0.14732)
		(layer "F.Cu")
		(net "9N2032")
	)
	(via
		(at 24.511 34.163)
		(size 0.508)
		(drill 0.2667)
		(layers "F.Cu" "B.Cu")
		(net "9N2032")
	)
	(segment
		(start 23.1521 31.75)
		(end 23.241 31.75)
		(width 0.14732)
		(layer "B.Cu")
		(net "9N2032")
	)
	(segment
		(start 23.876 33.528)
		(end 24.511 34.163)
		(width 0.14732)
		(layer "B.Cu")
		(net "9N2032")
	)
	(segment
		(start 23.876 32.385)
		(end 23.876 33.528)
		(width 0.14732)
		(layer "B.Cu")
		(net "9N2032")
	)
	(segment
		(start 23.241 31.75)
		(end 23.876 32.385)
		(width 0.14732)
		(layer "B.Cu")
		(net "9N2032")
	)
	(segment
		(start 33.246009 29.187191)
		(end 33.246009 28.548406)
		(width 0.14732)
		(layer "F.Cu")
		(net "9N1879")
	)
	(segment
		(start 32.6898 29.7434)
		(end 33.246009 29.187191)
		(width 0.14732)
		(layer "F.Cu")
		(net "9N1879")
	)
	(via
		(at 32.6898 29.7434)
		(size 0.4572)
		(drill 0.20574)
		(layers "F.Cu" "B.Cu")
		(net "9N1879")
	)
	(segment
		(start 32.6898 29.7434)
		(end 32.512 29.5656)
		(width 0.14732)
		(layer "B.Cu")
		(net "9N1879")
	)
	(segment
		(start 32.512 29.5656)
		(end 32.512 28.7401)
		(width 0.14732)
		(layer "B.Cu")
		(net "9N1879")
	)
	(segment
		(start 76.2508 28.1559)
		(end 76.2889 28.194)
		(width 0.14732)
		(layer "F.Cu")
		(net "6N4748")
	)
	(segment
		(start 74.3712 28.1559)
		(end 75.3872 28.1559)
		(width 0.14732)
		(layer "F.Cu")
		(net "6N4748")
	)
	(segment
		(start 76.2889 29.083)
		(end 76.2889 28.194)
		(width 0.14732)
		(layer "F.Cu")
		(net "6N4748")
	)
	(segment
		(start 75.3872 28.1559)
		(end 76.2508 28.1559)
		(width 0.14732)
		(layer "F.Cu")
		(net "6N4748")
	)
	(via
		(at 75.3872 28.1559)
		(size 0.762)
		(drill 0.381)
		(layers "F.Cu" "B.Cu")
		(net "6N4748")
	)
	(segment
		(start 62.737009 21.541994)
		(end 62.23701 21.041995)
		(width 0.13208)
		(layer "F.Cu")
		(net "6N3963")
	)
	(via
		(at 62.737009 21.541994)
		(size 0.4826)
		(drill 0.20574)
		(layers "F.Cu" "B.Cu")
		(net "6N3963")
	)
	(via
		(at 61.737011 20.541996)
		(size 0.762)
		(drill 0.381)
		(layers "F.Cu" "B.Cu")
		(net "6N3963")
	)
	(segment
		(start 62.316208 21.249792)
		(end 62.444808 21.249792)
		(width 0.14732)
		(layer "B.Cu")
		(net "6N3963")
	)
	(segment
		(start 61.737011 20.541996)
		(end 62.316208 21.249792)
		(width 0.14732)
		(layer "B.Cu")
		(net "6N3963")
	)
	(segment
		(start 63.236856 22.041841)
		(end 63.236856 22.041993)
		(width 0.14732)
		(layer "B.Cu")
		(net "6N3963")
	)
	(segment
		(start 62.737009 21.541994)
		(end 63.236856 22.041841)
		(width 0.14732)
		(layer "B.Cu")
		(net "6N3963")
	)
	(segment
		(start 62.444808 21.249792)
		(end 62.737009 21.541994)
		(width 0.14732)
		(layer "B.Cu")
		(net "6N3963")
	)
	(segment
		(start 64.737005 21.541994)
		(end 64.237006 21.041995)
		(width 0.13208)
		(layer "F.Cu")
		(net "6N3961")
	)
	(via
		(at 64.737005 21.541994)
		(size 0.4826)
		(drill 0.20574)
		(layers "F.Cu" "B.Cu")
		(net "6N3961")
	)
	(via
		(at 65.913 21.971)
		(size 0.762)
		(drill 0.381)
		(layers "F.Cu" "B.Cu")
		(net "6N3961")
	)
	(segment
		(start 66.802 23.995126)
		(end 66.428874 23.622)
		(width 0.14732)
		(layer "B.Cu")
		(net "6N3961")
	)
	(segment
		(start 65.913 23.106126)
		(end 65.913 21.971)
		(width 0.14732)
		(layer "B.Cu")
		(net "6N3961")
	)
	(segment
		(start 65.483994 21.541994)
		(end 64.737005 21.541994)
		(width 0.14732)
		(layer "B.Cu")
		(net "6N3961")
	)
	(segment
		(start 65.913 21.971)
		(end 65.483994 21.541994)
		(width 0.14732)
		(layer "B.Cu")
		(net "6N3961")
	)
	(segment
		(start 66.802 24.899874)
		(end 66.802 23.995126)
		(width 0.14732)
		(layer "B.Cu")
		(net "6N3961")
	)
	(segment
		(start 66.428874 23.622)
		(end 65.913 23.106126)
		(width 0.14732)
		(layer "B.Cu")
		(net "6N3961")
	)
	(segment
		(start 21.971 17.272)
		(end 21.971 17.7038)
		(width 0.14732)
		(layer "F.Cu")
		(net "3N2521")
	)
	(segment
		(start 21.5138 18.8341)
		(end 21.5138 18.161)
		(width 0.14732)
		(layer "F.Cu")
		(net "3N2521")
	)
	(segment
		(start 21.971 17.7038)
		(end 21.5138 18.161)
		(width 0.14732)
		(layer "F.Cu")
		(net "3N2521")
	)
	(via
		(at 22.792207 26.876629)
		(size 0.762)
		(drill 0.381)
		(layers "F.Cu" "B.Cu")
		(net "3N2521")
	)
	(via
		(at 21.5138 18.161)
		(size 0.508)
		(drill 0.25654)
		(layers "F.Cu" "B.Cu")
		(net "3N2521")
	)
	(segment
		(start 21.5138 18.161)
		(end 21.3614 18.3134)
		(width 0.14732)
		(layer "B.Cu")
		(net "3N2521")
	)
	(segment
		(start 22.558629 26.876629)
		(end 21.971 26.289)
		(width 0.14732)
		(layer "B.Cu")
		(net "3N2521")
	)
	(segment
		(start 22.792207 26.876629)
		(end 22.558629 26.876629)
		(width 0.14732)
		(layer "B.Cu")
		(net "3N2521")
	)
	(segment
		(start 21.971 26.289)
		(end 21.971 25.019)
		(width 0.14732)
		(layer "B.Cu")
		(net "3N2521")
	)
	(segment
		(start 21.3614 22.1234)
		(end 21.971 22.733)
		(width 0.14732)
		(layer "B.Cu")
		(net "3N2521")
	)
	(segment
		(start 21.3614 18.3134)
		(end 21.3614 22.1234)
		(width 0.14732)
		(layer "B.Cu")
		(net "3N2521")
	)
	(segment
		(start 21.971 22.733)
		(end 21.971 25.019)
		(width 0.14732)
		(layer "B.Cu")
		(net "3N2521")
	)
	(segment
		(start 34.925 7.493)
		(end 34.532011 7.100011)
		(width 0.14732)
		(layer "F.Cu")
		(net "3N2302")
	)
	(segment
		(start 34.925 8.0391)
		(end 34.925 7.493)
		(width 0.14732)
		(layer "F.Cu")
		(net "3N2302")
	)
	(segment
		(start 35.5219 8.636)
		(end 34.925 8.0391)
		(width 0.14732)
		(layer "F.Cu")
		(net "3N2302")
	)
	(segment
		(start 34.532011 7.100011)
		(end 34.2646 7.100011)
		(width 0.14732)
		(layer "F.Cu")
		(net "3N2302")
	)
	(via
		(at 35.5219 8.636)
		(size 0.508)
		(drill 0.25654)
		(layers "F.Cu" "B.Cu")
		(net "3N2302")
	)
	(segment
		(start 35.5219 9.779)
		(end 34.65068 8.90778)
		(width 0.14732)
		(layer "F.Cu")
		(net "3N2301")
	)
	(segment
		(start 34.65068 8.90778)
		(end 34.65068 7.98609)
		(width 0.14732)
		(layer "F.Cu")
		(net "3N2301")
	)
	(segment
		(start 34.65068 7.98609)
		(end 34.2646 7.60001)
		(width 0.14732)
		(layer "F.Cu")
		(net "3N2301")
	)
	(via
		(at 35.5219 9.7028)
		(size 0.508)
		(drill 0.25654)
		(layers "F.Cu" "B.Cu")
		(net "3N2301")
	)
	(segment
		(start 34.801988 6.099988)
		(end 34.2646 6.099988)
		(width 0.14732)
		(layer "F.Cu")
		(net "3N2291")
	)
	(segment
		(start 35.052 6.35)
		(end 34.801988 6.099988)
		(width 0.14732)
		(layer "F.Cu")
		(net "3N2291")
	)
	(segment
		(start 35.5219 6.35)
		(end 35.052 6.35)
		(width 0.14732)
		(layer "F.Cu")
		(net "3N2291")
	)
	(via
		(at 35.5219 6.35)
		(size 0.508)
		(drill 0.25654)
		(layers "F.Cu" "B.Cu")
		(net "3N2291")
	)
	(segment
		(start 35.5219 7.493)
		(end 34.628912 6.600012)
		(width 0.14732)
		(layer "F.Cu")
		(net "3N2290")
	)
	(segment
		(start 34.628912 6.600012)
		(end 34.2646 6.600012)
		(width 0.14732)
		(layer "F.Cu")
		(net "3N2290")
	)
	(via
		(at 35.5219 7.493)
		(size 0.508)
		(drill 0.25654)
		(layers "F.Cu" "B.Cu")
		(net "3N2290")
	)
	(segment
		(start 34.29 2.7051)
		(end 35.3949 2.7051)
		(width 0.14732)
		(layer "F.Cu")
		(net "3N2287")
	)
	(segment
		(start 34.29 2.7051)
		(end 34.2646 2.7305)
		(width 0.14732)
		(layer "F.Cu")
		(net "3N2287")
	)
	(segment
		(start 34.2646 2.7305)
		(end 34.2646 5.09999)
		(width 0.14732)
		(layer "F.Cu")
		(net "3N2287")
	)
	(via
		(at 35.3949 2.7051)
		(size 0.762)
		(drill 0.381)
		(layers "F.Cu" "B.Cu")
		(net "3N2287")
	)
	(segment
		(start 30.62699 7.60001)
		(end 30.226 8.001)
		(width 0.14732)
		(layer "F.Cu")
		(net "3N2286")
	)
	(segment
		(start 30.226 8.001)
		(end 29.9212 8.001)
		(width 0.14732)
		(layer "F.Cu")
		(net "3N2286")
	)
	(segment
		(start 29.9212 8.001)
		(end 28.9941 7.112)
		(width 0.14732)
		(layer "F.Cu")
		(net "3N2286")
	)
	(segment
		(start 31.0134 7.60001)
		(end 30.62699 7.60001)
		(width 0.14732)
		(layer "F.Cu")
		(net "3N2286")
	)
	(via
		(at 29.9212 8.001)
		(size 0.762)
		(drill 0.381)
		(layers "F.Cu" "B.Cu")
		(net "3N2286")
	)
	(segment
		(start 33.389011 2.820111)
		(end 33.389011 3.8227)
		(width 0.14732)
		(layer "F.Cu")
		(net "3N2285")
	)
	(segment
		(start 33.274 2.7051)
		(end 33.389011 2.820111)
		(width 0.14732)
		(layer "F.Cu")
		(net "3N2285")
	)
	(via
		(at 33.274 2.7051)
		(size 0.508)
		(drill 0.25654)
		(layers "F.Cu" "B.Cu")
		(net "3N2285")
	)
	(segment
		(start 31.888989 9.005011)
		(end 31.888989 8.8773)
		(width 0.14732)
		(layer "F.Cu")
		(net "3N2284")
	)
	(segment
		(start 31.623 9.271)
		(end 31.888989 9.005011)
		(width 0.14732)
		(layer "F.Cu")
		(net "3N2284")
	)
	(segment
		(start 29.14142 9.271)
		(end 28.9941 9.12368)
		(width 0.14732)
		(layer "F.Cu")
		(net "3N2284")
	)
	(segment
		(start 29.845 9.271)
		(end 31.623 9.271)
		(width 0.14732)
		(layer "F.Cu")
		(net "3N2284")
	)
	(segment
		(start 28.9941 9.12368)
		(end 28.9941 8.255)
		(width 0.14732)
		(layer "F.Cu")
		(net "3N2284")
	)
	(segment
		(start 29.845 9.271)
		(end 29.14142 9.271)
		(width 0.14732)
		(layer "F.Cu")
		(net "3N2284")
	)
	(via
		(at 29.845 9.271)
		(size 0.762)
		(drill 0.381)
		(layers "F.Cu" "B.Cu")
		(net "3N2284")
	)
	(segment
		(start 21.59 7.239)
		(end 22.098 6.731)
		(width 0.14732)
		(layer "F.Cu")
		(net "NFP_SMBUS_ALERT_L")
	)
	(segment
		(start 21.336 10.16)
		(end 21.59 9.906)
		(width 0.14732)
		(layer "F.Cu")
		(net "NFP_SMBUS_ALERT_L")
	)
	(segment
		(start 19.558 10.16)
		(end 21.336 10.16)
		(width 0.14732)
		(layer "F.Cu")
		(net "NFP_SMBUS_ALERT_L")
	)
	(segment
		(start 22.101988 5.711012)
		(end 22.101988 5.1308)
		(width 0.14732)
		(layer "F.Cu")
		(net "NFP_SMBUS_ALERT_L")
	)
	(segment
		(start 22.098 5.715)
		(end 22.101988 5.711012)
		(width 0.14732)
		(layer "F.Cu")
		(net "NFP_SMBUS_ALERT_L")
	)
	(segment
		(start 17.907 8.509)
		(end 19.558 10.16)
		(width 0.14732)
		(layer "F.Cu")
		(net "NFP_SMBUS_ALERT_L")
	)
	(segment
		(start 22.098 6.35)
		(end 22.098 5.715)
		(width 0.14732)
		(layer "F.Cu")
		(net "NFP_SMBUS_ALERT_L")
	)
	(segment
		(start 17.907 7.5311)
		(end 17.907 8.509)
		(width 0.14732)
		(layer "F.Cu")
		(net "NFP_SMBUS_ALERT_L")
	)
	(segment
		(start 22.098 6.731)
		(end 22.098 6.35)
		(width 0.14732)
		(layer "F.Cu")
		(net "NFP_SMBUS_ALERT_L")
	)
	(segment
		(start 21.59 9.906)
		(end 21.59 7.239)
		(width 0.14732)
		(layer "F.Cu")
		(net "NFP_SMBUS_ALERT_L")
	)
	(segment
		(start 18.415 7.0231)
		(end 17.907 7.5311)
		(width 0.14732)
		(layer "F.Cu")
		(net "NFP_SMBUS_ALERT_L")
	)
	(via
		(at 22.098 6.35)
		(size 0.508)
		(drill 0.25654)
		(layers "F.Cu" "B.Cu")
		(net "NFP_SMBUS_ALERT_L")
	)
	(segment
		(start 22.098 4.9911)
		(end 22.0599 4.953)
		(width 0.14732)
		(layer "B.Cu")
		(net "NFP_SMBUS_ALERT_L")
	)
	(segment
		(start 22.098 6.35)
		(end 22.098 4.9911)
		(width 0.14732)
		(layer "B.Cu")
		(net "NFP_SMBUS_ALERT_L")
	)
	(segment
		(start -1.016 33.147)
		(end -0.635 33.528)
		(width 0.14732)
		(layer "F.Cu")
		(net "VDD_7401_PGOOD")
	)
	(segment
		(start 35.8267 26.9367)
		(end 34.857715 26.9367)
		(width 0.127)
		(layer "F.Cu")
		(net "VDD_7401_PGOOD")
	)
	(segment
		(start 36.2458 26.5176)
		(end 35.8267 26.9367)
		(width 0.127)
		(layer "F.Cu")
		(net "VDD_7401_PGOOD")
	)
	(segment
		(start -0.635 34.925)
		(end 0.254 35.814)
		(width 0.14732)
		(layer "F.Cu")
		(net "VDD_7401_PGOOD")
	)
	(segment
		(start 1.016 35.814)
		(end 1.524 35.306)
		(width 0.14732)
		(layer "F.Cu")
		(net "VDD_7401_PGOOD")
	)
	(segment
		(start 11.246104 38.410896)
		(end 11.176 38.481)
		(width 0.2032)
		(layer "F.Cu")
		(net "VDD_7401_PGOOD")
	)
	(segment
		(start -0.635 33.528)
		(end -0.635 34.925)
		(width 0.14732)
		(layer "F.Cu")
		(net "VDD_7401_PGOOD")
	)
	(segment
		(start 0.254 35.814)
		(end 1.016 35.814)
		(width 0.14732)
		(layer "F.Cu")
		(net "VDD_7401_PGOOD")
	)
	(segment
		(start 1.524 34.5821)
		(end 1.524 35.306)
		(width 0.14732)
		(layer "F.Cu")
		(net "VDD_7401_PGOOD")
	)
	(segment
		(start 12.3063 38.410896)
		(end 11.246104 38.410896)
		(width 0.2032)
		(layer "F.Cu")
		(net "VDD_7401_PGOOD")
	)
	(segment
		(start 34.857715 26.9367)
		(end 34.746006 27.048409)
		(width 0.127)
		(layer "F.Cu")
		(net "VDD_7401_PGOOD")
	)
	(via
		(at 27.051 30.353)
		(size 0.508)
		(drill 0.254)
		(layers "F.Cu" "B.Cu")
		(net "VDD_7401_PGOOD")
	)
	(via
		(at 11.938 30.607)
		(size 0.508)
		(drill 0.254)
		(layers "F.Cu" "B.Cu")
		(net "VDD_7401_PGOOD")
	)
	(via
		(at 1.524 35.306)
		(size 0.508)
		(drill 0.254)
		(layers "F.Cu" "B.Cu")
		(net "VDD_7401_PGOOD")
	)
	(via
		(at 36.2458 26.5176)
		(size 0.4572)
		(drill 0.20574)
		(layers "F.Cu" "B.Cu")
		(net "VDD_7401_PGOOD")
	)
	(via
		(at 11.176 38.481)
		(size 0.508)
		(drill 0.254)
		(layers "F.Cu" "B.Cu")
		(net "VDD_7401_PGOOD")
	)
	(segment
		(start 11.938 30.607)
		(end 26.162 30.607)
		(width 0.12065)
		(layer "In3.Cu")
		(net "VDD_7401_PGOOD")
	)
	(segment
		(start 1.524 35.306)
		(end 2.032 34.798)
		(width 0.12065)
		(layer "In3.Cu")
		(net "VDD_7401_PGOOD")
	)
	(segment
		(start 10.033 37.338)
		(end 11.176 38.481)
		(width 0.12065)
		(layer "In3.Cu")
		(net "VDD_7401_PGOOD")
	)
	(segment
		(start 26.162 30.607)
		(end 26.416 30.353)
		(width 0.12065)
		(layer "In3.Cu")
		(net "VDD_7401_PGOOD")
	)
	(segment
		(start 8.001 37.338)
		(end 10.033 37.338)
		(width 0.12065)
		(layer "In3.Cu")
		(net "VDD_7401_PGOOD")
	)
	(segment
		(start 5.461 34.798)
		(end 8.001 37.338)
		(width 0.12065)
		(layer "In3.Cu")
		(net "VDD_7401_PGOOD")
	)
	(segment
		(start 26.416 30.353)
		(end 27.051 30.353)
		(width 0.12065)
		(layer "In3.Cu")
		(net "VDD_7401_PGOOD")
	)
	(segment
		(start 2.032 34.798)
		(end 5.461 34.798)
		(width 0.12065)
		(layer "In3.Cu")
		(net "VDD_7401_PGOOD")
	)
	(segment
		(start 31.556604 25.719659)
		(end 31.505804 25.668859)
		(width 0.12065)
		(layer "In6.Cu")
		(net "VDD_7401_PGOOD")
	)
	(segment
		(start 30.922341 26.248004)
		(end 30.663286 26.507059)
		(width 0.12065)
		(layer "In6.Cu")
		(net "VDD_7401_PGOOD")
	)
	(segment
		(start 30.922341 25.923596)
		(end 30.922341 26.248004)
		(width 0.12065)
		(layer "In6.Cu")
		(net "VDD_7401_PGOOD")
	)
	(segment
		(start 31.177078 25.668859)
		(end 30.922341 25.923596)
		(width 0.12065)
		(layer "In6.Cu")
		(net "VDD_7401_PGOOD")
	)
	(segment
		(start 35.270796 26.070941)
		(end 34.919514 25.719659)
		(width 0.12065)
		(layer "In6.Cu")
		(net "VDD_7401_PGOOD")
	)
	(segment
		(start 36.2458 26.5176)
		(end 36.0426 26.5176)
		(width 0.12065)
		(layer "In6.Cu")
		(net "VDD_7401_PGOOD")
	)
	(segment
		(start 34.919514 25.719659)
		(end 31.556604 25.719659)
		(width 0.12065)
		(layer "In6.Cu")
		(net "VDD_7401_PGOOD")
	)
	(segment
		(start 31.505804 25.668859)
		(end 31.177078 25.668859)
		(width 0.12065)
		(layer "In6.Cu")
		(net "VDD_7401_PGOOD")
	)
	(segment
		(start 36.0426 26.5176)
		(end 35.595941 26.070941)
		(width 0.12065)
		(layer "In6.Cu")
		(net "VDD_7401_PGOOD")
	)
	(segment
		(start 30.134941 26.507059)
		(end 27.051 29.591)
		(width 0.12065)
		(layer "In6.Cu")
		(net "VDD_7401_PGOOD")
	)
	(segment
		(start 35.595941 26.070941)
		(end 35.270796 26.070941)
		(width 0.12065)
		(layer "In6.Cu")
		(net "VDD_7401_PGOOD")
	)
	(segment
		(start 30.663286 26.507059)
		(end 30.134941 26.507059)
		(width 0.12065)
		(layer "In6.Cu")
		(net "VDD_7401_PGOOD")
	)
	(segment
		(start 27.051 29.591)
		(end 27.051 30.353)
		(width 0.12065)
		(layer "In6.Cu")
		(net "VDD_7401_PGOOD")
	)
	(segment
		(start 11.938 37.719)
		(end 11.176 38.481)
		(width 0.12065)
		(layer "In7.Cu")
		(net "VDD_7401_PGOOD")
	)
	(segment
		(start 11.938 30.607)
		(end 11.938 37.719)
		(width 0.12065)
		(layer "In7.Cu")
		(net "VDD_7401_PGOOD")
	)
	(segment
		(start 45.8851 53.1368)
		(end 45.8851 54.6989)
		(width 0.14732)
		(layer "F.Cu")
		(net "0.7V_REF")
	)
	(segment
		(start 46.85538 49.34712)
		(end 46.482 49.7205)
		(width 0.14732)
		(layer "F.Cu")
		(net "0.7V_REF")
	)
	(segment
		(start 46.101 50.292)
		(end 45.466 49.657)
		(width 0.14732)
		(layer "F.Cu")
		(net "0.7V_REF")
	)
	(segment
		(start 45.466 49.022)
		(end 45.14088 48.69688)
		(width 0.14732)
		(layer "F.Cu")
		(net "0.7V_REF")
	)
	(segment
		(start 45.14088 48.69688)
		(end 43.688 48.69688)
		(width 0.14732)
		(layer "F.Cu")
		(net "0.7V_REF")
	)
	(segment
		(start 45.466 49.657)
		(end 45.466 49.022)
		(width 0.14732)
		(layer "F.Cu")
		(net "0.7V_REF")
	)
	(segment
		(start 45.8851 54.6989)
		(end 45.847 54.737)
		(width 0.14732)
		(layer "F.Cu")
		(net "0.7V_REF")
	)
	(segment
		(start 46.482 49.7205)
		(end 46.482 50.292)
		(width 0.14732)
		(layer "F.Cu")
		(net "0.7V_REF")
	)
	(segment
		(start 46.482 50.292)
		(end 46.101 50.292)
		(width 0.14732)
		(layer "F.Cu")
		(net "0.7V_REF")
	)
	(segment
		(start 48.006 49.34712)
		(end 46.85538 49.34712)
		(width 0.14732)
		(layer "F.Cu")
		(net "0.7V_REF")
	)
	(via
		(at 45.847 54.737)
		(size 0.508)
		(drill 0.25654)
		(layers "F.Cu" "B.Cu")
		(net "0.7V_REF")
	)
	(via
		(at 46.482 50.292)
		(size 0.508)
		(drill 0.254)
		(layers "F.Cu" "B.Cu")
		(net "0.7V_REF")
	)
	(segment
		(start 45.847 54.737)
		(end 45.847 50.927)
		(width 0.12065)
		(layer "In7.Cu")
		(net "0.7V_REF")
	)
	(segment
		(start 45.847 50.927)
		(end 46.482 50.292)
		(width 0.12065)
		(layer "In7.Cu")
		(net "0.7V_REF")
	)
	(segment
		(start 27.449882 24.7523)
		(end 26.5303 24.7523)
		(width 0.127)
		(layer "F.Cu")
		(net "VDD_7401_EN")
	)
	(segment
		(start 12.3063 36.4109)
		(end 12.99464 36.4109)
		(width 0.2032)
		(layer "F.Cu")
		(net "VDD_7401_EN")
	)
	(segment
		(start 0.4191 34.5821)
		(end 0 34.163)
		(width 0.14732)
		(layer "F.Cu")
		(net "VDD_7401_EN")
	)
	(segment
		(start 0 34.163)
		(end 0 32.385)
		(width 0.14732)
		(layer "F.Cu")
		(net "VDD_7401_EN")
	)
	(segment
		(start 12.99464 36.4109)
		(end 13.1064 36.52266)
		(width 0.2032)
		(layer "F.Cu")
		(net "VDD_7401_EN")
	)
	(segment
		(start 0.635 34.5821)
		(end 0.635 35.306)
		(width 0.14732)
		(layer "F.Cu")
		(net "VDD_7401_EN")
	)
	(segment
		(start 0.635 34.5821)
		(end 0.4191 34.5821)
		(width 0.14732)
		(layer "F.Cu")
		(net "VDD_7401_EN")
	)
	(segment
		(start 26.5303 24.7523)
		(end 26.1112 25.1714)
		(width 0.127)
		(layer "F.Cu")
		(net "VDD_7401_EN")
	)
	(segment
		(start 0 32.385)
		(end -1.016 31.369)
		(width 0.14732)
		(layer "F.Cu")
		(net "VDD_7401_EN")
	)
	(segment
		(start 28.245994 25.548412)
		(end 27.449882 24.7523)
		(width 0.127)
		(layer "F.Cu")
		(net "VDD_7401_EN")
	)
	(via
		(at 0.635 35.306)
		(size 0.508)
		(drill 0.254)
		(layers "F.Cu" "B.Cu")
		(net "VDD_7401_EN")
	)
	(via
		(at 26.1112 25.1714)
		(size 0.4572)
		(drill 0.20574)
		(layers "F.Cu" "B.Cu")
		(net "VDD_7401_EN")
	)
	(via
		(at 13.1064 36.52266)
		(size 0.508)
		(drill 0.254)
		(layers "F.Cu" "B.Cu")
		(net "VDD_7401_EN")
	)
	(segment
		(start 10.74166 36.52266)
		(end 10.541 36.322)
		(width 0.12065)
		(layer "In3.Cu")
		(net "VDD_7401_EN")
	)
	(segment
		(start 7.747 30.607)
		(end 9.652 28.702)
		(width 0.12065)
		(layer "In3.Cu")
		(net "VDD_7401_EN")
	)
	(segment
		(start 13.1064 36.52266)
		(end 10.74166 36.52266)
		(width 0.12065)
		(layer "In3.Cu")
		(net "VDD_7401_EN")
	)
	(segment
		(start 17.653 27.813)
		(end 18.034 27.432)
		(width 0.12065)
		(layer "In3.Cu")
		(net "VDD_7401_EN")
	)
	(segment
		(start 11.826875 26.685875)
		(end 12.192 27.051)
		(width 0.12065)
		(layer "In3.Cu")
		(net "VDD_7401_EN")
	)
	(segment
		(start 12.573 27.813)
		(end 17.653 27.813)
		(width 0.12065)
		(layer "In3.Cu")
		(net "VDD_7401_EN")
	)
	(segment
		(start 20.447 26.924)
		(end 22.987 26.924)
		(width 0.12065)
		(layer "In3.Cu")
		(net "VDD_7401_EN")
	)
	(segment
		(start 9.652 27.051)
		(end 10.017125 26.685875)
		(width 0.12065)
		(layer "In3.Cu")
		(net "VDD_7401_EN")
	)
	(segment
		(start 12.192 27.051)
		(end 12.192 27.432)
		(width 0.12065)
		(layer "In3.Cu")
		(net "VDD_7401_EN")
	)
	(segment
		(start 25.7556 25.527)
		(end 26.1112 25.1714)
		(width 0.12065)
		(layer "In3.Cu")
		(net "VDD_7401_EN")
	)
	(segment
		(start 10.017125 26.685875)
		(end 11.826875 26.685875)
		(width 0.12065)
		(layer "In3.Cu")
		(net "VDD_7401_EN")
	)
	(segment
		(start 24.384 25.527)
		(end 25.7556 25.527)
		(width 0.12065)
		(layer "In3.Cu")
		(net "VDD_7401_EN")
	)
	(segment
		(start 8.001 36.322)
		(end 7.747 36.068)
		(width 0.12065)
		(layer "In3.Cu")
		(net "VDD_7401_EN")
	)
	(segment
		(start 18.034 27.432)
		(end 19.939 27.432)
		(width 0.12065)
		(layer "In3.Cu")
		(net "VDD_7401_EN")
	)
	(segment
		(start 10.541 36.322)
		(end 8.001 36.322)
		(width 0.12065)
		(layer "In3.Cu")
		(net "VDD_7401_EN")
	)
	(segment
		(start 9.652 28.702)
		(end 9.652 27.051)
		(width 0.12065)
		(layer "In3.Cu")
		(net "VDD_7401_EN")
	)
	(segment
		(start 12.192 27.432)
		(end 12.573 27.813)
		(width 0.12065)
		(layer "In3.Cu")
		(net "VDD_7401_EN")
	)
	(segment
		(start 19.939 27.432)
		(end 20.447 26.924)
		(width 0.12065)
		(layer "In3.Cu")
		(net "VDD_7401_EN")
	)
	(segment
		(start 7.747 36.068)
		(end 7.747 30.607)
		(width 0.12065)
		(layer "In3.Cu")
		(net "VDD_7401_EN")
	)
	(segment
		(start 22.987 26.924)
		(end 24.384 25.527)
		(width 0.12065)
		(layer "In3.Cu")
		(net "VDD_7401_EN")
	)
	(segment
		(start 12.03706 37.592)
		(end 5.588 37.592)
		(width 0.12065)
		(layer "In6.Cu")
		(net "VDD_7401_EN")
	)
	(segment
		(start 5.08 37.084)
		(end 2.413 37.084)
		(width 0.12065)
		(layer "In6.Cu")
		(net "VDD_7401_EN")
	)
	(segment
		(start 5.588 37.592)
		(end 5.08 37.084)
		(width 0.12065)
		(layer "In6.Cu")
		(net "VDD_7401_EN")
	)
	(segment
		(start 13.1064 36.52266)
		(end 12.03706 37.592)
		(width 0.12065)
		(layer "In6.Cu")
		(net "VDD_7401_EN")
	)
	(segment
		(start 2.413 37.084)
		(end 0.635 35.306)
		(width 0.12065)
		(layer "In6.Cu")
		(net "VDD_7401_EN")
	)
	(segment
		(start -0.889 37.465)
		(end -0.381 37.465)
		(width 0.14732)
		(layer "F.Cu")
		(net "PWR_GOOD_LED_L")
	)
	(segment
		(start 26.1112 26.035)
		(end 26.5303 26.4541)
		(width 0.127)
		(layer "F.Cu")
		(net "PWR_GOOD_LED_L")
	)
	(segment
		(start 26.5303 26.4541)
		(end 27.840305 26.4541)
		(width 0.127)
		(layer "F.Cu")
		(net "PWR_GOOD_LED_L")
	)
	(segment
		(start -0.381 37.465)
		(end 0.254 36.83)
		(width 0.14732)
		(layer "F.Cu")
		(net "PWR_GOOD_LED_L")
	)
	(segment
		(start 27.840305 26.4541)
		(end 28.245994 26.048411)
		(width 0.127)
		(layer "F.Cu")
		(net "PWR_GOOD_LED_L")
	)
	(via
		(at 7.493 48.8315)
		(size 0.508)
		(drill 0.254)
		(layers "F.Cu" "B.Cu")
		(net "PWR_GOOD_LED_L")
	)
	(via
		(at 12.7 48.9585)
		(size 0.508)
		(drill 0.25654)
		(layers "F.Cu" "B.Cu")
		(net "PWR_GOOD_LED_L")
	)
	(via
		(at -0.889 37.465)
		(size 0.508)
		(drill 0.254)
		(layers "F.Cu" "B.Cu")
		(net "PWR_GOOD_LED_L")
	)
	(via
		(at 26.1112 26.035)
		(size 0.4572)
		(drill 0.20574)
		(layers "F.Cu" "B.Cu")
		(net "PWR_GOOD_LED_L")
	)
	(via
		(at 6.096 1.397)
		(size 0.508)
		(drill 0.254)
		(layers "F.Cu" "B.Cu")
		(net "PWR_GOOD_LED_L")
	)
	(via
		(at 0 29.845)
		(size 0.508)
		(drill 0.2667)
		(layers "F.Cu" "B.Cu")
		(net "PWR_GOOD_LED_L")
	)
	(segment
		(start 6.096 2.286)
		(end 4.6609 3.7211)
		(width 0.14732)
		(layer "B.Cu")
		(net "PWR_GOOD_LED_L")
	)
	(segment
		(start 4.6609 3.7211)
		(end 4.6609 3.81)
		(width 0.14732)
		(layer "B.Cu")
		(net "PWR_GOOD_LED_L")
	)
	(segment
		(start 6.096 1.397)
		(end 6.096 2.286)
		(width 0.14732)
		(layer "B.Cu")
		(net "PWR_GOOD_LED_L")
	)
	(segment
		(start 7.8105 48.514)
		(end 7.493 48.8315)
		(width 0.12065)
		(layer "In2.Cu")
		(net "PWR_GOOD_LED_L")
	)
	(segment
		(start 12.7 48.9585)
		(end 12.2555 48.514)
		(width 0.12065)
		(layer "In2.Cu")
		(net "PWR_GOOD_LED_L")
	)
	(segment
		(start 12.2555 48.514)
		(end 7.8105 48.514)
		(width 0.12065)
		(layer "In2.Cu")
		(net "PWR_GOOD_LED_L")
	)
	(segment
		(start 7.112 38.1)
		(end 7.62 38.608)
		(width 0.12065)
		(layer "In3.Cu")
		(net "PWR_GOOD_LED_L")
	)
	(segment
		(start 9.144 38.989)
		(end 9.144 38.608)
		(width 0.12065)
		(layer "In3.Cu")
		(net "PWR_GOOD_LED_L")
	)
	(segment
		(start 3.506521 30.413325)
		(end 4.119829 30.413325)
		(width 0.12065)
		(layer "In3.Cu")
		(net "PWR_GOOD_LED_L")
	)
	(segment
		(start 19.359829 26.476325)
		(end 19.607479 26.228675)
		(width 0.12065)
		(layer "In3.Cu")
		(net "PWR_GOOD_LED_L")
	)
	(segment
		(start 18.994171 26.476325)
		(end 19.359829 26.476325)
		(width 0.12065)
		(layer "In3.Cu")
		(net "PWR_GOOD_LED_L")
	)
	(segment
		(start 7.976921 26.438225)
		(end 11.788775 26.438225)
		(width 0.12065)
		(layer "In3.Cu")
		(net "PWR_GOOD_LED_L")
	)
	(segment
		(start 12.411075 25.814071)
		(end 12.698146 25.527)
		(width 0.12065)
		(layer "In3.Cu")
		(net "PWR_GOOD_LED_L")
	)
	(segment
		(start 8.001 37.846)
		(end 5.969 35.814)
		(width 0.12065)
		(layer "In3.Cu")
		(net "PWR_GOOD_LED_L")
	)
	(segment
		(start 5.969 35.814)
		(end 1.39065 35.814)
		(width 0.12065)
		(layer "In3.Cu")
		(net "PWR_GOOD_LED_L")
	)
	(segment
		(start 12.698146 25.527)
		(end 17.272 25.527)
		(width 0.12065)
		(layer "In3.Cu")
		(net "PWR_GOOD_LED_L")
	)
	(segment
		(start 1.39065 35.814)
		(end 1.27 35.69335)
		(width 0.12065)
		(layer "In3.Cu")
		(net "PWR_GOOD_LED_L")
	)
	(segment
		(start 1.076325 35.488829)
		(end 1.076325 32.959675)
		(width 0.12065)
		(layer "In3.Cu")
		(net "PWR_GOOD_LED_L")
	)
	(segment
		(start 7.493 48.8315)
		(end 6.35 47.6885)
		(width 0.12065)
		(layer "In3.Cu")
		(net "PWR_GOOD_LED_L")
	)
	(segment
		(start 1.076325 32.959675)
		(end 1.082675 32.953325)
		(width 0.12065)
		(layer "In3.Cu")
		(net "PWR_GOOD_LED_L")
	)
	(segment
		(start 8.128 39.243)
		(end 8.89 39.243)
		(width 0.12065)
		(layer "In3.Cu")
		(net "PWR_GOOD_LED_L")
	)
	(segment
		(start 26.532459 25.613741)
		(end 26.1112 26.035)
		(width 0.12065)
		(layer "In3.Cu")
		(net "PWR_GOOD_LED_L")
	)
	(segment
		(start 12.411075 25.815925)
		(end 12.411075 25.814071)
		(width 0.12065)
		(layer "In3.Cu")
		(net "PWR_GOOD_LED_L")
	)
	(segment
		(start 4.119829 30.413325)
		(end 7.331075 27.202079)
		(width 0.12065)
		(layer "In3.Cu")
		(net "PWR_GOOD_LED_L")
	)
	(segment
		(start 17.973675 26.228675)
		(end 18.746521 26.228675)
		(width 0.12065)
		(layer "In3.Cu")
		(net "PWR_GOOD_LED_L")
	)
	(segment
		(start 1.082675 32.837171)
		(end 3.506521 30.413325)
		(width 0.12065)
		(layer "In3.Cu")
		(net "PWR_GOOD_LED_L")
	)
	(segment
		(start 23.174325 26.228675)
		(end 24.638 24.765)
		(width 0.12065)
		(layer "In3.Cu")
		(net "PWR_GOOD_LED_L")
	)
	(segment
		(start 17.272 25.527)
		(end 17.973675 26.228675)
		(width 0.12065)
		(layer "In3.Cu")
		(net "PWR_GOOD_LED_L")
	)
	(segment
		(start 7.62 38.735)
		(end 8.128 39.243)
		(width 0.12065)
		(layer "In3.Cu")
		(net "PWR_GOOD_LED_L")
	)
	(segment
		(start 8.382 37.846)
		(end 8.001 37.846)
		(width 0.12065)
		(layer "In3.Cu")
		(net "PWR_GOOD_LED_L")
	)
	(segment
		(start 8.89 39.243)
		(end 9.144 38.989)
		(width 0.12065)
		(layer "In3.Cu")
		(net "PWR_GOOD_LED_L")
	)
	(segment
		(start 1.27 35.69335)
		(end 1.27 35.682504)
		(width 0.12065)
		(layer "In3.Cu")
		(net "PWR_GOOD_LED_L")
	)
	(segment
		(start 19.607479 26.228675)
		(end 23.174325 26.228675)
		(width 0.12065)
		(layer "In3.Cu")
		(net "PWR_GOOD_LED_L")
	)
	(segment
		(start 11.788775 26.438225)
		(end 12.411075 25.815925)
		(width 0.12065)
		(layer "In3.Cu")
		(net "PWR_GOOD_LED_L")
	)
	(segment
		(start 6.35 47.6885)
		(end 6.35 38.481)
		(width 0.12065)
		(layer "In3.Cu")
		(net "PWR_GOOD_LED_L")
	)
	(segment
		(start 1.27 35.682504)
		(end 1.076325 35.488829)
		(width 0.12065)
		(layer "In3.Cu")
		(net "PWR_GOOD_LED_L")
	)
	(segment
		(start 26.289 24.765)
		(end 26.532459 25.008459)
		(width 0.12065)
		(layer "In3.Cu")
		(net "PWR_GOOD_LED_L")
	)
	(segment
		(start 24.638 24.765)
		(end 26.289 24.765)
		(width 0.12065)
		(layer "In3.Cu")
		(net "PWR_GOOD_LED_L")
	)
	(segment
		(start 18.746521 26.228675)
		(end 18.994171 26.476325)
		(width 0.12065)
		(layer "In3.Cu")
		(net "PWR_GOOD_LED_L")
	)
	(segment
		(start 7.331075 27.202079)
		(end 7.331075 27.084071)
		(width 0.12065)
		(layer "In3.Cu")
		(net "PWR_GOOD_LED_L")
	)
	(segment
		(start 6.35 38.481)
		(end 6.731 38.1)
		(width 0.12065)
		(layer "In3.Cu")
		(net "PWR_GOOD_LED_L")
	)
	(segment
		(start 9.144 38.608)
		(end 8.382 37.846)
		(width 0.12065)
		(layer "In3.Cu")
		(net "PWR_GOOD_LED_L")
	)
	(segment
		(start 26.532459 25.008459)
		(end 26.532459 25.613741)
		(width 0.12065)
		(layer "In3.Cu")
		(net "PWR_GOOD_LED_L")
	)
	(segment
		(start 7.331075 27.084071)
		(end 7.976921 26.438225)
		(width 0.12065)
		(layer "In3.Cu")
		(net "PWR_GOOD_LED_L")
	)
	(segment
		(start 1.082675 32.953325)
		(end 1.082675 32.837171)
		(width 0.12065)
		(layer "In3.Cu")
		(net "PWR_GOOD_LED_L")
	)
	(segment
		(start 6.731 38.1)
		(end 7.112 38.1)
		(width 0.12065)
		(layer "In3.Cu")
		(net "PWR_GOOD_LED_L")
	)
	(segment
		(start 7.62 38.608)
		(end 7.62 38.735)
		(width 0.12065)
		(layer "In3.Cu")
		(net "PWR_GOOD_LED_L")
	)
	(segment
		(start 0.508 10.287)
		(end 3.429 10.287)
		(width 0.12065)
		(layer "In6.Cu")
		(net "PWR_GOOD_LED_L")
	)
	(segment
		(start -0.508 11.303)
		(end 0.508 10.287)
		(width 0.12065)
		(layer "In6.Cu")
		(net "PWR_GOOD_LED_L")
	)
	(segment
		(start 8.382 47.752)
		(end 11.43 47.752)
		(width 0.12065)
		(layer "In6.Cu")
		(net "PWR_GOOD_LED_L")
	)
	(segment
		(start 0 29.845)
		(end -0.508 29.337)
		(width 0.12065)
		(layer "In6.Cu")
		(net "PWR_GOOD_LED_L")
	)
	(segment
		(start -0.889 37.465)
		(end -0.889 36.576)
		(width 0.12065)
		(layer "In6.Cu")
		(net "PWR_GOOD_LED_L")
	)
	(segment
		(start 12.6365 48.9585)
		(end 12.7 48.9585)
		(width 0.12065)
		(layer "In6.Cu")
		(net "PWR_GOOD_LED_L")
	)
	(segment
		(start -0.508 36.195)
		(end -0.508 30.353)
		(width 0.12065)
		(layer "In6.Cu")
		(net "PWR_GOOD_LED_L")
	)
	(segment
		(start 6.096 7.62)
		(end 6.096 1.397)
		(width 0.12065)
		(layer "In6.Cu")
		(net "PWR_GOOD_LED_L")
	)
	(segment
		(start 6.477 45.847)
		(end 8.382 47.752)
		(width 0.12065)
		(layer "In6.Cu")
		(net "PWR_GOOD_LED_L")
	)
	(segment
		(start 4.953 37.465)
		(end 6.477 38.989)
		(width 0.12065)
		(layer "In6.Cu")
		(net "PWR_GOOD_LED_L")
	)
	(segment
		(start -0.508 30.353)
		(end 0 29.845)
		(width 0.12065)
		(layer "In6.Cu")
		(net "PWR_GOOD_LED_L")
	)
	(segment
		(start -0.889 36.576)
		(end -0.508 36.195)
		(width 0.12065)
		(layer "In6.Cu")
		(net "PWR_GOOD_LED_L")
	)
	(segment
		(start 11.43 47.752)
		(end 12.6365 48.9585)
		(width 0.12065)
		(layer "In6.Cu")
		(net "PWR_GOOD_LED_L")
	)
	(segment
		(start -0.889 37.465)
		(end 4.953 37.465)
		(width 0.12065)
		(layer "In6.Cu")
		(net "PWR_GOOD_LED_L")
	)
	(segment
		(start 6.477 38.989)
		(end 6.477 45.847)
		(width 0.12065)
		(layer "In6.Cu")
		(net "PWR_GOOD_LED_L")
	)
	(segment
		(start -0.508 29.337)
		(end -0.508 11.303)
		(width 0.12065)
		(layer "In6.Cu")
		(net "PWR_GOOD_LED_L")
	)
	(segment
		(start 3.429 10.287)
		(end 6.096 7.62)
		(width 0.12065)
		(layer "In6.Cu")
		(net "PWR_GOOD_LED_L")
	)
	(via
		(at 6.096 0.254)
		(size 0.508)
		(drill 0.25654)
		(layers "F.Cu" "B.Cu")
		(net "CPLD_NFP_RST_LED_L")
	)
	(via
		(at 26.924 26.035)
		(size 0.4572)
		(drill 0.20574)
		(layers "F.Cu" "B.Cu")
		(net "CPLD_NFP_RST_LED_L")
	)
	(via
		(at 3.556 4.064)
		(size 0.762)
		(drill 0.381)
		(layers "F.Cu" "B.Cu")
		(net "CPLD_NFP_RST_LED_L")
	)
	(segment
		(start 4.191 3.398926)
		(end 4.191 3.429)
		(width 0.14732)
		(layer "B.Cu")
		(net "CPLD_NFP_RST_LED_L")
	)
	(segment
		(start 6.096 0.381)
		(end 5.588 0.889)
		(width 0.14732)
		(layer "B.Cu")
		(net "CPLD_NFP_RST_LED_L")
	)
	(segment
		(start 5.588 0.889)
		(end 5.588 2.001926)
		(width 0.14732)
		(layer "B.Cu")
		(net "CPLD_NFP_RST_LED_L")
	)
	(segment
		(start 6.096 0.254)
		(end 6.096 0.381)
		(width 0.14732)
		(layer "B.Cu")
		(net "CPLD_NFP_RST_LED_L")
	)
	(segment
		(start 5.588 2.001926)
		(end 4.191 3.398926)
		(width 0.14732)
		(layer "B.Cu")
		(net "CPLD_NFP_RST_LED_L")
	)
	(segment
		(start 4.191 3.429)
		(end 3.556 4.064)
		(width 0.14732)
		(layer "B.Cu")
		(net "CPLD_NFP_RST_LED_L")
	)
	(segment
		(start 4.5339 4.572)
		(end 4.6609 4.699)
		(width 0.14732)
		(layer "B.Cu")
		(net "CPLD_NFP_RST_LED_L")
	)
	(segment
		(start 3.556 4.064)
		(end 4.064 4.572)
		(width 0.14732)
		(layer "B.Cu")
		(net "CPLD_NFP_RST_LED_L")
	)
	(segment
		(start 4.064 4.572)
		(end 4.5339 4.572)
		(width 0.14732)
		(layer "B.Cu")
		(net "CPLD_NFP_RST_LED_L")
	)
	(segment
		(start 26.988211 26.048411)
		(end 28.745993 26.048411)
		(width 0.127)
		(layer "In1.Cu")
		(net "CPLD_NFP_RST_LED_L")
	)
	(segment
		(start 26.924 26.035)
		(end 26.988211 26.048411)
		(width 0.127)
		(layer "In1.Cu")
		(net "CPLD_NFP_RST_LED_L")
	)
	(segment
		(start 6.604 0.762)
		(end 6.604 8.509)
		(width 0.12065)
		(layer "In7.Cu")
		(net "CPLD_NFP_RST_LED_L")
	)
	(segment
		(start 8.213725 22.004071)
		(end 8.213725 22.056725)
		(width 0.12065)
		(layer "In7.Cu")
		(net "CPLD_NFP_RST_LED_L")
	)
	(segment
		(start 6.096 0.254)
		(end 6.604 0.762)
		(width 0.12065)
		(layer "In7.Cu")
		(net "CPLD_NFP_RST_LED_L")
	)
	(segment
		(start 23.368 22.606)
		(end 25.273 22.606)
		(width 0.12065)
		(layer "In7.Cu")
		(net "CPLD_NFP_RST_LED_L")
	)
	(segment
		(start 15.973425 23.17148)
		(end 16.411905 22.733)
		(width 0.12065)
		(layer "In7.Cu")
		(net "CPLD_NFP_RST_LED_L")
	)
	(segment
		(start 19.999325 24.455171)
		(end 19.999325 24.511)
		(width 0.12065)
		(layer "In7.Cu")
		(net "CPLD_NFP_RST_LED_L")
	)
	(segment
		(start 19.116675 24.455171)
		(end 19.375171 24.196675)
		(width 0.12065)
		(layer "In7.Cu")
		(net "CPLD_NFP_RST_LED_L")
	)
	(segment
		(start 21.463 24.511)
		(end 23.368 22.606)
		(width 0.12065)
		(layer "In7.Cu")
		(net "CPLD_NFP_RST_LED_L")
	)
	(segment
		(start 27.335734 25.623266)
		(end 26.924 26.035)
		(width 0.12065)
		(layer "In7.Cu")
		(net "CPLD_NFP_RST_LED_L")
	)
	(segment
		(start 6.604 8.509)
		(end 6.096 9.017)
		(width 0.12065)
		(layer "In7.Cu")
		(net "CPLD_NFP_RST_LED_L")
	)
	(segment
		(start 14.605 26.289)
		(end 14.605 24.868454)
		(width 0.12065)
		(layer "In7.Cu")
		(net "CPLD_NFP_RST_LED_L")
	)
	(segment
		(start 9.570085 22.86)
		(end 9.570085 23.764545)
		(width 0.12065)
		(layer "In7.Cu")
		(net "CPLD_NFP_RST_LED_L")
	)
	(segment
		(start 9.33831 22.628225)
		(end 9.570085 22.86)
		(width 0.12065)
		(layer "In7.Cu")
		(net "CPLD_NFP_RST_LED_L")
	)
	(segment
		(start 16.411905 22.733)
		(end 17.028846 22.733)
		(width 0.12065)
		(layer "In7.Cu")
		(net "CPLD_NFP_RST_LED_L")
	)
	(segment
		(start 6.096 9.017)
		(end 6.096 19.886346)
		(width 0.12065)
		(layer "In7.Cu")
		(net "CPLD_NFP_RST_LED_L")
	)
	(segment
		(start 14.842896 24.003)
		(end 15.621 24.003)
		(width 0.12065)
		(layer "In7.Cu")
		(net "CPLD_NFP_RST_LED_L")
	)
	(segment
		(start 9.570085 23.764545)
		(end 9.871075 24.065535)
		(width 0.12065)
		(layer "In7.Cu")
		(net "CPLD_NFP_RST_LED_L")
	)
	(segment
		(start 17.399 23.876)
		(end 18.034 24.511)
		(width 0.12065)
		(layer "In7.Cu")
		(net "CPLD_NFP_RST_LED_L")
	)
	(segment
		(start 17.028846 22.733)
		(end 17.399 23.103154)
		(width 0.12065)
		(layer "In7.Cu")
		(net "CPLD_NFP_RST_LED_L")
	)
	(segment
		(start 27.335734 23.297871)
		(end 27.335734 25.623266)
		(width 0.12065)
		(layer "In7.Cu")
		(net "CPLD_NFP_RST_LED_L")
	)
	(segment
		(start 18.034 24.511)
		(end 19.116675 24.511)
		(width 0.12065)
		(layer "In7.Cu")
		(net "CPLD_NFP_RST_LED_L")
	)
	(segment
		(start 10.16 26.543)
		(end 14.351 26.543)
		(width 0.12065)
		(layer "In7.Cu")
		(net "CPLD_NFP_RST_LED_L")
	)
	(segment
		(start 19.375171 24.196675)
		(end 19.740829 24.196675)
		(width 0.12065)
		(layer "In7.Cu")
		(net "CPLD_NFP_RST_LED_L")
	)
	(segment
		(start 14.351 26.543)
		(end 14.605 26.289)
		(width 0.12065)
		(layer "In7.Cu")
		(net "CPLD_NFP_RST_LED_L")
	)
	(segment
		(start 9.871075 24.065535)
		(end 9.871075 26.254075)
		(width 0.12065)
		(layer "In7.Cu")
		(net "CPLD_NFP_RST_LED_L")
	)
	(segment
		(start 9.871075 26.254075)
		(end 10.16 26.543)
		(width 0.12065)
		(layer "In7.Cu")
		(net "CPLD_NFP_RST_LED_L")
	)
	(segment
		(start 14.61135 24.234546)
		(end 14.842896 24.003)
		(width 0.12065)
		(layer "In7.Cu")
		(net "CPLD_NFP_RST_LED_L")
	)
	(segment
		(start 27.086204 23.048341)
		(end 27.335734 23.297871)
		(width 0.12065)
		(layer "In7.Cu")
		(net "CPLD_NFP_RST_LED_L")
	)
	(segment
		(start 15.973425 23.650575)
		(end 15.973425 23.17148)
		(width 0.12065)
		(layer "In7.Cu")
		(net "CPLD_NFP_RST_LED_L")
	)
	(segment
		(start 14.61135 24.862104)
		(end 14.61135 24.234546)
		(width 0.12065)
		(layer "In7.Cu")
		(net "CPLD_NFP_RST_LED_L")
	)
	(segment
		(start 8.785225 22.628225)
		(end 9.33831 22.628225)
		(width 0.12065)
		(layer "In7.Cu")
		(net "CPLD_NFP_RST_LED_L")
	)
	(segment
		(start 6.096 19.886346)
		(end 8.213725 22.004071)
		(width 0.12065)
		(layer "In7.Cu")
		(net "CPLD_NFP_RST_LED_L")
	)
	(segment
		(start 17.399 23.103154)
		(end 17.399 23.876)
		(width 0.12065)
		(layer "In7.Cu")
		(net "CPLD_NFP_RST_LED_L")
	)
	(segment
		(start 19.116675 24.511)
		(end 19.116675 24.455171)
		(width 0.12065)
		(layer "In7.Cu")
		(net "CPLD_NFP_RST_LED_L")
	)
	(segment
		(start 8.213725 22.056725)
		(end 8.785225 22.628225)
		(width 0.12065)
		(layer "In7.Cu")
		(net "CPLD_NFP_RST_LED_L")
	)
	(segment
		(start 15.621 24.003)
		(end 15.973425 23.650575)
		(width 0.12065)
		(layer "In7.Cu")
		(net "CPLD_NFP_RST_LED_L")
	)
	(segment
		(start 25.273 22.606)
		(end 25.715341 23.048341)
		(width 0.12065)
		(layer "In7.Cu")
		(net "CPLD_NFP_RST_LED_L")
	)
	(segment
		(start 14.605 24.868454)
		(end 14.61135 24.862104)
		(width 0.12065)
		(layer "In7.Cu")
		(net "CPLD_NFP_RST_LED_L")
	)
	(segment
		(start 25.715341 23.048341)
		(end 27.086204 23.048341)
		(width 0.12065)
		(layer "In7.Cu")
		(net "CPLD_NFP_RST_LED_L")
	)
	(segment
		(start 19.740829 24.196675)
		(end 19.999325 24.455171)
		(width 0.12065)
		(layer "In7.Cu")
		(net "CPLD_NFP_RST_LED_L")
	)
	(segment
		(start 19.999325 24.511)
		(end 21.463 24.511)
		(width 0.12065)
		(layer "In7.Cu")
		(net "CPLD_NFP_RST_LED_L")
	)
	(segment
		(start 44.236996 3.042006)
		(end 43.736997 2.542007)
		(width 0.099314)
		(layer "F.Cu")
		(net "NFP_SERDES1_TX3_P")
	)
	(via
		(at 43.736997 2.542007)
		(size 0.4826)
		(drill 0.20574)
		(layers "F.Cu" "B.Cu")
		(net "NFP_SERDES1_TX3_P")
	)
	(via
		(at 9.0424 14.5669)
		(size 0.508)
		(drill 0.254)
		(layers "F.Cu" "B.Cu")
		(net "NFP_SERDES1_TX3_P")
	)
	(segment
		(start 9.6774 15.2019)
		(end 9.0424 14.5669)
		(width 0.099314)
		(layer "B.Cu")
		(net "NFP_SERDES1_TX3_P")
	)
	(segment
		(start 43.250942 1.733017)
		(end 43.274056 1.709903)
		(width 0.095758)
		(layer "In7.Cu")
		(net "NFP_SERDES1_TX3_P")
	)
	(segment
		(start 20.84197 4.645889)
		(end 20.94865 4.752569)
		(width 0.096012)
		(layer "In7.Cu")
		(net "NFP_SERDES1_TX3_P")
	)
	(segment
		(start 43.343932 2.703932)
		(end 43.343932 2.290547)
		(width 0.095758)
		(layer "In7.Cu")
		(net "NFP_SERDES1_TX3_P")
	)
	(segment
		(start 16.374618 11.33221)
		(end 15.96771 11.739118)
		(width 0.096012)
		(layer "In7.Cu")
		(net "NFP_SERDES1_TX3_P")
	)
	(segment
		(start 12.05103 15.50797)
		(end 11.94435 15.61465)
		(width 0.096012)
		(layer "In7.Cu")
		(net "NFP_SERDES1_TX3_P")
	)
	(segment
		(start 43.274056 1.709903)
		(end 43.274056 1.683868)
		(width 0.095758)
		(layer "In7.Cu")
		(net "NFP_SERDES1_TX3_P")
	)
	(segment
		(start 20.11934 5.39275)
		(end 20.11934 6.309462)
		(width 0.096012)
		(layer "In7.Cu")
		(net "NFP_SERDES1_TX3_P")
	)
	(segment
		(start 20.11934 1.102487)
		(end 20.11934 2.450059)
		(width 0.096012)
		(layer "In7.Cu")
		(net "NFP_SERDES1_TX3_P")
	)
	(segment
		(start 21.410371 3.196844)
		(end 21.410295 3.19692)
		(width 0.096012)
		(layer "In7.Cu")
		(net "NFP_SERDES1_TX3_P")
	)
	(segment
		(start 20.378522 5.133569)
		(end 20.11934 5.39275)
		(width 0.096012)
		(layer "In7.Cu")
		(net "NFP_SERDES1_TX3_P")
	)
	(segment
		(start 11.94435 15.61465)
		(end 11.67003 15.61465)
		(width 0.096012)
		(layer "In7.Cu")
		(net "NFP_SERDES1_TX3_P")
	)
	(segment
		(start 20.94865 4.752569)
		(end 20.94865 5.026889)
		(width 0.096012)
		(layer "In7.Cu")
		(net "NFP_SERDES1_TX3_P")
	)
	(segment
		(start 20.94865 5.026889)
		(end 20.84197 5.133569)
		(width 0.096012)
		(layer "In7.Cu")
		(net "NFP_SERDES1_TX3_P")
	)
	(segment
		(start 9.547225 15.071725)
		(end 9.0424 14.5669)
		(width 0.096012)
		(layer "In7.Cu")
		(net "NFP_SERDES1_TX3_P")
	)
	(segment
		(start 11.56335 15.330907)
		(end 11.304168 15.071725)
		(width 0.096012)
		(layer "In7.Cu")
		(net "NFP_SERDES1_TX3_P")
	)
	(segment
		(start 12.9953 15.071725)
		(end 12.310212 15.071725)
		(width 0.096012)
		(layer "In7.Cu")
		(net "NFP_SERDES1_TX3_P")
	)
	(segment
		(start 20.378522 4.645889)
		(end 20.84197 4.645889)
		(width 0.096012)
		(layer "In7.Cu")
		(net "NFP_SERDES1_TX3_P")
	)
	(segment
		(start 11.304168 15.071725)
		(end 9.547225 15.071725)
		(width 0.096012)
		(layer "In7.Cu")
		(net "NFP_SERDES1_TX3_P")
	)
	(segment
		(start 17.399 10.007092)
		(end 17.399 10.680776)
		(width 0.096012)
		(layer "In7.Cu")
		(net "NFP_SERDES1_TX3_P")
	)
	(segment
		(start 19.37131 7.057492)
		(end 19.37131 8.034782)
		(width 0.096012)
		(layer "In7.Cu")
		(net "NFP_SERDES1_TX3_P")
	)
	(segment
		(start 11.67003 15.61465)
		(end 11.56335 15.50797)
		(width 0.096012)
		(layer "In7.Cu")
		(net "NFP_SERDES1_TX3_P")
	)
	(segment
		(start 20.11934 3.456102)
		(end 20.11934 4.386707)
		(width 0.096012)
		(layer "In7.Cu")
		(net "NFP_SERDES1_TX3_P")
	)
	(segment
		(start 16.747566 11.33221)
		(end 16.374618 11.33221)
		(width 0.096012)
		(layer "In7.Cu")
		(net "NFP_SERDES1_TX3_P")
	)
	(segment
		(start 20.378522 2.70924)
		(end 21.753576 2.70924)
		(width 0.096012)
		(layer "In7.Cu")
		(net "NFP_SERDES1_TX3_P")
	)
	(segment
		(start 21.753652 3.196844)
		(end 21.410371 3.196844)
		(width 0.096012)
		(layer "In7.Cu")
		(net "NFP_SERDES1_TX3_P")
	)
	(segment
		(start 20.84197 5.133569)
		(end 20.378522 5.133569)
		(width 0.096012)
		(layer "In7.Cu")
		(net "NFP_SERDES1_TX3_P")
	)
	(segment
		(start 43.274056 1.683868)
		(end 43.274056 0.856056)
		(width 0.096012)
		(layer "In7.Cu")
		(net "NFP_SERDES1_TX3_P")
	)
	(segment
		(start 15.96771 13.636092)
		(end 15.731592 13.87221)
		(width 0.096012)
		(layer "In7.Cu")
		(net "NFP_SERDES1_TX3_P")
	)
	(segment
		(start 42.672 0.254)
		(end 20.967827 0.254)
		(width 0.096012)
		(layer "In7.Cu")
		(net "NFP_SERDES1_TX3_P")
	)
	(segment
		(start 12.05103 15.330907)
		(end 12.05103 15.50797)
		(width 0.096012)
		(layer "In7.Cu")
		(net "NFP_SERDES1_TX3_P")
	)
	(segment
		(start 43.736997 2.542007)
		(end 43.736997 2.638323)
		(width 0.095758)
		(layer "In7.Cu")
		(net "NFP_SERDES1_TX3_P")
	)
	(segment
		(start 20.11934 6.309462)
		(end 19.37131 7.057492)
		(width 0.096012)
		(layer "In7.Cu")
		(net "NFP_SERDES1_TX3_P")
	)
	(segment
		(start 13.42771 14.279118)
		(end 13.42771 14.639239)
		(width 0.096012)
		(layer "In7.Cu")
		(net "NFP_SERDES1_TX3_P")
	)
	(segment
		(start 21.860256 3.09024)
		(end 21.753652 3.196844)
		(width 0.096012)
		(layer "In7.Cu")
		(net "NFP_SERDES1_TX3_P")
	)
	(segment
		(start 43.274056 0.856056)
		(end 42.672 0.254)
		(width 0.096012)
		(layer "In7.Cu")
		(net "NFP_SERDES1_TX3_P")
	)
	(segment
		(start 21.860256 2.81592)
		(end 21.860256 3.09024)
		(width 0.096012)
		(layer "In7.Cu")
		(net "NFP_SERDES1_TX3_P")
	)
	(segment
		(start 13.42771 14.639239)
		(end 12.9953 15.071725)
		(width 0.096012)
		(layer "In7.Cu")
		(net "NFP_SERDES1_TX3_P")
	)
	(segment
		(start 19.37131 8.034782)
		(end 17.399 10.007092)
		(width 0.096012)
		(layer "In7.Cu")
		(net "NFP_SERDES1_TX3_P")
	)
	(segment
		(start 17.399 10.680776)
		(end 16.747566 11.33221)
		(width 0.096012)
		(layer "In7.Cu")
		(net "NFP_SERDES1_TX3_P")
	)
	(segment
		(start 43.343932 2.290547)
		(end 43.250942 2.197557)
		(width 0.095758)
		(layer "In7.Cu")
		(net "NFP_SERDES1_TX3_P")
	)
	(segment
		(start 43.250942 2.197557)
		(end 43.250942 1.733017)
		(width 0.095758)
		(layer "In7.Cu")
		(net "NFP_SERDES1_TX3_P")
	)
	(segment
		(start 43.434025 2.794025)
		(end 43.343932 2.703932)
		(width 0.095758)
		(layer "In7.Cu")
		(net "NFP_SERDES1_TX3_P")
	)
	(segment
		(start 21.410295 3.19692)
		(end 20.378522 3.19692)
		(width 0.096012)
		(layer "In7.Cu")
		(net "NFP_SERDES1_TX3_P")
	)
	(segment
		(start 20.11934 2.450059)
		(end 20.378522 2.70924)
		(width 0.096012)
		(layer "In7.Cu")
		(net "NFP_SERDES1_TX3_P")
	)
	(segment
		(start 20.378522 3.19692)
		(end 20.11934 3.456102)
		(width 0.096012)
		(layer "In7.Cu")
		(net "NFP_SERDES1_TX3_P")
	)
	(segment
		(start 43.581295 2.794025)
		(end 43.434025 2.794025)
		(width 0.095758)
		(layer "In7.Cu")
		(net "NFP_SERDES1_TX3_P")
	)
	(segment
		(start 21.753576 2.70924)
		(end 21.860256 2.81592)
		(width 0.096012)
		(layer "In7.Cu")
		(net "NFP_SERDES1_TX3_P")
	)
	(segment
		(start 15.731592 13.87221)
		(end 13.834618 13.87221)
		(width 0.096012)
		(layer "In7.Cu")
		(net "NFP_SERDES1_TX3_P")
	)
	(segment
		(start 12.310212 15.071725)
		(end 12.05103 15.330907)
		(width 0.096012)
		(layer "In7.Cu")
		(net "NFP_SERDES1_TX3_P")
	)
	(segment
		(start 15.96771 11.739118)
		(end 15.96771 13.636092)
		(width 0.096012)
		(layer "In7.Cu")
		(net "NFP_SERDES1_TX3_P")
	)
	(segment
		(start 20.11934 4.386707)
		(end 20.378522 4.645889)
		(width 0.096012)
		(layer "In7.Cu")
		(net "NFP_SERDES1_TX3_P")
	)
	(segment
		(start 11.56335 15.50797)
		(end 11.56335 15.330907)
		(width 0.096012)
		(layer "In7.Cu")
		(net "NFP_SERDES1_TX3_P")
	)
	(segment
		(start 43.736997 2.638323)
		(end 43.581295 2.794025)
		(width 0.095758)
		(layer "In7.Cu")
		(net "NFP_SERDES1_TX3_P")
	)
	(segment
		(start 20.967827 0.254)
		(end 20.11934 1.102487)
		(width 0.096012)
		(layer "In7.Cu")
		(net "NFP_SERDES1_TX3_P")
	)
	(segment
		(start 13.834618 13.87221)
		(end 13.42771 14.279118)
		(width 0.096012)
		(layer "In7.Cu")
		(net "NFP_SERDES1_TX3_P")
	)
	(segment
		(start 44.236996 4.042004)
		(end 43.736997 3.542005)
		(width 0.099314)
		(layer "F.Cu")
		(net "NFP_SERDES1_TX3_N")
	)
	(via
		(at 43.736997 3.542005)
		(size 0.4826)
		(drill 0.25654)
		(layers "F.Cu" "B.Cu")
		(net "NFP_SERDES1_TX3_N")
	)
	(via
		(at 9.0424 15.8369)
		(size 0.508)
		(drill 0.254)
		(layers "F.Cu" "B.Cu")
		(net "NFP_SERDES1_TX3_N")
	)
	(segment
		(start 9.6774 16.4719)
		(end 9.0424 15.8369)
		(width 0.099314)
		(layer "B.Cu")
		(net "NFP_SERDES1_TX3_N")
	)
	(segment
		(start 20.949818 4.385539)
		(end 20.48637 4.385539)
		(width 0.096012)
		(layer "In7.Cu")
		(net "NFP_SERDES1_TX3_N")
	)
	(segment
		(start 20.48637 3.45727)
		(end 21.518143 3.45727)
		(width 0.096012)
		(layer "In7.Cu")
		(net "NFP_SERDES1_TX3_N")
	)
	(segment
		(start 21.209 5.134737)
		(end 21.209 4.64472)
		(width 0.096012)
		(layer "In7.Cu")
		(net "NFP_SERDES1_TX3_N")
	)
	(segment
		(start 13.68806 14.386966)
		(end 13.942466 14.13256)
		(width 0.096012)
		(layer "In7.Cu")
		(net "NFP_SERDES1_TX3_N")
	)
	(segment
		(start 21.209 4.64472)
		(end 20.949818 4.385539)
		(width 0.096012)
		(layer "In7.Cu")
		(net "NFP_SERDES1_TX3_N")
	)
	(segment
		(start 21.861424 2.44889)
		(end 20.48637 2.44889)
		(width 0.096012)
		(layer "In7.Cu")
		(net "NFP_SERDES1_TX3_N")
	)
	(segment
		(start 16.482466 11.59256)
		(end 16.855415 11.59256)
		(width 0.096012)
		(layer "In7.Cu")
		(net "NFP_SERDES1_TX3_N")
	)
	(segment
		(start 43.03682 1.733017)
		(end 43.03682 2.286305)
		(width 0.095758)
		(layer "In7.Cu")
		(net "NFP_SERDES1_TX3_N")
	)
	(segment
		(start 16.855415 11.59256)
		(end 17.65935 10.788625)
		(width 0.096012)
		(layer "In7.Cu")
		(net "NFP_SERDES1_TX3_N")
	)
	(segment
		(start 11.303 15.438755)
		(end 11.303 15.615818)
		(width 0.096012)
		(layer "In7.Cu")
		(net "NFP_SERDES1_TX3_N")
	)
	(segment
		(start 9.547225 15.332075)
		(end 11.19632 15.332075)
		(width 0.096012)
		(layer "In7.Cu")
		(net "NFP_SERDES1_TX3_N")
	)
	(segment
		(start 11.562182 15.875)
		(end 12.052198 15.875)
		(width 0.096012)
		(layer "In7.Cu")
		(net "NFP_SERDES1_TX3_N")
	)
	(segment
		(start 12.052198 15.875)
		(end 12.31138 15.615818)
		(width 0.096012)
		(layer "In7.Cu")
		(net "NFP_SERDES1_TX3_N")
	)
	(segment
		(start 19.63166 8.14263)
		(end 19.63166 7.16534)
		(width 0.096012)
		(layer "In7.Cu")
		(net "NFP_SERDES1_TX3_N")
	)
	(segment
		(start 20.48637 2.44889)
		(end 20.37969 2.34221)
		(width 0.096012)
		(layer "In7.Cu")
		(net "NFP_SERDES1_TX3_N")
	)
	(segment
		(start 43.12981 2.379294)
		(end 43.12981 2.934818)
		(width 0.095758)
		(layer "In7.Cu")
		(net "NFP_SERDES1_TX3_N")
	)
	(segment
		(start 11.303 15.615818)
		(end 11.562182 15.875)
		(width 0.096012)
		(layer "In7.Cu")
		(net "NFP_SERDES1_TX3_N")
	)
	(segment
		(start 21.51822 3.457194)
		(end 21.861501 3.457194)
		(width 0.096012)
		(layer "In7.Cu")
		(net "NFP_SERDES1_TX3_N")
	)
	(segment
		(start 21.861501 3.457194)
		(end 22.120606 3.198089)
		(width 0.096012)
		(layer "In7.Cu")
		(net "NFP_SERDES1_TX3_N")
	)
	(segment
		(start 16.22806 13.74394)
		(end 16.22806 11.846966)
		(width 0.096012)
		(layer "In7.Cu")
		(net "NFP_SERDES1_TX3_N")
	)
	(segment
		(start 20.37969 5.500599)
		(end 20.48637 5.393919)
		(width 0.096012)
		(layer "In7.Cu")
		(net "NFP_SERDES1_TX3_N")
	)
	(segment
		(start 22.120606 2.708072)
		(end 21.861424 2.44889)
		(width 0.096012)
		(layer "In7.Cu")
		(net "NFP_SERDES1_TX3_N")
	)
	(segment
		(start 20.48637 5.393919)
		(end 20.949818 5.393919)
		(width 0.096012)
		(layer "In7.Cu")
		(net "NFP_SERDES1_TX3_N")
	)
	(segment
		(start 20.37969 2.34221)
		(end 20.37969 1.210335)
		(width 0.096012)
		(layer "In7.Cu")
		(net "NFP_SERDES1_TX3_N")
	)
	(segment
		(start 16.22806 11.846966)
		(end 16.482466 11.59256)
		(width 0.096012)
		(layer "In7.Cu")
		(net "NFP_SERDES1_TX3_N")
	)
	(segment
		(start 19.63166 7.16534)
		(end 20.37969 6.41731)
		(width 0.096012)
		(layer "In7.Cu")
		(net "NFP_SERDES1_TX3_N")
	)
	(segment
		(start 13.68806 14.747088)
		(end 13.68806 14.386966)
		(width 0.096012)
		(layer "In7.Cu")
		(net "NFP_SERDES1_TX3_N")
	)
	(segment
		(start 22.120606 3.198089)
		(end 22.120606 2.708072)
		(width 0.096012)
		(layer "In7.Cu")
		(net "NFP_SERDES1_TX3_N")
	)
	(segment
		(start 13.103174 15.332075)
		(end 13.68806 14.747088)
		(width 0.096012)
		(layer "In7.Cu")
		(net "NFP_SERDES1_TX3_N")
	)
	(segment
		(start 12.31138 15.615818)
		(end 12.31138 15.438755)
		(width 0.096012)
		(layer "In7.Cu")
		(net "NFP_SERDES1_TX3_N")
	)
	(segment
		(start 9.0424 15.8369)
		(end 9.547225 15.332075)
		(width 0.096012)
		(layer "In7.Cu")
		(net "NFP_SERDES1_TX3_N")
	)
	(segment
		(start 43.013706 1.709903)
		(end 43.03682 1.733017)
		(width 0.095758)
		(layer "In7.Cu")
		(net "NFP_SERDES1_TX3_N")
	)
	(segment
		(start 43.03682 2.286305)
		(end 43.12981 2.379294)
		(width 0.095758)
		(layer "In7.Cu")
		(net "NFP_SERDES1_TX3_N")
	)
	(segment
		(start 20.37969 1.210335)
		(end 21.075675 0.51435)
		(width 0.096012)
		(layer "In7.Cu")
		(net "NFP_SERDES1_TX3_N")
	)
	(segment
		(start 43.013706 1.683868)
		(end 43.013706 1.709903)
		(width 0.095758)
		(layer "In7.Cu")
		(net "NFP_SERDES1_TX3_N")
	)
	(segment
		(start 20.37969 3.56395)
		(end 20.48637 3.45727)
		(width 0.096012)
		(layer "In7.Cu")
		(net "NFP_SERDES1_TX3_N")
	)
	(segment
		(start 17.65935 10.11494)
		(end 19.63166 8.14263)
		(width 0.096012)
		(layer "In7.Cu")
		(net "NFP_SERDES1_TX3_N")
	)
	(segment
		(start 15.83944 14.13256)
		(end 16.22806 13.74394)
		(width 0.096012)
		(layer "In7.Cu")
		(net "NFP_SERDES1_TX3_N")
	)
	(segment
		(start 20.37969 4.278859)
		(end 20.37969 3.56395)
		(width 0.096012)
		(layer "In7.Cu")
		(net "NFP_SERDES1_TX3_N")
	)
	(segment
		(start 13.942466 14.13256)
		(end 15.83944 14.13256)
		(width 0.096012)
		(layer "In7.Cu")
		(net "NFP_SERDES1_TX3_N")
	)
	(segment
		(start 12.41806 15.332075)
		(end 13.103174 15.332075)
		(width 0.096012)
		(layer "In7.Cu")
		(net "NFP_SERDES1_TX3_N")
	)
	(segment
		(start 11.19632 15.332075)
		(end 11.303 15.438755)
		(width 0.096012)
		(layer "In7.Cu")
		(net "NFP_SERDES1_TX3_N")
	)
	(segment
		(start 20.48637 4.385539)
		(end 20.37969 4.278859)
		(width 0.096012)
		(layer "In7.Cu")
		(net "NFP_SERDES1_TX3_N")
	)
	(segment
		(start 43.013706 0.963905)
		(end 43.013706 1.683868)
		(width 0.096012)
		(layer "In7.Cu")
		(net "NFP_SERDES1_TX3_N")
	)
	(segment
		(start 21.075675 0.51435)
		(end 42.564152 0.51435)
		(width 0.096012)
		(layer "In7.Cu")
		(net "NFP_SERDES1_TX3_N")
	)
	(segment
		(start 21.518143 3.45727)
		(end 21.51822 3.457194)
		(width 0.096012)
		(layer "In7.Cu")
		(net "NFP_SERDES1_TX3_N")
	)
	(segment
		(start 20.37969 6.41731)
		(end 20.37969 5.500599)
		(width 0.096012)
		(layer "In7.Cu")
		(net "NFP_SERDES1_TX3_N")
	)
	(segment
		(start 12.31138 15.438755)
		(end 12.41806 15.332075)
		(width 0.096012)
		(layer "In7.Cu")
		(net "NFP_SERDES1_TX3_N")
	)
	(segment
		(start 20.949818 5.393919)
		(end 21.209 5.134737)
		(width 0.096012)
		(layer "In7.Cu")
		(net "NFP_SERDES1_TX3_N")
	)
	(segment
		(start 17.65935 10.788625)
		(end 17.65935 10.11494)
		(width 0.096012)
		(layer "In7.Cu")
		(net "NFP_SERDES1_TX3_N")
	)
	(segment
		(start 43.12981 2.934818)
		(end 43.736997 3.542005)
		(width 0.095758)
		(layer "In7.Cu")
		(net "NFP_SERDES1_TX3_N")
	)
	(segment
		(start 42.564152 0.51435)
		(end 43.013706 0.963905)
		(width 0.096012)
		(layer "In7.Cu")
		(net "NFP_SERDES1_TX3_N")
	)
	(segment
		(start 45.236994 4.042004)
		(end 44.736995 3.542005)
		(width 0.099314)
		(layer "F.Cu")
		(net "NFP_SERDES1_TX2_P")
	)
	(via
		(at 44.736995 3.542005)
		(size 0.4826)
		(drill 0.20574)
		(layers "F.Cu" "B.Cu")
		(net "NFP_SERDES1_TX2_P")
	)
	(via
		(at 9.0424 12.0269)
		(size 0.508)
		(drill 0.254)
		(layers "F.Cu" "B.Cu")
		(net "NFP_SERDES1_TX2_P")
	)
	(segment
		(start 8.4074 12.6619)
		(end 9.0424 12.0269)
		(width 0.099314)
		(layer "B.Cu")
		(net "NFP_SERDES1_TX2_P")
	)
	(segment
		(start 44.367298 1.670685)
		(end 44.367298 0.270459)
		(width 0.096012)
		(layer "In7.Cu")
		(net "NFP_SERDES1_TX2_P")
	)
	(segment
		(start 15.1765 9.92124)
		(end 14.55674 10.541)
		(width 0.096012)
		(layer "In7.Cu")
		(net "NFP_SERDES1_TX2_P")
	)
	(segment
		(start 19.31924 -0.256438)
		(end 19.31924 0.083083)
		(width 0.096012)
		(layer "In7.Cu")
		(net "NFP_SERDES1_TX2_P")
	)
	(segment
		(start 19.598742 -0.53594)
		(end 19.31924 -0.256438)
		(width 0.096012)
		(layer "In7.Cu")
		(net "NFP_SERDES1_TX2_P")
	)
	(segment
		(start 16.842334 8.65124)
		(end 16.515588 8.65124)
		(width 0.096012)
		(layer "In7.Cu")
		(net "NFP_SERDES1_TX2_P")
	)
	(segment
		(start 19.31924 5.57276)
		(end 17.312234 7.579766)
		(width 0.096012)
		(layer "In7.Cu")
		(net "NFP_SERDES1_TX2_P")
	)
	(segment
		(start 15.82674 9.340088)
		(end 15.82674 9.666834)
		(width 0.096012)
		(layer "In7.Cu")
		(net "NFP_SERDES1_TX2_P")
	)
	(segment
		(start 11.957152 13.83665)
		(end 11.156848 13.83665)
		(width 0.096012)
		(layer "In7.Cu")
		(net "NFP_SERDES1_TX2_P")
	)
	(segment
		(start 44.367298 1.72527)
		(end 44.367298 1.670685)
		(width 0.095758)
		(layer "In7.Cu")
		(net "NFP_SERDES1_TX2_P")
	)
	(segment
		(start 19.31924 1.272819)
		(end 19.31924 5.57276)
		(width 0.096012)
		(layer "In7.Cu")
		(net "NFP_SERDES1_TX2_P")
	)
	(segment
		(start 12.43076 11.19124)
		(end 12.15771 11.46429)
		(width 0.096012)
		(layer "In7.Cu")
		(net "NFP_SERDES1_TX2_P")
	)
	(segment
		(start 44.444133 3.810025)
		(end 44.344184 3.710076)
		(width 0.095758)
		(layer "In7.Cu")
		(net "NFP_SERDES1_TX2_P")
	)
	(segment
		(start 16.515588 8.65124)
		(end 15.82674 9.340088)
		(width 0.096012)
		(layer "In7.Cu")
		(net "NFP_SERDES1_TX2_P")
	)
	(segment
		(start 18.669 0.427609)
		(end 18.669 0.928294)
		(width 0.096012)
		(layer "In7.Cu")
		(net "NFP_SERDES1_TX2_P")
	)
	(segment
		(start 44.597295 3.810025)
		(end 44.444133 3.810025)
		(width 0.095758)
		(layer "In7.Cu")
		(net "NFP_SERDES1_TX2_P")
	)
	(segment
		(start 9.5885 12.573)
		(end 9.0424 12.0269)
		(width 0.096012)
		(layer "In7.Cu")
		(net "NFP_SERDES1_TX2_P")
	)
	(segment
		(start 11.00709 13.686892)
		(end 11.00709 12.931242)
		(width 0.096012)
		(layer "In7.Cu")
		(net "NFP_SERDES1_TX2_P")
	)
	(segment
		(start 12.15771 13.636092)
		(end 11.957152 13.83665)
		(width 0.096012)
		(layer "In7.Cu")
		(net "NFP_SERDES1_TX2_P")
	)
	(segment
		(start 17.312234 7.579766)
		(end 17.312234 8.18134)
		(width 0.096012)
		(layer "In7.Cu")
		(net "NFP_SERDES1_TX2_P")
	)
	(segment
		(start 44.367298 0.270459)
		(end 43.560898 -0.53594)
		(width 0.096012)
		(layer "In7.Cu")
		(net "NFP_SERDES1_TX2_P")
	)
	(segment
		(start 44.736995 3.670325)
		(end 44.597295 3.810025)
		(width 0.095758)
		(layer "In7.Cu")
		(net "NFP_SERDES1_TX2_P")
	)
	(segment
		(start 18.917514 1.176807)
		(end 19.223228 1.176807)
		(width 0.096012)
		(layer "In7.Cu")
		(net "NFP_SERDES1_TX2_P")
	)
	(segment
		(start 43.560898 -0.53594)
		(end 19.598742 -0.53594)
		(width 0.096012)
		(layer "In7.Cu")
		(net "NFP_SERDES1_TX2_P")
	)
	(segment
		(start 10.648848 12.573)
		(end 9.5885 12.573)
		(width 0.096012)
		(layer "In7.Cu")
		(net "NFP_SERDES1_TX2_P")
	)
	(segment
		(start 15.572334 9.92124)
		(end 15.1765 9.92124)
		(width 0.096012)
		(layer "In7.Cu")
		(net "NFP_SERDES1_TX2_P")
	)
	(segment
		(start 18.669 0.928294)
		(end 18.917514 1.176807)
		(width 0.096012)
		(layer "In7.Cu")
		(net "NFP_SERDES1_TX2_P")
	)
	(segment
		(start 15.82674 9.666834)
		(end 15.572334 9.92124)
		(width 0.096012)
		(layer "In7.Cu")
		(net "NFP_SERDES1_TX2_P")
	)
	(segment
		(start 19.31924 0.083083)
		(end 19.223228 0.179095)
		(width 0.096012)
		(layer "In7.Cu")
		(net "NFP_SERDES1_TX2_P")
	)
	(segment
		(start 18.917514 0.179095)
		(end 18.669 0.427609)
		(width 0.096012)
		(layer "In7.Cu")
		(net "NFP_SERDES1_TX2_P")
	)
	(segment
		(start 11.00709 12.931242)
		(end 10.648848 12.573)
		(width 0.096012)
		(layer "In7.Cu")
		(net "NFP_SERDES1_TX2_P")
	)
	(segment
		(start 19.223228 0.179095)
		(end 18.917514 0.179095)
		(width 0.096012)
		(layer "In7.Cu")
		(net "NFP_SERDES1_TX2_P")
	)
	(segment
		(start 12.15771 11.46429)
		(end 12.15771 13.636092)
		(width 0.096012)
		(layer "In7.Cu")
		(net "NFP_SERDES1_TX2_P")
	)
	(segment
		(start 14.55674 10.936834)
		(end 14.302334 11.19124)
		(width 0.096012)
		(layer "In7.Cu")
		(net "NFP_SERDES1_TX2_P")
	)
	(segment
		(start 44.344184 1.748384)
		(end 44.367298 1.72527)
		(width 0.095758)
		(layer "In7.Cu")
		(net "NFP_SERDES1_TX2_P")
	)
	(segment
		(start 14.302334 11.19124)
		(end 12.43076 11.19124)
		(width 0.096012)
		(layer "In7.Cu")
		(net "NFP_SERDES1_TX2_P")
	)
	(segment
		(start 44.344184 3.710076)
		(end 44.344184 1.748384)
		(width 0.095758)
		(layer "In7.Cu")
		(net "NFP_SERDES1_TX2_P")
	)
	(segment
		(start 17.312234 8.18134)
		(end 16.842334 8.65124)
		(width 0.096012)
		(layer "In7.Cu")
		(net "NFP_SERDES1_TX2_P")
	)
	(segment
		(start 44.736995 3.542005)
		(end 44.736995 3.670325)
		(width 0.095758)
		(layer "In7.Cu")
		(net "NFP_SERDES1_TX2_P")
	)
	(segment
		(start 14.55674 10.541)
		(end 14.55674 10.936834)
		(width 0.096012)
		(layer "In7.Cu")
		(net "NFP_SERDES1_TX2_P")
	)
	(segment
		(start 19.223228 1.176807)
		(end 19.31924 1.272819)
		(width 0.096012)
		(layer "In7.Cu")
		(net "NFP_SERDES1_TX2_P")
	)
	(segment
		(start 11.156848 13.83665)
		(end 11.00709 13.686892)
		(width 0.096012)
		(layer "In7.Cu")
		(net "NFP_SERDES1_TX2_P")
	)
	(segment
		(start 45.236994 5.042002)
		(end 44.736995 4.542003)
		(width 0.099314)
		(layer "F.Cu")
		(net "NFP_SERDES1_TX2_N")
	)
	(via
		(at 44.736995 4.542003)
		(size 0.4826)
		(drill 0.25654)
		(layers "F.Cu" "B.Cu")
		(net "NFP_SERDES1_TX2_N")
	)
	(via
		(at 9.0424 13.2969)
		(size 0.508)
		(drill 0.254)
		(layers "F.Cu" "B.Cu")
		(net "NFP_SERDES1_TX2_N")
	)
	(segment
		(start 8.4074 13.9319)
		(end 9.0424 13.2969)
		(width 0.099314)
		(layer "B.Cu")
		(net "NFP_SERDES1_TX2_N")
	)
	(segment
		(start 15.284348 10.18159)
		(end 14.81709 10.648848)
		(width 0.096012)
		(layer "In7.Cu")
		(net "NFP_SERDES1_TX2_N")
	)
	(segment
		(start 12.41806 13.744016)
		(end 12.065076 14.097)
		(width 0.096012)
		(layer "In7.Cu")
		(net "NFP_SERDES1_TX2_N")
	)
	(segment
		(start 12.538608 11.45159)
		(end 12.41806 11.572138)
		(width 0.096012)
		(layer "In7.Cu")
		(net "NFP_SERDES1_TX2_N")
	)
	(segment
		(start 15.680182 10.18159)
		(end 15.284348 10.18159)
		(width 0.096012)
		(layer "In7.Cu")
		(net "NFP_SERDES1_TX2_N")
	)
	(segment
		(start 19.57959 0.190932)
		(end 19.331076 0.439445)
		(width 0.096012)
		(layer "In7.Cu")
		(net "NFP_SERDES1_TX2_N")
	)
	(segment
		(start 10.74674 13.79474)
		(end 10.74674 13.03909)
		(width 0.096012)
		(layer "In7.Cu")
		(net "NFP_SERDES1_TX2_N")
	)
	(segment
		(start 18.92935 0.820445)
		(end 19.025362 0.916457)
		(width 0.096012)
		(layer "In7.Cu")
		(net "NFP_SERDES1_TX2_N")
	)
	(segment
		(start 14.81709 10.648848)
		(end 14.81709 11.044682)
		(width 0.096012)
		(layer "In7.Cu")
		(net "NFP_SERDES1_TX2_N")
	)
	(segment
		(start 19.57959 -0.14859)
		(end 19.57959 0.190932)
		(width 0.096012)
		(layer "In7.Cu")
		(net "NFP_SERDES1_TX2_N")
	)
	(segment
		(start 16.623436 8.91159)
		(end 16.08709 9.447936)
		(width 0.096012)
		(layer "In7.Cu")
		(net "NFP_SERDES1_TX2_N")
	)
	(segment
		(start 19.331076 0.439445)
		(end 19.025362 0.439445)
		(width 0.096012)
		(layer "In7.Cu")
		(net "NFP_SERDES1_TX2_N")
	)
	(segment
		(start 44.106948 1.670685)
		(end 44.106948 0.378308)
		(width 0.096012)
		(layer "In7.Cu")
		(net "NFP_SERDES1_TX2_N")
	)
	(segment
		(start 19.331076 0.916457)
		(end 19.57959 1.164971)
		(width 0.096012)
		(layer "In7.Cu")
		(net "NFP_SERDES1_TX2_N")
	)
	(segment
		(start 44.130062 1.748384)
		(end 44.106948 1.72527)
		(width 0.095758)
		(layer "In7.Cu")
		(net "NFP_SERDES1_TX2_N")
	)
	(segment
		(start 19.025362 0.439445)
		(end 18.92935 0.535457)
		(width 0.096012)
		(layer "In7.Cu")
		(net "NFP_SERDES1_TX2_N")
	)
	(segment
		(start 44.130062 3.93507)
		(end 44.130062 1.748384)
		(width 0.095758)
		(layer "In7.Cu")
		(net "NFP_SERDES1_TX2_N")
	)
	(segment
		(start 16.950182 8.91159)
		(end 16.623436 8.91159)
		(width 0.096012)
		(layer "In7.Cu")
		(net "NFP_SERDES1_TX2_N")
	)
	(segment
		(start 19.70659 -0.27559)
		(end 19.57959 -0.14859)
		(width 0.096012)
		(layer "In7.Cu")
		(net "NFP_SERDES1_TX2_N")
	)
	(segment
		(start 16.08709 9.447936)
		(end 16.08709 9.774682)
		(width 0.096012)
		(layer "In7.Cu")
		(net "NFP_SERDES1_TX2_N")
	)
	(segment
		(start 9.50595 12.83335)
		(end 9.0424 13.2969)
		(width 0.096012)
		(layer "In7.Cu")
		(net "NFP_SERDES1_TX2_N")
	)
	(segment
		(start 18.92935 0.535457)
		(end 18.92935 0.820445)
		(width 0.096012)
		(layer "In7.Cu")
		(net "NFP_SERDES1_TX2_N")
	)
	(segment
		(start 19.57959 5.680608)
		(end 17.572584 7.687615)
		(width 0.096012)
		(layer "In7.Cu")
		(net "NFP_SERDES1_TX2_N")
	)
	(segment
		(start 19.025362 0.916457)
		(end 19.331076 0.916457)
		(width 0.096012)
		(layer "In7.Cu")
		(net "NFP_SERDES1_TX2_N")
	)
	(segment
		(start 44.736995 4.542003)
		(end 44.130062 3.93507)
		(width 0.095758)
		(layer "In7.Cu")
		(net "NFP_SERDES1_TX2_N")
	)
	(segment
		(start 12.065076 14.097)
		(end 11.049 14.097)
		(width 0.096012)
		(layer "In7.Cu")
		(net "NFP_SERDES1_TX2_N")
	)
	(segment
		(start 44.106948 1.72527)
		(end 44.106948 1.670685)
		(width 0.095758)
		(layer "In7.Cu")
		(net "NFP_SERDES1_TX2_N")
	)
	(segment
		(start 17.572584 8.289188)
		(end 16.950182 8.91159)
		(width 0.096012)
		(layer "In7.Cu")
		(net "NFP_SERDES1_TX2_N")
	)
	(segment
		(start 19.57959 1.164971)
		(end 19.57959 5.680608)
		(width 0.096012)
		(layer "In7.Cu")
		(net "NFP_SERDES1_TX2_N")
	)
	(segment
		(start 10.74674 13.03909)
		(end 10.541 12.83335)
		(width 0.096012)
		(layer "In7.Cu")
		(net "NFP_SERDES1_TX2_N")
	)
	(segment
		(start 17.572584 7.687615)
		(end 17.572584 8.289188)
		(width 0.096012)
		(layer "In7.Cu")
		(net "NFP_SERDES1_TX2_N")
	)
	(segment
		(start 10.541 12.83335)
		(end 9.50595 12.83335)
		(width 0.096012)
		(layer "In7.Cu")
		(net "NFP_SERDES1_TX2_N")
	)
	(segment
		(start 12.41806 11.572138)
		(end 12.41806 13.744016)
		(width 0.096012)
		(layer "In7.Cu")
		(net "NFP_SERDES1_TX2_N")
	)
	(segment
		(start 14.410182 11.45159)
		(end 12.538608 11.45159)
		(width 0.096012)
		(layer "In7.Cu")
		(net "NFP_SERDES1_TX2_N")
	)
	(segment
		(start 14.81709 11.044682)
		(end 14.410182 11.45159)
		(width 0.096012)
		(layer "In7.Cu")
		(net "NFP_SERDES1_TX2_N")
	)
	(segment
		(start 16.08709 9.774682)
		(end 15.680182 10.18159)
		(width 0.096012)
		(layer "In7.Cu")
		(net "NFP_SERDES1_TX2_N")
	)
	(segment
		(start 43.45305 -0.27559)
		(end 19.70659 -0.27559)
		(width 0.096012)
		(layer "In7.Cu")
		(net "NFP_SERDES1_TX2_N")
	)
	(segment
		(start 11.049 14.097)
		(end 10.74674 13.79474)
		(width 0.096012)
		(layer "In7.Cu")
		(net "NFP_SERDES1_TX2_N")
	)
	(segment
		(start 44.106948 0.378308)
		(end 43.45305 -0.27559)
		(width 0.096012)
		(layer "In7.Cu")
		(net "NFP_SERDES1_TX2_N")
	)
	(segment
		(start 46.236992 3.042006)
		(end 45.736993 2.542007)
		(width 0.099314)
		(layer "F.Cu")
		(net "NFP_SERDES1_TX1_P")
	)
	(via
		(at 45.736993 2.542007)
		(size 0.4826)
		(drill 0.20574)
		(layers "F.Cu" "B.Cu")
		(net "NFP_SERDES1_TX1_P")
	)
	(via
		(at 9.0424 9.4869)
		(size 0.508)
		(drill 0.254)
		(layers "F.Cu" "B.Cu")
		(net "NFP_SERDES1_TX1_P")
	)
	(segment
		(start 9.6774 10.1219)
		(end 9.0424 9.4869)
		(width 0.099314)
		(layer "B.Cu")
		(net "NFP_SERDES1_TX1_P")
	)
	(segment
		(start 14.956739 6.252261)
		(end 14.605 6.604)
		(width 0.096012)
		(layer "In7.Cu")
		(net "NFP_SERDES1_TX1_P")
	)
	(segment
		(start 13.42771 9.199118)
		(end 13.42771 9.81329)
		(width 0.096012)
		(layer "In7.Cu")
		(net "NFP_SERDES1_TX1_P")
	)
	(segment
		(start 14.605 8.696198)
		(end 14.508988 8.79221)
		(width 0.096012)
		(layer "In7.Cu")
		(net "NFP_SERDES1_TX1_P")
	)
	(segment
		(start 44.430848 -1.28397)
		(end 18.095824 -1.28397)
		(width 0.096012)
		(layer "In7.Cu")
		(net "NFP_SERDES1_TX1_P")
	)
	(segment
		(start 45.736993 2.542007)
		(end 45.736993 2.68986)
		(width 0.095758)
		(layer "In7.Cu")
		(net "NFP_SERDES1_TX1_P")
	)
	(segment
		(start 45.366305 -0.348513)
		(end 44.430848 -1.28397)
		(width 0.096012)
		(layer "In7.Cu")
		(net "NFP_SERDES1_TX1_P")
	)
	(segment
		(start 12.16467 8.895182)
		(end 11.915394 8.645906)
		(width 0.096012)
		(layer "In7.Cu")
		(net "NFP_SERDES1_TX1_P")
	)
	(segment
		(start 11.15629 9.885045)
		(end 11.04961 9.991725)
		(width 0.096012)
		(layer "In7.Cu")
		(net "NFP_SERDES1_TX1_P")
	)
	(segment
		(start 11.04961 9.991725)
		(end 9.547225 9.991725)
		(width 0.096012)
		(layer "In7.Cu")
		(net "NFP_SERDES1_TX1_P")
	)
	(segment
		(start 45.366305 1.550035)
		(end 45.366305 1.524)
		(width 0.095758)
		(layer "In7.Cu")
		(net "NFP_SERDES1_TX1_P")
	)
	(segment
		(start 45.366305 1.524)
		(end 45.366305 -0.348513)
		(width 0.096012)
		(layer "In7.Cu")
		(net "NFP_SERDES1_TX1_P")
	)
	(segment
		(start 13.42771 9.81329)
		(end 13.249275 9.991725)
		(width 0.096012)
		(layer "In7.Cu")
		(net "NFP_SERDES1_TX1_P")
	)
	(segment
		(start 18.095824 -1.28397)
		(end 17.84731 -1.035456)
		(width 0.096012)
		(layer "In7.Cu")
		(net "NFP_SERDES1_TX1_P")
	)
	(segment
		(start 45.736993 2.68986)
		(end 45.632853 2.794)
		(width 0.095758)
		(layer "In7.Cu")
		(net "NFP_SERDES1_TX1_P")
	)
	(segment
		(start 45.632853 2.794)
		(end 45.443877 2.794)
		(width 0.095758)
		(layer "In7.Cu")
		(net "NFP_SERDES1_TX1_P")
	)
	(segment
		(start 14.605 6.604)
		(end 14.605 8.696198)
		(width 0.096012)
		(layer "In7.Cu")
		(net "NFP_SERDES1_TX1_P")
	)
	(segment
		(start 13.834618 8.79221)
		(end 13.42771 9.199118)
		(width 0.096012)
		(layer "In7.Cu")
		(net "NFP_SERDES1_TX1_P")
	)
	(segment
		(start 45.443877 2.794)
		(end 45.343928 2.694051)
		(width 0.095758)
		(layer "In7.Cu")
		(net "NFP_SERDES1_TX1_P")
	)
	(segment
		(start 17.89303 3.635502)
		(end 17.89303 5.956173)
		(width 0.096012)
		(layer "In7.Cu")
		(net "NFP_SERDES1_TX1_P")
	)
	(segment
		(start 12.27135 9.991725)
		(end 12.16467 9.885045)
		(width 0.096012)
		(layer "In7.Cu")
		(net "NFP_SERDES1_TX1_P")
	)
	(segment
		(start 45.343928 2.694051)
		(end 45.343928 1.572412)
		(width 0.095758)
		(layer "In7.Cu")
		(net "NFP_SERDES1_TX1_P")
	)
	(segment
		(start 12.16467 9.885045)
		(end 12.16467 8.895182)
		(width 0.096012)
		(layer "In7.Cu")
		(net "NFP_SERDES1_TX1_P")
	)
	(segment
		(start 11.915394 8.645906)
		(end 11.405565 8.645906)
		(width 0.096012)
		(layer "In7.Cu")
		(net "NFP_SERDES1_TX1_P")
	)
	(segment
		(start 9.547225 9.991725)
		(end 9.0424 9.4869)
		(width 0.096012)
		(layer "In7.Cu")
		(net "NFP_SERDES1_TX1_P")
	)
	(segment
		(start 11.15629 8.895182)
		(end 11.15629 9.885045)
		(width 0.096012)
		(layer "In7.Cu")
		(net "NFP_SERDES1_TX1_P")
	)
	(segment
		(start 17.84731 3.589782)
		(end 17.89303 3.635502)
		(width 0.096012)
		(layer "In7.Cu")
		(net "NFP_SERDES1_TX1_P")
	)
	(segment
		(start 14.508988 8.79221)
		(end 13.834618 8.79221)
		(width 0.096012)
		(layer "In7.Cu")
		(net "NFP_SERDES1_TX1_P")
	)
	(segment
		(start 13.249275 9.991725)
		(end 12.27135 9.991725)
		(width 0.096012)
		(layer "In7.Cu")
		(net "NFP_SERDES1_TX1_P")
	)
	(segment
		(start 17.84731 -1.035456)
		(end 17.84731 3.589782)
		(width 0.096012)
		(layer "In7.Cu")
		(net "NFP_SERDES1_TX1_P")
	)
	(segment
		(start 17.89303 5.956173)
		(end 17.596942 6.252261)
		(width 0.096012)
		(layer "In7.Cu")
		(net "NFP_SERDES1_TX1_P")
	)
	(segment
		(start 17.596942 6.252261)
		(end 14.956739 6.252261)
		(width 0.096012)
		(layer "In7.Cu")
		(net "NFP_SERDES1_TX1_P")
	)
	(segment
		(start 45.343928 1.572412)
		(end 45.366305 1.550035)
		(width 0.095758)
		(layer "In7.Cu")
		(net "NFP_SERDES1_TX1_P")
	)
	(segment
		(start 11.405565 8.645906)
		(end 11.15629 8.895182)
		(width 0.096012)
		(layer "In7.Cu")
		(net "NFP_SERDES1_TX1_P")
	)
	(segment
		(start 46.236992 4.042004)
		(end 45.736993 3.542005)
		(width 0.099314)
		(layer "F.Cu")
		(net "NFP_SERDES1_TX1_N")
	)
	(via
		(at 9.0424 10.7569)
		(size 0.508)
		(drill 0.254)
		(layers "F.Cu" "B.Cu")
		(net "NFP_SERDES1_TX1_N")
	)
	(via
		(at 45.736993 3.542005)
		(size 0.4826)
		(drill 0.25654)
		(layers "F.Cu" "B.Cu")
		(net "NFP_SERDES1_TX1_N")
	)
	(segment
		(start 9.6774 11.3919)
		(end 9.0424 10.7569)
		(width 0.099314)
		(layer "B.Cu")
		(net "NFP_SERDES1_TX1_N")
	)
	(segment
		(start 11.90432 9.992893)
		(end 12.163577 10.252151)
		(width 0.096012)
		(layer "In7.Cu")
		(net "NFP_SERDES1_TX1_N")
	)
	(segment
		(start 45.129806 1.560881)
		(end 45.129806 2.934818)
		(width 0.095758)
		(layer "In7.Cu")
		(net "NFP_SERDES1_TX1_N")
	)
	(segment
		(start 45.129806 2.934818)
		(end 45.736993 3.542005)
		(width 0.095758)
		(layer "In7.Cu")
		(net "NFP_SERDES1_TX1_N")
	)
	(segment
		(start 11.90432 9.00303)
		(end 11.90432 9.992893)
		(width 0.096012)
		(layer "In7.Cu")
		(net "NFP_SERDES1_TX1_N")
	)
	(segment
		(start 11.513414 8.906256)
		(end 11.807546 8.906256)
		(width 0.096012)
		(layer "In7.Cu")
		(net "NFP_SERDES1_TX1_N")
	)
	(segment
		(start 45.105955 -0.240665)
		(end 45.105955 1.524)
		(width 0.096012)
		(layer "In7.Cu")
		(net "NFP_SERDES1_TX1_N")
	)
	(segment
		(start 14.86535 8.804046)
		(end 14.86535 6.711848)
		(width 0.096012)
		(layer "In7.Cu")
		(net "NFP_SERDES1_TX1_N")
	)
	(segment
		(start 12.379122 10.252151)
		(end 12.379198 10.252075)
		(width 0.096012)
		(layer "In7.Cu")
		(net "NFP_SERDES1_TX1_N")
	)
	(segment
		(start 11.807546 8.906256)
		(end 11.90432 9.00303)
		(width 0.096012)
		(layer "In7.Cu")
		(net "NFP_SERDES1_TX1_N")
	)
	(segment
		(start 13.942466 9.05256)
		(end 14.616836 9.05256)
		(width 0.096012)
		(layer "In7.Cu")
		(net "NFP_SERDES1_TX1_N")
	)
	(segment
		(start 9.547225 10.252075)
		(end 11.157458 10.252075)
		(width 0.096012)
		(layer "In7.Cu")
		(net "NFP_SERDES1_TX1_N")
	)
	(segment
		(start 9.0424 10.7569)
		(end 9.547225 10.252075)
		(width 0.096012)
		(layer "In7.Cu")
		(net "NFP_SERDES1_TX1_N")
	)
	(segment
		(start 18.10766 -0.927608)
		(end 18.203672 -1.02362)
		(width 0.096012)
		(layer "In7.Cu")
		(net "NFP_SERDES1_TX1_N")
	)
	(segment
		(start 18.15338 3.527654)
		(end 18.10766 3.481934)
		(width 0.096012)
		(layer "In7.Cu")
		(net "NFP_SERDES1_TX1_N")
	)
	(segment
		(start 12.379198 10.252075)
		(end 13.357123 10.252075)
		(width 0.096012)
		(layer "In7.Cu")
		(net "NFP_SERDES1_TX1_N")
	)
	(segment
		(start 12.163577 10.252151)
		(end 12.379122 10.252151)
		(width 0.096012)
		(layer "In7.Cu")
		(net "NFP_SERDES1_TX1_N")
	)
	(segment
		(start 45.105955 1.524)
		(end 45.105955 1.53703)
		(width 0.095758)
		(layer "In7.Cu")
		(net "NFP_SERDES1_TX1_N")
	)
	(segment
		(start 15.064588 6.512611)
		(end 17.704791 6.512611)
		(width 0.096012)
		(layer "In7.Cu")
		(net "NFP_SERDES1_TX1_N")
	)
	(segment
		(start 45.105955 1.53703)
		(end 45.129806 1.560881)
		(width 0.095758)
		(layer "In7.Cu")
		(net "NFP_SERDES1_TX1_N")
	)
	(segment
		(start 13.68806 9.306966)
		(end 13.942466 9.05256)
		(width 0.096012)
		(layer "In7.Cu")
		(net "NFP_SERDES1_TX1_N")
	)
	(segment
		(start 11.41664 9.00303)
		(end 11.513414 8.906256)
		(width 0.096012)
		(layer "In7.Cu")
		(net "NFP_SERDES1_TX1_N")
	)
	(segment
		(start 14.616836 9.05256)
		(end 14.86535 8.804046)
		(width 0.096012)
		(layer "In7.Cu")
		(net "NFP_SERDES1_TX1_N")
	)
	(segment
		(start 18.15338 6.064021)
		(end 18.15338 3.527654)
		(width 0.096012)
		(layer "In7.Cu")
		(net "NFP_SERDES1_TX1_N")
	)
	(segment
		(start 18.10766 3.481934)
		(end 18.10766 -0.927608)
		(width 0.096012)
		(layer "In7.Cu")
		(net "NFP_SERDES1_TX1_N")
	)
	(segment
		(start 13.357123 10.252075)
		(end 13.68806 9.921138)
		(width 0.096012)
		(layer "In7.Cu")
		(net "NFP_SERDES1_TX1_N")
	)
	(segment
		(start 17.704791 6.512611)
		(end 18.15338 6.064021)
		(width 0.096012)
		(layer "In7.Cu")
		(net "NFP_SERDES1_TX1_N")
	)
	(segment
		(start 44.323 -1.02362)
		(end 45.105955 -0.240665)
		(width 0.096012)
		(layer "In7.Cu")
		(net "NFP_SERDES1_TX1_N")
	)
	(segment
		(start 11.157458 10.252075)
		(end 11.41664 9.992893)
		(width 0.096012)
		(layer "In7.Cu")
		(net "NFP_SERDES1_TX1_N")
	)
	(segment
		(start 18.203672 -1.02362)
		(end 44.323 -1.02362)
		(width 0.096012)
		(layer "In7.Cu")
		(net "NFP_SERDES1_TX1_N")
	)
	(segment
		(start 13.68806 9.921138)
		(end 13.68806 9.306966)
		(width 0.096012)
		(layer "In7.Cu")
		(net "NFP_SERDES1_TX1_N")
	)
	(segment
		(start 14.86535 6.711848)
		(end 15.064588 6.512611)
		(width 0.096012)
		(layer "In7.Cu")
		(net "NFP_SERDES1_TX1_N")
	)
	(segment
		(start 11.41664 9.992893)
		(end 11.41664 9.00303)
		(width 0.096012)
		(layer "In7.Cu")
		(net "NFP_SERDES1_TX1_N")
	)
	(segment
		(start 47.23699 4.042004)
		(end 46.736991 3.542005)
		(width 0.099314)
		(layer "F.Cu")
		(net "NFP_SERDES1_TX0_P")
	)
	(via
		(at 46.736991 3.542005)
		(size 0.4826)
		(drill 0.20574)
		(layers "F.Cu" "B.Cu")
		(net "NFP_SERDES1_TX0_P")
	)
	(via
		(at 7.7724 6.9469)
		(size 0.508)
		(drill 0.254)
		(layers "F.Cu" "B.Cu")
		(net "NFP_SERDES1_TX0_P")
	)
	(segment
		(start 8.4074 7.5819)
		(end 7.7724 6.9469)
		(width 0.099314)
		(layer "B.Cu")
		(net "NFP_SERDES1_TX0_P")
	)
	(segment
		(start 13.716 3.683)
		(end 13.335 4.064)
		(width 0.096012)
		(layer "In7.Cu")
		(net "NFP_SERDES1_TX0_P")
	)
	(segment
		(start 13.335 5.969)
		(end 13.081 6.223)
		(width 0.096012)
		(layer "In7.Cu")
		(net "NFP_SERDES1_TX0_P")
	)
	(segment
		(start 46.367294 -1.130706)
		(end 45.466 -2.032)
		(width 0.096012)
		(layer "In7.Cu")
		(net "NFP_SERDES1_TX0_P")
	)
	(segment
		(start 46.736991 3.542005)
		(end 46.736991 3.711524)
		(width 0.095758)
		(layer "In7.Cu")
		(net "NFP_SERDES1_TX0_P")
	)
	(segment
		(start 46.34418 3.715715)
		(end 46.34418 1.612519)
		(width 0.095758)
		(layer "In7.Cu")
		(net "NFP_SERDES1_TX0_P")
	)
	(segment
		(start 11.141583 6.223)
		(end 10.893044 6.471539)
		(width 0.096012)
		(layer "In7.Cu")
		(net "NFP_SERDES1_TX0_P")
	)
	(segment
		(start 17.399 -2.032)
		(end 17.09928 -1.73228)
		(width 0.096012)
		(layer "In7.Cu")
		(net "NFP_SERDES1_TX0_P")
	)
	(segment
		(start 46.367294 1.56337)
		(end 46.367294 -1.130706)
		(width 0.096012)
		(layer "In7.Cu")
		(net "NFP_SERDES1_TX0_P")
	)
	(segment
		(start 46.736991 3.711524)
		(end 46.632825 3.81569)
		(width 0.095758)
		(layer "In7.Cu")
		(net "NFP_SERDES1_TX0_P")
	)
	(segment
		(start 13.335 4.064)
		(end 13.335 5.969)
		(width 0.096012)
		(layer "In7.Cu")
		(net "NFP_SERDES1_TX0_P")
	)
	(segment
		(start 10.893044 6.471539)
		(end 10.893044 7.396988)
		(width 0.096012)
		(layer "In7.Cu")
		(net "NFP_SERDES1_TX0_P")
	)
	(segment
		(start 10.797032 7.493)
		(end 8.3185 7.493)
		(width 0.096012)
		(layer "In7.Cu")
		(net "NFP_SERDES1_TX0_P")
	)
	(segment
		(start 17.09928 -1.73228)
		(end 17.09928 3.34772)
		(width 0.096012)
		(layer "In7.Cu")
		(net "NFP_SERDES1_TX0_P")
	)
	(segment
		(start 16.764 3.683)
		(end 13.716 3.683)
		(width 0.096012)
		(layer "In7.Cu")
		(net "NFP_SERDES1_TX0_P")
	)
	(segment
		(start 17.09928 3.34772)
		(end 16.764 3.683)
		(width 0.096012)
		(layer "In7.Cu")
		(net "NFP_SERDES1_TX0_P")
	)
	(segment
		(start 8.3185 7.493)
		(end 7.7724 6.9469)
		(width 0.096012)
		(layer "In7.Cu")
		(net "NFP_SERDES1_TX0_P")
	)
	(segment
		(start 10.893044 7.396988)
		(end 10.797032 7.493)
		(width 0.096012)
		(layer "In7.Cu")
		(net "NFP_SERDES1_TX0_P")
	)
	(segment
		(start 45.466 -2.032)
		(end 17.399 -2.032)
		(width 0.096012)
		(layer "In7.Cu")
		(net "NFP_SERDES1_TX0_P")
	)
	(segment
		(start 46.632825 3.81569)
		(end 46.444154 3.81569)
		(width 0.095758)
		(layer "In7.Cu")
		(net "NFP_SERDES1_TX0_P")
	)
	(segment
		(start 13.081 6.223)
		(end 11.141583 6.223)
		(width 0.096012)
		(layer "In7.Cu")
		(net "NFP_SERDES1_TX0_P")
	)
	(segment
		(start 46.34418 1.612519)
		(end 46.367294 1.589405)
		(width 0.095758)
		(layer "In7.Cu")
		(net "NFP_SERDES1_TX0_P")
	)
	(segment
		(start 46.444154 3.81569)
		(end 46.34418 3.715715)
		(width 0.095758)
		(layer "In7.Cu")
		(net "NFP_SERDES1_TX0_P")
	)
	(segment
		(start 46.367294 1.589405)
		(end 46.367294 1.56337)
		(width 0.095758)
		(layer "In7.Cu")
		(net "NFP_SERDES1_TX0_P")
	)
	(segment
		(start 47.23699 5.042002)
		(end 46.736991 4.542003)
		(width 0.099314)
		(layer "F.Cu")
		(net "NFP_SERDES1_TX0_N")
	)
	(via
		(at 7.7724 8.2169)
		(size 0.508)
		(drill 0.254)
		(layers "F.Cu" "B.Cu")
		(net "NFP_SERDES1_TX0_N")
	)
	(via
		(at 46.736991 4.542003)
		(size 0.4826)
		(drill 0.25654)
		(layers "F.Cu" "B.Cu")
		(net "NFP_SERDES1_TX0_N")
	)
	(segment
		(start 8.4074 8.8519)
		(end 7.7724 8.2169)
		(width 0.099314)
		(layer "B.Cu")
		(net "NFP_SERDES1_TX0_N")
	)
	(segment
		(start 17.35963 3.455568)
		(end 16.871848 3.94335)
		(width 0.096012)
		(layer "In7.Cu")
		(net "NFP_SERDES1_TX0_N")
	)
	(segment
		(start 46.106944 -1.022858)
		(end 45.358152 -1.77165)
		(width 0.096012)
		(layer "In7.Cu")
		(net "NFP_SERDES1_TX0_N")
	)
	(segment
		(start 13.59535 4.171848)
		(end 13.59535 6.076848)
		(width 0.096012)
		(layer "In7.Cu")
		(net "NFP_SERDES1_TX0_N")
	)
	(segment
		(start 46.106944 1.56337)
		(end 46.106944 -1.022858)
		(width 0.096012)
		(layer "In7.Cu")
		(net "NFP_SERDES1_TX0_N")
	)
	(segment
		(start 16.871848 3.94335)
		(end 13.823848 3.94335)
		(width 0.096012)
		(layer "In7.Cu")
		(net "NFP_SERDES1_TX0_N")
	)
	(segment
		(start 13.59535 6.076848)
		(end 13.188848 6.48335)
		(width 0.096012)
		(layer "In7.Cu")
		(net "NFP_SERDES1_TX0_N")
	)
	(segment
		(start 8.23595 7.75335)
		(end 7.7724 8.2169)
		(width 0.096012)
		(layer "In7.Cu")
		(net "NFP_SERDES1_TX0_N")
	)
	(segment
		(start 46.106944 1.589405)
		(end 46.106944 1.56337)
		(width 0.095758)
		(layer "In7.Cu")
		(net "NFP_SERDES1_TX0_N")
	)
	(segment
		(start 11.249431 6.48335)
		(end 11.153394 6.579387)
		(width 0.096012)
		(layer "In7.Cu")
		(net "NFP_SERDES1_TX0_N")
	)
	(segment
		(start 11.153394 7.504836)
		(end 10.90488 7.75335)
		(width 0.096012)
		(layer "In7.Cu")
		(net "NFP_SERDES1_TX0_N")
	)
	(segment
		(start 17.35963 -1.624432)
		(end 17.35963 3.455568)
		(width 0.096012)
		(layer "In7.Cu")
		(net "NFP_SERDES1_TX0_N")
	)
	(segment
		(start 10.90488 7.75335)
		(end 8.23595 7.75335)
		(width 0.096012)
		(layer "In7.Cu")
		(net "NFP_SERDES1_TX0_N")
	)
	(segment
		(start 13.188848 6.48335)
		(end 11.249431 6.48335)
		(width 0.096012)
		(layer "In7.Cu")
		(net "NFP_SERDES1_TX0_N")
	)
	(segment
		(start 11.153394 6.579387)
		(end 11.153394 7.504836)
		(width 0.096012)
		(layer "In7.Cu")
		(net "NFP_SERDES1_TX0_N")
	)
	(segment
		(start 17.506848 -1.77165)
		(end 17.35963 -1.624432)
		(width 0.096012)
		(layer "In7.Cu")
		(net "NFP_SERDES1_TX0_N")
	)
	(segment
		(start 46.130058 1.612519)
		(end 46.106944 1.589405)
		(width 0.095758)
		(layer "In7.Cu")
		(net "NFP_SERDES1_TX0_N")
	)
	(segment
		(start 13.823848 3.94335)
		(end 13.59535 4.171848)
		(width 0.096012)
		(layer "In7.Cu")
		(net "NFP_SERDES1_TX0_N")
	)
	(segment
		(start 45.358152 -1.77165)
		(end 17.506848 -1.77165)
		(width 0.096012)
		(layer "In7.Cu")
		(net "NFP_SERDES1_TX0_N")
	)
	(segment
		(start 46.736991 4.542003)
		(end 46.130058 3.93507)
		(width 0.095758)
		(layer "In7.Cu")
		(net "NFP_SERDES1_TX0_N")
	)
	(segment
		(start 46.130058 3.93507)
		(end 46.130058 1.612519)
		(width 0.095758)
		(layer "In7.Cu")
		(net "NFP_SERDES1_TX0_N")
	)
	(segment
		(start 44.236996 6.042)
		(end 43.736997 5.542001)
		(width 0.099314)
		(layer "F.Cu")
		(net "NFP_SERDES1_RX3_P")
	)
	(via
		(at 9.0424 25.9969)
		(size 0.508)
		(drill 0.254)
		(layers "F.Cu" "B.Cu")
		(net "NFP_SERDES1_RX3_P")
	)
	(via
		(at 43.736997 5.542001)
		(size 0.4826)
		(drill 0.20574)
		(layers "F.Cu" "B.Cu")
		(net "NFP_SERDES1_RX3_P")
	)
	(segment
		(start 9.6774 26.6319)
		(end 9.0424 25.9969)
		(width 0.099314)
		(layer "B.Cu")
		(net "NFP_SERDES1_RX3_P")
	)
	(segment
		(start 25.64765 11.669624)
		(end 23.45342 13.863853)
		(width 0.096012)
		(layer "In6.Cu")
		(net "NFP_SERDES1_RX3_P")
	)
	(segment
		(start 31.01086 6.83514)
		(end 30.23235 7.61365)
		(width 0.096012)
		(layer "In6.Cu")
		(net "NFP_SERDES1_RX3_P")
	)
	(segment
		(start 18.36674 21.09691)
		(end 17.144924 22.318726)
		(width 0.096012)
		(layer "In6.Cu")
		(net "NFP_SERDES1_RX3_P")
	)
	(segment
		(start 37.618721 5.800852)
		(end 37.473179 5.65531)
		(width 0.095758)
		(layer "In6.Cu")
		(net "NFP_SERDES1_RX3_P")
	)
	(segment
		(start 18.611875 19.615099)
		(end 18.611875 20.269606)
		(width 0.096012)
		(layer "In6.Cu")
		(net "NFP_SERDES1_RX3_P")
	)
	(segment
		(start 38.234671 5.800852)
		(end 37.618721 5.800852)
		(width 0.095758)
		(layer "In6.Cu")
		(net "NFP_SERDES1_RX3_P")
	)
	(segment
		(start 18.36674 20.514742)
		(end 18.36674 21.09691)
		(width 0.096012)
		(layer "In6.Cu")
		(net "NFP_SERDES1_RX3_P")
	)
	(segment
		(start 30.23235 7.61365)
		(end 27.451152 7.61365)
		(width 0.096012)
		(layer "In6.Cu")
		(net "NFP_SERDES1_RX3_P")
	)
	(segment
		(start 8.135849 25.746075)
		(end 8.93572 25.746075)
		(width 0.096012)
		(layer "In6.Cu")
		(net "NFP_SERDES1_RX3_P")
	)
	(segment
		(start 38.36863 5.934812)
		(end 38.234671 5.800852)
		(width 0.095758)
		(layer "In6.Cu")
		(net "NFP_SERDES1_RX3_P")
	)
	(segment
		(start 6.096 24.256924)
		(end 6.096 25.17079)
		(width 0.096012)
		(layer "In6.Cu")
		(net "NFP_SERDES1_RX3_P")
	)
	(segment
		(start 21.91131 14.931492)
		(end 21.91131 15.549042)
		(width 0.096012)
		(layer "In6.Cu")
		(net "NFP_SERDES1_RX3_P")
	)
	(segment
		(start 37.473179 5.65531)
		(end 37.017325 5.65531)
		(width 0.095758)
		(layer "In6.Cu")
		(net "NFP_SERDES1_RX3_P")
	)
	(segment
		(start 21.27631 16.950665)
		(end 18.611875 19.615099)
		(width 0.096012)
		(layer "In6.Cu")
		(net "NFP_SERDES1_RX3_P")
	)
	(segment
		(start 34.98469 5.65531)
		(end 33.80486 6.83514)
		(width 0.096012)
		(layer "In6.Cu")
		(net "NFP_SERDES1_RX3_P")
	)
	(segment
		(start 25.64765 9.417152)
		(end 25.64765 11.669624)
		(width 0.096012)
		(layer "In6.Cu")
		(net "NFP_SERDES1_RX3_P")
	)
	(segment
		(start 43.34825 5.930748)
		(end 42.9038 5.930748)
		(width 0.095758)
		(layer "In6.Cu")
		(net "NFP_SERDES1_RX3_P")
	)
	(segment
		(start 42.899736 5.934812)
		(end 38.36863 5.934812)
		(width 0.095758)
		(layer "In6.Cu")
		(net "NFP_SERDES1_RX3_P")
	)
	(segment
		(start 33.80486 6.83514)
		(end 31.01086 6.83514)
		(width 0.096012)
		(layer "In6.Cu")
		(net "NFP_SERDES1_RX3_P")
	)
	(segment
		(start 17.144924 23.622)
		(end 16.788232 23.978692)
		(width 0.096012)
		(layer "In6.Cu")
		(net "NFP_SERDES1_RX3_P")
	)
	(segment
		(start 17.144924 22.318726)
		(end 17.144924 23.622)
		(width 0.096012)
		(layer "In6.Cu")
		(net "NFP_SERDES1_RX3_P")
	)
	(segment
		(start 8.93572 25.746075)
		(end 9.0424 25.852755)
		(width 0.096012)
		(layer "In6.Cu")
		(net "NFP_SERDES1_RX3_P")
	)
	(segment
		(start 6.096 25.17079)
		(end 6.48777 25.56256)
		(width 0.096012)
		(layer "In6.Cu")
		(net "NFP_SERDES1_RX3_P")
	)
	(segment
		(start 9.0424 25.852755)
		(end 9.0424 25.9969)
		(width 0.096012)
		(layer "In6.Cu")
		(net "NFP_SERDES1_RX3_P")
	)
	(segment
		(start 18.611875 20.269606)
		(end 18.36674 20.514742)
		(width 0.096012)
		(layer "In6.Cu")
		(net "NFP_SERDES1_RX3_P")
	)
	(segment
		(start 21.91131 15.549042)
		(end 21.27631 16.184042)
		(width 0.096012)
		(layer "In6.Cu")
		(net "NFP_SERDES1_RX3_P")
	)
	(segment
		(start 23.248874 13.868476)
		(end 22.974325 13.868476)
		(width 0.096012)
		(layer "In6.Cu")
		(net "NFP_SERDES1_RX3_P")
	)
	(segment
		(start 43.736997 5.542001)
		(end 43.34825 5.930748)
		(width 0.095758)
		(layer "In6.Cu")
		(net "NFP_SERDES1_RX3_P")
	)
	(segment
		(start 7.952334 25.56256)
		(end 8.135849 25.746075)
		(width 0.096012)
		(layer "In6.Cu")
		(net "NFP_SERDES1_RX3_P")
	)
	(segment
		(start 37.017325 5.65531)
		(end 34.98469 5.65531)
		(width 0.096012)
		(layer "In6.Cu")
		(net "NFP_SERDES1_RX3_P")
	)
	(segment
		(start 6.48777 25.56256)
		(end 7.952334 25.56256)
		(width 0.096012)
		(layer "In6.Cu")
		(net "NFP_SERDES1_RX3_P")
	)
	(segment
		(start 16.788232 23.978692)
		(end 6.374232 23.978692)
		(width 0.096012)
		(layer "In6.Cu")
		(net "NFP_SERDES1_RX3_P")
	)
	(segment
		(start 6.374232 23.978692)
		(end 6.096 24.256924)
		(width 0.096012)
		(layer "In6.Cu")
		(net "NFP_SERDES1_RX3_P")
	)
	(segment
		(start 27.451152 7.61365)
		(end 25.64765 9.417152)
		(width 0.096012)
		(layer "In6.Cu")
		(net "NFP_SERDES1_RX3_P")
	)
	(segment
		(start 22.974325 13.868476)
		(end 21.91131 14.931492)
		(width 0.096012)
		(layer "In6.Cu")
		(net "NFP_SERDES1_RX3_P")
	)
	(segment
		(start 23.45342 13.863853)
		(end 23.253497 13.863853)
		(width 0.096012)
		(layer "In6.Cu")
		(net "NFP_SERDES1_RX3_P")
	)
	(segment
		(start 21.27631 16.184042)
		(end 21.27631 16.950665)
		(width 0.096012)
		(layer "In6.Cu")
		(net "NFP_SERDES1_RX3_P")
	)
	(segment
		(start 42.9038 5.930748)
		(end 42.899736 5.934812)
		(width 0.095758)
		(layer "In6.Cu")
		(net "NFP_SERDES1_RX3_P")
	)
	(segment
		(start 23.253497 13.863853)
		(end 23.248874 13.868476)
		(width 0.096012)
		(layer "In6.Cu")
		(net "NFP_SERDES1_RX3_P")
	)
	(segment
		(start 44.236996 7.041998)
		(end 43.736997 6.541999)
		(width 0.099314)
		(layer "F.Cu")
		(net "NFP_SERDES1_RX3_N")
	)
	(via
		(at 43.736997 6.541999)
		(size 0.4826)
		(drill 0.25654)
		(layers "F.Cu" "B.Cu")
		(net "NFP_SERDES1_RX3_N")
	)
	(via
		(at 9.0424 24.7269)
		(size 0.508)
		(drill 0.254)
		(layers "F.Cu" "B.Cu")
		(net "NFP_SERDES1_RX3_N")
	)
	(segment
		(start 9.6774 25.3619)
		(end 9.0424 24.7269)
		(width 0.099314)
		(layer "B.Cu")
		(net "NFP_SERDES1_RX3_N")
	)
	(segment
		(start 38.279934 6.148934)
		(end 38.145974 6.014974)
		(width 0.095758)
		(layer "In6.Cu")
		(net "NFP_SERDES1_RX3_N")
	)
	(segment
		(start 17.405274 23.729848)
		(end 16.89608 24.239042)
		(width 0.096012)
		(layer "In6.Cu")
		(net "NFP_SERDES1_RX3_N")
	)
	(segment
		(start 27.559 7.874)
		(end 25.908 9.525)
		(width 0.096012)
		(layer "In6.Cu")
		(net "NFP_SERDES1_RX3_N")
	)
	(segment
		(start 31.118708 7.09549)
		(end 30.340198 7.874)
		(width 0.096012)
		(layer "In6.Cu")
		(net "NFP_SERDES1_RX3_N")
	)
	(segment
		(start 9.05825 25.485725)
		(end 9.271 25.272975)
		(width 0.096012)
		(layer "In6.Cu")
		(net "NFP_SERDES1_RX3_N")
	)
	(segment
		(start 6.35635 25.062942)
		(end 6.595618 25.30221)
		(width 0.096012)
		(layer "In6.Cu")
		(net "NFP_SERDES1_RX3_N")
	)
	(segment
		(start 22.17166 15.03934)
		(end 22.17166 15.65689)
		(width 0.096012)
		(layer "In6.Cu")
		(net "NFP_SERDES1_RX3_N")
	)
	(segment
		(start 42.988433 6.148934)
		(end 38.279934 6.148934)
		(width 0.095758)
		(layer "In6.Cu")
		(net "NFP_SERDES1_RX3_N")
	)
	(segment
		(start 37.017325 5.91566)
		(end 35.092538 5.91566)
		(width 0.096012)
		(layer "In6.Cu")
		(net "NFP_SERDES1_RX3_N")
	)
	(segment
		(start 18.62709 21.204758)
		(end 17.405274 22.426574)
		(width 0.096012)
		(layer "In6.Cu")
		(net "NFP_SERDES1_RX3_N")
	)
	(segment
		(start 23.082174 14.128826)
		(end 22.17166 15.03934)
		(width 0.096012)
		(layer "In6.Cu")
		(net "NFP_SERDES1_RX3_N")
	)
	(segment
		(start 35.092538 5.91566)
		(end 33.912708 7.09549)
		(width 0.096012)
		(layer "In6.Cu")
		(net "NFP_SERDES1_RX3_N")
	)
	(segment
		(start 43.339868 6.14487)
		(end 42.992497 6.14487)
		(width 0.095758)
		(layer "In6.Cu")
		(net "NFP_SERDES1_RX3_N")
	)
	(segment
		(start 23.361345 14.124203)
		(end 23.356722 14.128826)
		(width 0.096012)
		(layer "In6.Cu")
		(net "NFP_SERDES1_RX3_N")
	)
	(segment
		(start 33.912708 7.09549)
		(end 31.118708 7.09549)
		(width 0.096012)
		(layer "In6.Cu")
		(net "NFP_SERDES1_RX3_N")
	)
	(segment
		(start 6.595618 25.30221)
		(end 8.060182 25.30221)
		(width 0.096012)
		(layer "In6.Cu")
		(net "NFP_SERDES1_RX3_N")
	)
	(segment
		(start 8.060182 25.30221)
		(end 8.243697 25.485725)
		(width 0.096012)
		(layer "In6.Cu")
		(net "NFP_SERDES1_RX3_N")
	)
	(segment
		(start 18.62709 20.62259)
		(end 18.62709 21.204758)
		(width 0.096012)
		(layer "In6.Cu")
		(net "NFP_SERDES1_RX3_N")
	)
	(segment
		(start 25.908 11.777472)
		(end 23.561269 14.124203)
		(width 0.096012)
		(layer "In6.Cu")
		(net "NFP_SERDES1_RX3_N")
	)
	(segment
		(start 18.872225 20.377455)
		(end 18.62709 20.62259)
		(width 0.096012)
		(layer "In6.Cu")
		(net "NFP_SERDES1_RX3_N")
	)
	(segment
		(start 30.340198 7.874)
		(end 27.559 7.874)
		(width 0.096012)
		(layer "In6.Cu")
		(net "NFP_SERDES1_RX3_N")
	)
	(segment
		(start 17.405274 22.426574)
		(end 17.405274 23.729848)
		(width 0.096012)
		(layer "In6.Cu")
		(net "NFP_SERDES1_RX3_N")
	)
	(segment
		(start 22.17166 15.65689)
		(end 21.53666 16.29189)
		(width 0.096012)
		(layer "In6.Cu")
		(net "NFP_SERDES1_RX3_N")
	)
	(segment
		(start 42.992497 6.14487)
		(end 42.988433 6.148934)
		(width 0.095758)
		(layer "In6.Cu")
		(net "NFP_SERDES1_RX3_N")
	)
	(segment
		(start 23.356722 14.128826)
		(end 23.082174 14.128826)
		(width 0.096012)
		(layer "In6.Cu")
		(net "NFP_SERDES1_RX3_N")
	)
	(segment
		(start 38.145974 6.014974)
		(end 37.465 6.014974)
		(width 0.095758)
		(layer "In6.Cu")
		(net "NFP_SERDES1_RX3_N")
	)
	(segment
		(start 21.53666 17.058513)
		(end 18.872225 19.722973)
		(width 0.096012)
		(layer "In6.Cu")
		(net "NFP_SERDES1_RX3_N")
	)
	(segment
		(start 43.736997 6.541999)
		(end 43.339868 6.14487)
		(width 0.095758)
		(layer "In6.Cu")
		(net "NFP_SERDES1_RX3_N")
	)
	(segment
		(start 37.365686 5.91566)
		(end 37.017325 5.91566)
		(width 0.095758)
		(layer "In6.Cu")
		(net "NFP_SERDES1_RX3_N")
	)
	(segment
		(start 23.561269 14.124203)
		(end 23.361345 14.124203)
		(width 0.096012)
		(layer "In6.Cu")
		(net "NFP_SERDES1_RX3_N")
	)
	(segment
		(start 21.53666 16.29189)
		(end 21.53666 17.058513)
		(width 0.096012)
		(layer "In6.Cu")
		(net "NFP_SERDES1_RX3_N")
	)
	(segment
		(start 9.271 25.272975)
		(end 9.271 24.9555)
		(width 0.096012)
		(layer "In6.Cu")
		(net "NFP_SERDES1_RX3_N")
	)
	(segment
		(start 9.271 24.9555)
		(end 9.0424 24.7269)
		(width 0.096012)
		(layer "In6.Cu")
		(net "NFP_SERDES1_RX3_N")
	)
	(segment
		(start 18.872225 19.722973)
		(end 18.872225 20.377455)
		(width 0.096012)
		(layer "In6.Cu")
		(net "NFP_SERDES1_RX3_N")
	)
	(segment
		(start 37.465 6.014974)
		(end 37.365686 5.91566)
		(width 0.095758)
		(layer "In6.Cu")
		(net "NFP_SERDES1_RX3_N")
	)
	(segment
		(start 6.48208 24.239042)
		(end 6.35635 24.364772)
		(width 0.096012)
		(layer "In6.Cu")
		(net "NFP_SERDES1_RX3_N")
	)
	(segment
		(start 16.89608 24.239042)
		(end 6.48208 24.239042)
		(width 0.096012)
		(layer "In6.Cu")
		(net "NFP_SERDES1_RX3_N")
	)
	(segment
		(start 25.908 9.525)
		(end 25.908 11.777472)
		(width 0.096012)
		(layer "In6.Cu")
		(net "NFP_SERDES1_RX3_N")
	)
	(segment
		(start 8.243697 25.485725)
		(end 9.05825 25.485725)
		(width 0.096012)
		(layer "In6.Cu")
		(net "NFP_SERDES1_RX3_N")
	)
	(segment
		(start 6.35635 24.364772)
		(end 6.35635 25.062942)
		(width 0.096012)
		(layer "In6.Cu")
		(net "NFP_SERDES1_RX3_N")
	)
	(segment
		(start 45.236994 7.041998)
		(end 44.736995 6.541999)
		(width 0.099314)
		(layer "F.Cu")
		(net "NFP_SERDES1_RX2_P")
	)
	(via
		(at 44.736995 6.541999)
		(size 0.4826)
		(drill 0.20574)
		(layers "F.Cu" "B.Cu")
		(net "NFP_SERDES1_RX2_P")
	)
	(via
		(at 7.7724 23.4569)
		(size 0.508)
		(drill 0.254)
		(layers "F.Cu" "B.Cu")
		(net "NFP_SERDES1_RX2_P")
	)
	(segment
		(start 8.4074 24.0919)
		(end 7.7724 23.4569)
		(width 0.099314)
		(layer "B.Cu")
		(net "NFP_SERDES1_RX2_P")
	)
	(segment
		(start 29.173043 6.851726)
		(end 27.070075 6.851726)
		(width 0.096012)
		(layer "In6.Cu")
		(net "NFP_SERDES1_RX2_P")
	)
	(segment
		(start 27.070075 6.851726)
		(end 25.345492 8.57631)
		(width 0.096012)
		(layer "In6.Cu")
		(net "NFP_SERDES1_RX2_P")
	)
	(segment
		(start 25.345492 8.57631)
		(end 24.477218 8.57631)
		(width 0.096012)
		(layer "In6.Cu")
		(net "NFP_SERDES1_RX2_P")
	)
	(segment
		(start 7.518349 23.241)
		(end 7.645349 23.368)
		(width 0.096012)
		(layer "In6.Cu")
		(net "NFP_SERDES1_RX2_P")
	)
	(segment
		(start 7.6835 23.368)
		(end 7.7724 23.4569)
		(width 0.096012)
		(layer "In6.Cu")
		(net "NFP_SERDES1_RX2_P")
	)
	(segment
		(start 16.73479 18.95221)
		(end 15.82674 19.86026)
		(width 0.096012)
		(layer "In6.Cu")
		(net "NFP_SERDES1_RX2_P")
	)
	(segment
		(start 44.736995 6.541999)
		(end 44.736995 6.571005)
		(width 0.096012)
		(layer "In6.Cu")
		(net "NFP_SERDES1_RX2_P")
	)
	(segment
		(start 20.64131 15.248103)
		(end 20.52828 15.361133)
		(width 0.096012)
		(layer "In6.Cu")
		(net "NFP_SERDES1_RX2_P")
	)
	(segment
		(start 23.68931 12.031218)
		(end 23.68931 12.570079)
		(width 0.096012)
		(layer "In6.Cu")
		(net "NFP_SERDES1_RX2_P")
	)
	(segment
		(start 37.798959 4.537659)
		(end 37.646534 4.385234)
		(width 0.096012)
		(layer "In6.Cu")
		(net "NFP_SERDES1_RX2_P")
	)
	(segment
		(start 34.705265 4.537735)
		(end 33.655 5.588)
		(width 0.096012)
		(layer "In6.Cu")
		(net "NFP_SERDES1_RX2_P")
	)
	(segment
		(start 38.182474 4.813122)
		(end 38.074422 4.813122)
		(width 0.095758)
		(layer "In6.Cu")
		(net "NFP_SERDES1_RX2_P")
	)
	(segment
		(start 20.52828 16.428695)
		(end 18.004765 18.95221)
		(width 0.096012)
		(layer "In6.Cu")
		(net "NFP_SERDES1_RX2_P")
	)
	(segment
		(start 24.003 11.717528)
		(end 23.68931 12.031218)
		(width 0.096012)
		(layer "In6.Cu")
		(net "NFP_SERDES1_RX2_P")
	)
	(segment
		(start 24.477218 8.57631)
		(end 24.003 9.050528)
		(width 0.096012)
		(layer "In6.Cu")
		(net "NFP_SERDES1_RX2_P")
	)
	(segment
		(start 23.143566 13.115823)
		(end 22.943642 13.115823)
		(width 0.096012)
		(layer "In6.Cu")
		(net "NFP_SERDES1_RX2_P")
	)
	(segment
		(start 15.460574 21.463)
		(end 6.616802 21.463)
		(width 0.096012)
		(layer "In6.Cu")
		(net "NFP_SERDES1_RX2_P")
	)
	(segment
		(start 15.82674 19.86026)
		(end 15.82674 21.096834)
		(width 0.096012)
		(layer "In6.Cu")
		(net "NFP_SERDES1_RX2_P")
	)
	(segment
		(start 44.402121 6.731)
		(end 44.344184 6.673063)
		(width 0.095758)
		(layer "In6.Cu")
		(net "NFP_SERDES1_RX2_P")
	)
	(segment
		(start 6.459855 23.241)
		(end 7.518349 23.241)
		(width 0.096012)
		(layer "In6.Cu")
		(net "NFP_SERDES1_RX2_P")
	)
	(segment
		(start 30.284268 5.740502)
		(end 29.173043 6.851726)
		(width 0.096012)
		(layer "In6.Cu")
		(net "NFP_SERDES1_RX2_P")
	)
	(segment
		(start 22.939019 13.120446)
		(end 22.600082 13.120446)
		(width 0.096012)
		(layer "In6.Cu")
		(net "NFP_SERDES1_RX2_P")
	)
	(segment
		(start 44.577 6.731)
		(end 44.402121 6.731)
		(width 0.095758)
		(layer "In6.Cu")
		(net "NFP_SERDES1_RX2_P")
	)
	(segment
		(start 38.304419 4.935068)
		(end 38.182474 4.813122)
		(width 0.095758)
		(layer "In6.Cu")
		(net "NFP_SERDES1_RX2_P")
	)
	(segment
		(start 30.284268 5.740425)
		(end 30.284268 5.740502)
		(width 0.096012)
		(layer "In6.Cu")
		(net "NFP_SERDES1_RX2_P")
	)
	(segment
		(start 6.096 21.983802)
		(end 6.096 22.877145)
		(width 0.096012)
		(layer "In6.Cu")
		(net "NFP_SERDES1_RX2_P")
	)
	(segment
		(start 33.655 5.588)
		(end 30.436693 5.588)
		(width 0.096012)
		(layer "In6.Cu")
		(net "NFP_SERDES1_RX2_P")
	)
	(segment
		(start 22.600082 13.120446)
		(end 20.64131 15.079218)
		(width 0.096012)
		(layer "In6.Cu")
		(net "NFP_SERDES1_RX2_P")
	)
	(segment
		(start 34.705265 4.537659)
		(end 34.705265 4.537735)
		(width 0.096012)
		(layer "In6.Cu")
		(net "NFP_SERDES1_RX2_P")
	)
	(segment
		(start 18.004765 18.95221)
		(end 16.73479 18.95221)
		(width 0.096012)
		(layer "In6.Cu")
		(net "NFP_SERDES1_RX2_P")
	)
	(segment
		(start 20.64131 15.079218)
		(end 20.64131 15.248103)
		(width 0.096012)
		(layer "In6.Cu")
		(net "NFP_SERDES1_RX2_P")
	)
	(segment
		(start 6.616802 21.463)
		(end 6.096 21.983802)
		(width 0.096012)
		(layer "In6.Cu")
		(net "NFP_SERDES1_RX2_P")
	)
	(segment
		(start 38.074422 4.813122)
		(end 37.798959 4.537659)
		(width 0.095758)
		(layer "In6.Cu")
		(net "NFP_SERDES1_RX2_P")
	)
	(segment
		(start 20.52828 15.361133)
		(end 20.52828 16.428695)
		(width 0.096012)
		(layer "In6.Cu")
		(net "NFP_SERDES1_RX2_P")
	)
	(segment
		(start 7.645349 23.368)
		(end 7.6835 23.368)
		(width 0.096012)
		(layer "In6.Cu")
		(net "NFP_SERDES1_RX2_P")
	)
	(segment
		(start 44.344184 6.673063)
		(end 44.344184 5.202123)
		(width 0.095758)
		(layer "In6.Cu")
		(net "NFP_SERDES1_RX2_P")
	)
	(segment
		(start 23.68931 12.570079)
		(end 23.143566 13.115823)
		(width 0.096012)
		(layer "In6.Cu")
		(net "NFP_SERDES1_RX2_P")
	)
	(segment
		(start 44.736995 6.571005)
		(end 44.577 6.731)
		(width 0.096012)
		(layer "In6.Cu")
		(net "NFP_SERDES1_RX2_P")
	)
	(segment
		(start 44.344184 5.202123)
		(end 44.077128 4.935068)
		(width 0.095758)
		(layer "In6.Cu")
		(net "NFP_SERDES1_RX2_P")
	)
	(segment
		(start 44.077128 4.935068)
		(end 38.304419 4.935068)
		(width 0.095758)
		(layer "In6.Cu")
		(net "NFP_SERDES1_RX2_P")
	)
	(segment
		(start 22.943642 13.115823)
		(end 22.939019 13.120446)
		(width 0.096012)
		(layer "In6.Cu")
		(net "NFP_SERDES1_RX2_P")
	)
	(segment
		(start 6.096 22.877145)
		(end 6.459855 23.241)
		(width 0.096012)
		(layer "In6.Cu")
		(net "NFP_SERDES1_RX2_P")
	)
	(segment
		(start 34.85769 4.385234)
		(end 34.705265 4.537659)
		(width 0.096012)
		(layer "In6.Cu")
		(net "NFP_SERDES1_RX2_P")
	)
	(segment
		(start 30.436693 5.588)
		(end 30.284268 5.740425)
		(width 0.096012)
		(layer "In6.Cu")
		(net "NFP_SERDES1_RX2_P")
	)
	(segment
		(start 37.646534 4.385234)
		(end 34.85769 4.385234)
		(width 0.096012)
		(layer "In6.Cu")
		(net "NFP_SERDES1_RX2_P")
	)
	(segment
		(start 15.82674 21.096834)
		(end 15.460574 21.463)
		(width 0.096012)
		(layer "In6.Cu")
		(net "NFP_SERDES1_RX2_P")
	)
	(segment
		(start 24.003 9.050528)
		(end 24.003 11.717528)
		(width 0.096012)
		(layer "In6.Cu")
		(net "NFP_SERDES1_RX2_P")
	)
	(segment
		(start 45.236994 8.041996)
		(end 44.736995 7.541997)
		(width 0.099314)
		(layer "F.Cu")
		(net "NFP_SERDES1_RX2_N")
	)
	(via
		(at 7.7724 22.1869)
		(size 0.508)
		(drill 0.254)
		(layers "F.Cu" "B.Cu")
		(net "NFP_SERDES1_RX2_N")
	)
	(via
		(at 44.736995 7.541997)
		(size 0.4826)
		(drill 0.25654)
		(layers "F.Cu" "B.Cu")
		(net "NFP_SERDES1_RX2_N")
	)
	(segment
		(start 8.4074 22.8219)
		(end 7.7724 22.1869)
		(width 0.099314)
		(layer "B.Cu")
		(net "NFP_SERDES1_RX2_N")
	)
	(segment
		(start 23.251414 13.376173)
		(end 23.051491 13.376173)
		(width 0.096012)
		(layer "In6.Cu")
		(net "NFP_SERDES1_RX2_N")
	)
	(segment
		(start 20.90166 15.187066)
		(end 20.90166 15.355951)
		(width 0.096012)
		(layer "In6.Cu")
		(net "NFP_SERDES1_RX2_N")
	)
	(segment
		(start 38.093777 5.027244)
		(end 37.920651 5.027244)
		(width 0.095758)
		(layer "In6.Cu")
		(net "NFP_SERDES1_RX2_N")
	)
	(segment
		(start 24.26335 11.825376)
		(end 23.94966 12.139066)
		(width 0.096012)
		(layer "In6.Cu")
		(net "NFP_SERDES1_RX2_N")
	)
	(segment
		(start 23.051491 13.376173)
		(end 23.046868 13.380796)
		(width 0.096012)
		(layer "In6.Cu")
		(net "NFP_SERDES1_RX2_N")
	)
	(segment
		(start 15.568422 21.72335)
		(end 6.72465 21.72335)
		(width 0.096012)
		(layer "In6.Cu")
		(net "NFP_SERDES1_RX2_N")
	)
	(segment
		(start 20.78863 15.468981)
		(end 20.78863 16.536543)
		(width 0.096012)
		(layer "In6.Cu")
		(net "NFP_SERDES1_RX2_N")
	)
	(segment
		(start 37.538685 4.645584)
		(end 34.965615 4.645584)
		(width 0.096012)
		(layer "In6.Cu")
		(net "NFP_SERDES1_RX2_N")
	)
	(segment
		(start 20.78863 16.536543)
		(end 18.112613 19.21256)
		(width 0.096012)
		(layer "In6.Cu")
		(net "NFP_SERDES1_RX2_N")
	)
	(segment
		(start 38.530759 5.14919)
		(end 38.450672 5.229276)
		(width 0.095758)
		(layer "In6.Cu")
		(net "NFP_SERDES1_RX2_N")
	)
	(segment
		(start 6.35635 22.09165)
		(end 6.35635 22.769297)
		(width 0.096012)
		(layer "In6.Cu")
		(net "NFP_SERDES1_RX2_N")
	)
	(segment
		(start 34.965615 4.645584)
		(end 33.762848 5.84835)
		(width 0.096012)
		(layer "In6.Cu")
		(net "NFP_SERDES1_RX2_N")
	)
	(segment
		(start 38.450672 5.229276)
		(end 38.295809 5.229276)
		(width 0.095758)
		(layer "In6.Cu")
		(net "NFP_SERDES1_RX2_N")
	)
	(segment
		(start 16.08709 21.204682)
		(end 15.568422 21.72335)
		(width 0.096012)
		(layer "In6.Cu")
		(net "NFP_SERDES1_RX2_N")
	)
	(segment
		(start 43.988431 5.14919)
		(end 38.530759 5.14919)
		(width 0.095758)
		(layer "In6.Cu")
		(net "NFP_SERDES1_RX2_N")
	)
	(segment
		(start 27.177924 7.112076)
		(end 25.45334 8.83666)
		(width 0.096012)
		(layer "In6.Cu")
		(net "NFP_SERDES1_RX2_N")
	)
	(segment
		(start 23.94966 12.139066)
		(end 23.94966 12.677927)
		(width 0.096012)
		(layer "In6.Cu")
		(net "NFP_SERDES1_RX2_N")
	)
	(segment
		(start 37.631802 4.7387)
		(end 37.61486 4.721758)
		(width 0.095758)
		(layer "In6.Cu")
		(net "NFP_SERDES1_RX2_N")
	)
	(segment
		(start 44.736995 7.541997)
		(end 44.130062 6.935064)
		(width 0.095758)
		(layer "In6.Cu")
		(net "NFP_SERDES1_RX2_N")
	)
	(segment
		(start 16.08709 19.968108)
		(end 16.08709 21.204682)
		(width 0.096012)
		(layer "In6.Cu")
		(net "NFP_SERDES1_RX2_N")
	)
	(segment
		(start 44.130062 5.29082)
		(end 43.988431 5.14919)
		(width 0.095758)
		(layer "In6.Cu")
		(net "NFP_SERDES1_RX2_N")
	)
	(segment
		(start 37.61486 4.721758)
		(end 37.538685 4.645584)
		(width 0.096012)
		(layer "In6.Cu")
		(net "NFP_SERDES1_RX2_N")
	)
	(segment
		(start 6.35635 22.769297)
		(end 6.567703 22.98065)
		(width 0.096012)
		(layer "In6.Cu")
		(net "NFP_SERDES1_RX2_N")
	)
	(segment
		(start 30.544618 5.84835)
		(end 29.280891 7.112076)
		(width 0.096012)
		(layer "In6.Cu")
		(net "NFP_SERDES1_RX2_N")
	)
	(segment
		(start 33.762848 5.84835)
		(end 30.544618 5.84835)
		(width 0.096012)
		(layer "In6.Cu")
		(net "NFP_SERDES1_RX2_N")
	)
	(segment
		(start 7.49935 22.98065)
		(end 7.7724 22.7076)
		(width 0.096012)
		(layer "In6.Cu")
		(net "NFP_SERDES1_RX2_N")
	)
	(segment
		(start 24.585066 8.83666)
		(end 24.26335 9.158376)
		(width 0.096012)
		(layer "In6.Cu")
		(net "NFP_SERDES1_RX2_N")
	)
	(segment
		(start 38.295809 5.229276)
		(end 38.093777 5.027244)
		(width 0.095758)
		(layer "In6.Cu")
		(net "NFP_SERDES1_RX2_N")
	)
	(segment
		(start 29.280891 7.112076)
		(end 27.177924 7.112076)
		(width 0.096012)
		(layer "In6.Cu")
		(net "NFP_SERDES1_RX2_N")
	)
	(segment
		(start 7.7724 22.7076)
		(end 7.7724 22.1869)
		(width 0.096012)
		(layer "In6.Cu")
		(net "NFP_SERDES1_RX2_N")
	)
	(segment
		(start 44.130062 6.935064)
		(end 44.130062 5.29082)
		(width 0.095758)
		(layer "In6.Cu")
		(net "NFP_SERDES1_RX2_N")
	)
	(segment
		(start 37.920651 5.027244)
		(end 37.632056 4.7387)
		(width 0.095758)
		(layer "In6.Cu")
		(net "NFP_SERDES1_RX2_N")
	)
	(segment
		(start 23.046868 13.380796)
		(end 22.70793 13.380796)
		(width 0.096012)
		(layer "In6.Cu")
		(net "NFP_SERDES1_RX2_N")
	)
	(segment
		(start 6.72465 21.72335)
		(end 6.35635 22.09165)
		(width 0.096012)
		(layer "In6.Cu")
		(net "NFP_SERDES1_RX2_N")
	)
	(segment
		(start 24.26335 9.158376)
		(end 24.26335 11.825376)
		(width 0.096012)
		(layer "In6.Cu")
		(net "NFP_SERDES1_RX2_N")
	)
	(segment
		(start 22.70793 13.380796)
		(end 20.90166 15.187066)
		(width 0.096012)
		(layer "In6.Cu")
		(net "NFP_SERDES1_RX2_N")
	)
	(segment
		(start 18.112613 19.21256)
		(end 16.842638 19.21256)
		(width 0.096012)
		(layer "In6.Cu")
		(net "NFP_SERDES1_RX2_N")
	)
	(segment
		(start 37.632056 4.7387)
		(end 37.631802 4.7387)
		(width 0.095758)
		(layer "In6.Cu")
		(net "NFP_SERDES1_RX2_N")
	)
	(segment
		(start 6.567703 22.98065)
		(end 7.49935 22.98065)
		(width 0.096012)
		(layer "In6.Cu")
		(net "NFP_SERDES1_RX2_N")
	)
	(segment
		(start 23.94966 12.677927)
		(end 23.251414 13.376173)
		(width 0.096012)
		(layer "In6.Cu")
		(net "NFP_SERDES1_RX2_N")
	)
	(segment
		(start 25.45334 8.83666)
		(end 24.585066 8.83666)
		(width 0.096012)
		(layer "In6.Cu")
		(net "NFP_SERDES1_RX2_N")
	)
	(segment
		(start 16.842638 19.21256)
		(end 16.08709 19.968108)
		(width 0.096012)
		(layer "In6.Cu")
		(net "NFP_SERDES1_RX2_N")
	)
	(segment
		(start 20.90166 15.355951)
		(end 20.78863 15.468981)
		(width 0.096012)
		(layer "In6.Cu")
		(net "NFP_SERDES1_RX2_N")
	)
	(segment
		(start 46.236992 6.042)
		(end 45.736993 5.542001)
		(width 0.099314)
		(layer "F.Cu")
		(net "NFP_SERDES1_RX1_P")
	)
	(via
		(at 9.0424 20.9169)
		(size 0.508)
		(drill 0.254)
		(layers "F.Cu" "B.Cu")
		(net "NFP_SERDES1_RX1_P")
	)
	(via
		(at 45.736993 5.542001)
		(size 0.4826)
		(drill 0.20574)
		(layers "F.Cu" "B.Cu")
		(net "NFP_SERDES1_RX1_P")
	)
	(segment
		(start 9.6774 21.5519)
		(end 9.0424 20.9169)
		(width 0.099314)
		(layer "B.Cu")
		(net "NFP_SERDES1_RX1_P")
	)
	(segment
		(start 38.164897 3.683)
		(end 38.151867 3.683)
		(width 0.095758)
		(layer "In6.Cu")
		(net "NFP_SERDES1_RX1_P")
	)
	(segment
		(start 14.986 17.792802)
		(end 14.986 18.161)
		(width 0.096012)
		(layer "In6.Cu")
		(net "NFP_SERDES1_RX1_P")
	)
	(segment
		(start 22.733 8.817686)
		(end 22.733 12.098528)
		(width 0.096012)
		(layer "In6.Cu")
		(net "NFP_SERDES1_RX1_P")
	)
	(segment
		(start 8.92175 20.79625)
		(end 9.0424 20.9169)
		(width 0.096012)
		(layer "In6.Cu")
		(net "NFP_SERDES1_RX1_P")
	)
	(segment
		(start 45.736993 5.610123)
		(end 45.632853 5.714263)
		(width 0.095758)
		(layer "In6.Cu")
		(net "NFP_SERDES1_RX1_P")
	)
	(segment
		(start 45.367042 1.806042)
		(end 45.085 1.524)
		(width 0.096012)
		(layer "In6.Cu")
		(net "NFP_SERDES1_RX1_P")
	)
	(segment
		(start 34.348445 3.637356)
		(end 33.651292 4.33451)
		(width 0.096012)
		(layer "In6.Cu")
		(net "NFP_SERDES1_RX1_P")
	)
	(segment
		(start 23.722406 7.82828)
		(end 22.733 8.817686)
		(width 0.096012)
		(layer "In6.Cu")
		(net "NFP_SERDES1_RX1_P")
	)
	(segment
		(start 38.127864 3.683)
		(end 38.08222 3.637356)
		(width 0.096012)
		(layer "In6.Cu")
		(net "NFP_SERDES1_RX1_P")
	)
	(segment
		(start 45.367042 1.924685)
		(end 45.367042 1.806042)
		(width 0.096012)
		(layer "In6.Cu")
		(net "NFP_SERDES1_RX1_P")
	)
	(segment
		(start 8.655152 18.91665)
		(end 8.24865 19.323152)
		(width 0.096012)
		(layer "In6.Cu")
		(net "NFP_SERDES1_RX1_P")
	)
	(segment
		(start 8.638007 20.79625)
		(end 8.92175 20.79625)
		(width 0.096012)
		(layer "In6.Cu")
		(net "NFP_SERDES1_RX1_P")
	)
	(segment
		(start 22.448444 12.383084)
		(end 22.294647 12.383084)
		(width 0.096012)
		(layer "In6.Cu")
		(net "NFP_SERDES1_RX1_P")
	)
	(segment
		(start 45.343928 5.614314)
		(end 45.343928 1.973834)
		(width 0.095758)
		(layer "In6.Cu")
		(net "NFP_SERDES1_RX1_P")
	)
	(segment
		(start 8.24865 19.323152)
		(end 8.24865 20.406893)
		(width 0.096012)
		(layer "In6.Cu")
		(net "NFP_SERDES1_RX1_P")
	)
	(segment
		(start 45.367042 1.95072)
		(end 45.367042 1.924685)
		(width 0.095758)
		(layer "In6.Cu")
		(net "NFP_SERDES1_RX1_P")
	)
	(segment
		(start 31.695161 4.33451)
		(end 31.337021 4.69265)
		(width 0.096012)
		(layer "In6.Cu")
		(net "NFP_SERDES1_RX1_P")
	)
	(segment
		(start 19.903948 14.92758)
		(end 18.560288 16.27124)
		(width 0.096012)
		(layer "In6.Cu")
		(net "NFP_SERDES1_RX1_P")
	)
	(segment
		(start 45.343928 1.973834)
		(end 45.367042 1.95072)
		(width 0.095758)
		(layer "In6.Cu")
		(net "NFP_SERDES1_RX1_P")
	)
	(segment
		(start 14.23035 18.91665)
		(end 8.655152 18.91665)
		(width 0.096012)
		(layer "In6.Cu")
		(net "NFP_SERDES1_RX1_P")
	)
	(segment
		(start 39.751 1.524)
		(end 39.078383 2.196617)
		(width 0.096012)
		(layer "In6.Cu")
		(net "NFP_SERDES1_RX1_P")
	)
	(segment
		(start 39.078383 2.196617)
		(end 39.078383 2.54)
		(width 0.096012)
		(layer "In6.Cu")
		(net "NFP_SERDES1_RX1_P")
	)
	(segment
		(start 39.129843 3.704692)
		(end 38.899643 3.934892)
		(width 0.095758)
		(layer "In6.Cu")
		(net "NFP_SERDES1_RX1_P")
	)
	(segment
		(start 45.443877 5.714263)
		(end 45.343928 5.614314)
		(width 0.095758)
		(layer "In6.Cu")
		(net "NFP_SERDES1_RX1_P")
	)
	(segment
		(start 38.214681 3.732784)
		(end 38.164897 3.683)
		(width 0.095758)
		(layer "In6.Cu")
		(net "NFP_SERDES1_RX1_P")
	)
	(segment
		(start 39.078383 2.55303)
		(end 39.129843 2.604491)
		(width 0.095758)
		(layer "In6.Cu")
		(net "NFP_SERDES1_RX1_P")
	)
	(segment
		(start 22.733 12.098528)
		(end 22.448444 12.383084)
		(width 0.096012)
		(layer "In6.Cu")
		(net "NFP_SERDES1_RX1_P")
	)
	(segment
		(start 26.760272 6.103645)
		(end 25.035637 7.82828)
		(width 0.096012)
		(layer "In6.Cu")
		(net "NFP_SERDES1_RX1_P")
	)
	(segment
		(start 16.507562 16.27124)
		(end 14.986 17.792802)
		(width 0.096012)
		(layer "In6.Cu")
		(net "NFP_SERDES1_RX1_P")
	)
	(segment
		(start 30.274235 4.69265)
		(end 28.863239 6.103645)
		(width 0.096012)
		(layer "In6.Cu")
		(net "NFP_SERDES1_RX1_P")
	)
	(segment
		(start 39.078383 2.54)
		(end 39.078383 2.55303)
		(width 0.095758)
		(layer "In6.Cu")
		(net "NFP_SERDES1_RX1_P")
	)
	(segment
		(start 8.24865 20.406893)
		(end 8.638007 20.79625)
		(width 0.096012)
		(layer "In6.Cu")
		(net "NFP_SERDES1_RX1_P")
	)
	(segment
		(start 38.240005 3.732784)
		(end 38.214681 3.732784)
		(width 0.095758)
		(layer "In6.Cu")
		(net "NFP_SERDES1_RX1_P")
	)
	(segment
		(start 14.986 18.161)
		(end 14.23035 18.91665)
		(width 0.096012)
		(layer "In6.Cu")
		(net "NFP_SERDES1_RX1_P")
	)
	(segment
		(start 28.863239 6.103645)
		(end 26.760272 6.103645)
		(width 0.096012)
		(layer "In6.Cu")
		(net "NFP_SERDES1_RX1_P")
	)
	(segment
		(start 38.899643 3.934892)
		(end 38.442113 3.934892)
		(width 0.095758)
		(layer "In6.Cu")
		(net "NFP_SERDES1_RX1_P")
	)
	(segment
		(start 45.085 1.524)
		(end 39.751 1.524)
		(width 0.096012)
		(layer "In6.Cu")
		(net "NFP_SERDES1_RX1_P")
	)
	(segment
		(start 33.651292 4.33451)
		(end 31.695161 4.33451)
		(width 0.096012)
		(layer "In6.Cu")
		(net "NFP_SERDES1_RX1_P")
	)
	(segment
		(start 45.632853 5.714263)
		(end 45.443877 5.714263)
		(width 0.095758)
		(layer "In6.Cu")
		(net "NFP_SERDES1_RX1_P")
	)
	(segment
		(start 38.442113 3.934892)
		(end 38.240005 3.732784)
		(width 0.095758)
		(layer "In6.Cu")
		(net "NFP_SERDES1_RX1_P")
	)
	(segment
		(start 25.035637 7.82828)
		(end 23.722406 7.82828)
		(width 0.096012)
		(layer "In6.Cu")
		(net "NFP_SERDES1_RX1_P")
	)
	(segment
		(start 38.08222 3.637356)
		(end 34.348445 3.637356)
		(width 0.096012)
		(layer "In6.Cu")
		(net "NFP_SERDES1_RX1_P")
	)
	(segment
		(start 45.736993 5.542001)
		(end 45.736993 5.610123)
		(width 0.095758)
		(layer "In6.Cu")
		(net "NFP_SERDES1_RX1_P")
	)
	(segment
		(start 18.560288 16.27124)
		(end 16.507562 16.27124)
		(width 0.096012)
		(layer "In6.Cu")
		(net "NFP_SERDES1_RX1_P")
	)
	(segment
		(start 22.294647 12.383084)
		(end 19.903948 14.773783)
		(width 0.096012)
		(layer "In6.Cu")
		(net "NFP_SERDES1_RX1_P")
	)
	(segment
		(start 31.337021 4.69265)
		(end 30.274235 4.69265)
		(width 0.096012)
		(layer "In6.Cu")
		(net "NFP_SERDES1_RX1_P")
	)
	(segment
		(start 39.129843 2.604491)
		(end 39.129843 3.704692)
		(width 0.095758)
		(layer "In6.Cu")
		(net "NFP_SERDES1_RX1_P")
	)
	(segment
		(start 19.903948 14.773783)
		(end 19.903948 14.92758)
		(width 0.096012)
		(layer "In6.Cu")
		(net "NFP_SERDES1_RX1_P")
	)
	(segment
		(start 38.151867 3.683)
		(end 38.127864 3.683)
		(width 0.096012)
		(layer "In6.Cu")
		(net "NFP_SERDES1_RX1_P")
	)
	(segment
		(start 46.236992 7.041998)
		(end 45.736993 6.541999)
		(width 0.099314)
		(layer "F.Cu")
		(net "NFP_SERDES1_RX1_N")
	)
	(via
		(at 45.736993 6.541999)
		(size 0.4826)
		(drill 0.25654)
		(layers "F.Cu" "B.Cu")
		(net "NFP_SERDES1_RX1_N")
	)
	(via
		(at 9.0424 19.6469)
		(size 0.508)
		(drill 0.254)
		(layers "F.Cu" "B.Cu")
		(net "NFP_SERDES1_RX1_N")
	)
	(segment
		(start 9.6774 20.2819)
		(end 9.0424 19.6469)
		(width 0.099314)
		(layer "B.Cu")
		(net "NFP_SERDES1_RX1_N")
	)
	(segment
		(start 45.106692 1.924685)
		(end 45.106692 1.91389)
		(width 0.096012)
		(layer "In6.Cu")
		(net "NFP_SERDES1_RX1_N")
	)
	(segment
		(start 38.151867 3.946906)
		(end 38.13142 3.946906)
		(width 0.096012)
		(layer "In6.Cu")
		(net "NFP_SERDES1_RX1_N")
	)
	(segment
		(start 45.106692 1.91389)
		(end 44.977152 1.78435)
		(width 0.096012)
		(layer "In6.Cu")
		(net "NFP_SERDES1_RX1_N")
	)
	(segment
		(start 39.343965 2.545232)
		(end 39.343965 3.793439)
		(width 0.095758)
		(layer "In6.Cu")
		(net "NFP_SERDES1_RX1_N")
	)
	(segment
		(start 15.24635 18.268848)
		(end 14.338198 19.177)
		(width 0.096012)
		(layer "In6.Cu")
		(net "NFP_SERDES1_RX1_N")
	)
	(segment
		(start 15.24635 17.90065)
		(end 15.24635 18.268848)
		(width 0.096012)
		(layer "In6.Cu")
		(net "NFP_SERDES1_RX1_N")
	)
	(segment
		(start 9.09066 20.043902)
		(end 9.16432 19.970242)
		(width 0.096012)
		(layer "In6.Cu")
		(net "NFP_SERDES1_RX1_N")
	)
	(segment
		(start 8.981415 20.48256)
		(end 9.09066 20.373315)
		(width 0.096012)
		(layer "In6.Cu")
		(net "NFP_SERDES1_RX1_N")
	)
	(segment
		(start 16.61541 16.53159)
		(end 15.24635 17.90065)
		(width 0.096012)
		(layer "In6.Cu")
		(net "NFP_SERDES1_RX1_N")
	)
	(segment
		(start 31.80301 4.59486)
		(end 31.44487 4.953)
		(width 0.096012)
		(layer "In6.Cu")
		(net "NFP_SERDES1_RX1_N")
	)
	(segment
		(start 39.343965 3.793439)
		(end 38.98839 4.149014)
		(width 0.095758)
		(layer "In6.Cu")
		(net "NFP_SERDES1_RX1_N")
	)
	(segment
		(start 33.75914 4.59486)
		(end 31.80301 4.59486)
		(width 0.096012)
		(layer "In6.Cu")
		(net "NFP_SERDES1_RX1_N")
	)
	(segment
		(start 22.556292 12.643434)
		(end 22.402495 12.643434)
		(width 0.096012)
		(layer "In6.Cu")
		(net "NFP_SERDES1_RX1_N")
	)
	(segment
		(start 28.971062 6.364021)
		(end 26.868095 6.364021)
		(width 0.096012)
		(layer "In6.Cu")
		(net "NFP_SERDES1_RX1_N")
	)
	(segment
		(start 18.668136 16.53159)
		(end 16.61541 16.53159)
		(width 0.096012)
		(layer "In6.Cu")
		(net "NFP_SERDES1_RX1_N")
	)
	(segment
		(start 23.830255 8.08863)
		(end 22.99335 8.925535)
		(width 0.096012)
		(layer "In6.Cu")
		(net "NFP_SERDES1_RX1_N")
	)
	(segment
		(start 20.164298 14.881631)
		(end 20.164298 15.035428)
		(width 0.096012)
		(layer "In6.Cu")
		(net "NFP_SERDES1_RX1_N")
	)
	(segment
		(start 26.868095 6.364021)
		(end 25.143485 8.08863)
		(width 0.096012)
		(layer "In6.Cu")
		(net "NFP_SERDES1_RX1_N")
	)
	(segment
		(start 25.143485 8.08863)
		(end 23.830255 8.08863)
		(width 0.096012)
		(layer "In6.Cu")
		(net "NFP_SERDES1_RX1_N")
	)
	(segment
		(start 14.338198 19.177)
		(end 8.763 19.177)
		(width 0.096012)
		(layer "In6.Cu")
		(net "NFP_SERDES1_RX1_N")
	)
	(segment
		(start 20.164298 15.035428)
		(end 18.668136 16.53159)
		(width 0.096012)
		(layer "In6.Cu")
		(net "NFP_SERDES1_RX1_N")
	)
	(segment
		(start 8.856955 20.488072)
		(end 8.862466 20.48256)
		(width 0.096012)
		(layer "In6.Cu")
		(net "NFP_SERDES1_RX1_N")
	)
	(segment
		(start 31.44487 4.953)
		(end 30.382083 4.953)
		(width 0.096012)
		(layer "In6.Cu")
		(net "NFP_SERDES1_RX1_N")
	)
	(segment
		(start 30.382083 4.953)
		(end 28.971062 6.364021)
		(width 0.096012)
		(layer "In6.Cu")
		(net "NFP_SERDES1_RX1_N")
	)
	(segment
		(start 39.338733 2.54)
		(end 39.343965 2.545232)
		(width 0.095758)
		(layer "In6.Cu")
		(net "NFP_SERDES1_RX1_N")
	)
	(segment
		(start 22.99335 8.925535)
		(end 22.99335 12.206376)
		(width 0.096012)
		(layer "In6.Cu")
		(net "NFP_SERDES1_RX1_N")
	)
	(segment
		(start 22.402495 12.643434)
		(end 20.164298 14.881631)
		(width 0.096012)
		(layer "In6.Cu")
		(net "NFP_SERDES1_RX1_N")
	)
	(segment
		(start 38.98839 4.149014)
		(end 38.377901 4.149014)
		(width 0.095758)
		(layer "In6.Cu")
		(net "NFP_SERDES1_RX1_N")
	)
	(segment
		(start 22.99335 12.206376)
		(end 22.556292 12.643434)
		(width 0.096012)
		(layer "In6.Cu")
		(net "NFP_SERDES1_RX1_N")
	)
	(segment
		(start 45.129806 1.973834)
		(end 45.106692 1.95072)
		(width 0.095758)
		(layer "In6.Cu")
		(net "NFP_SERDES1_RX1_N")
	)
	(segment
		(start 45.129806 5.934812)
		(end 45.129806 1.973834)
		(width 0.095758)
		(layer "In6.Cu")
		(net "NFP_SERDES1_RX1_N")
	)
	(segment
		(start 8.862466 20.48256)
		(end 8.981415 20.48256)
		(width 0.096012)
		(layer "In6.Cu")
		(net "NFP_SERDES1_RX1_N")
	)
	(segment
		(start 38.377901 4.149014)
		(end 38.175794 3.946906)
		(width 0.095758)
		(layer "In6.Cu")
		(net "NFP_SERDES1_RX1_N")
	)
	(segment
		(start 38.175794 3.946906)
		(end 38.151867 3.946906)
		(width 0.095758)
		(layer "In6.Cu")
		(net "NFP_SERDES1_RX1_N")
	)
	(segment
		(start 8.509 19.431)
		(end 8.509 20.299045)
		(width 0.096012)
		(layer "In6.Cu")
		(net "NFP_SERDES1_RX1_N")
	)
	(segment
		(start 8.509 20.299045)
		(end 8.698027 20.488072)
		(width 0.096012)
		(layer "In6.Cu")
		(net "NFP_SERDES1_RX1_N")
	)
	(segment
		(start 38.08222 3.897706)
		(end 34.456294 3.897706)
		(width 0.096012)
		(layer "In6.Cu")
		(net "NFP_SERDES1_RX1_N")
	)
	(segment
		(start 45.106692 1.95072)
		(end 45.106692 1.924685)
		(width 0.095758)
		(layer "In6.Cu")
		(net "NFP_SERDES1_RX1_N")
	)
	(segment
		(start 9.16432 19.970242)
		(end 9.16432 19.76882)
		(width 0.096012)
		(layer "In6.Cu")
		(net "NFP_SERDES1_RX1_N")
	)
	(segment
		(start 39.858848 1.78435)
		(end 39.338733 2.304466)
		(width 0.096012)
		(layer "In6.Cu")
		(net "NFP_SERDES1_RX1_N")
	)
	(segment
		(start 8.698027 20.488072)
		(end 8.856955 20.488072)
		(width 0.096012)
		(layer "In6.Cu")
		(net "NFP_SERDES1_RX1_N")
	)
	(segment
		(start 9.16432 19.76882)
		(end 9.0424 19.6469)
		(width 0.096012)
		(layer "In6.Cu")
		(net "NFP_SERDES1_RX1_N")
	)
	(segment
		(start 9.09066 20.373315)
		(end 9.09066 20.043902)
		(width 0.096012)
		(layer "In6.Cu")
		(net "NFP_SERDES1_RX1_N")
	)
	(segment
		(start 44.977152 1.78435)
		(end 39.858848 1.78435)
		(width 0.096012)
		(layer "In6.Cu")
		(net "NFP_SERDES1_RX1_N")
	)
	(segment
		(start 39.338733 2.304466)
		(end 39.338733 2.54)
		(width 0.096012)
		(layer "In6.Cu")
		(net "NFP_SERDES1_RX1_N")
	)
	(segment
		(start 38.13142 3.946906)
		(end 38.08222 3.897706)
		(width 0.096012)
		(layer "In6.Cu")
		(net "NFP_SERDES1_RX1_N")
	)
	(segment
		(start 34.456294 3.897706)
		(end 33.75914 4.59486)
		(width 0.096012)
		(layer "In6.Cu")
		(net "NFP_SERDES1_RX1_N")
	)
	(segment
		(start 8.763 19.177)
		(end 8.509 19.431)
		(width 0.096012)
		(layer "In6.Cu")
		(net "NFP_SERDES1_RX1_N")
	)
	(segment
		(start 45.736993 6.541999)
		(end 45.129806 5.934812)
		(width 0.095758)
		(layer "In6.Cu")
		(net "NFP_SERDES1_RX1_N")
	)
	(segment
		(start 47.23699 7.041998)
		(end 46.736991 6.541999)
		(width 0.099314)
		(layer "F.Cu")
		(net "NFP_SERDES1_RX0_P")
	)
	(via
		(at 46.736991 6.541999)
		(size 0.4826)
		(drill 0.20574)
		(layers "F.Cu" "B.Cu")
		(net "NFP_SERDES1_RX0_P")
	)
	(via
		(at 7.874 17.1069)
		(size 0.508)
		(drill 0.254)
		(layers "F.Cu" "B.Cu")
		(net "NFP_SERDES1_RX0_P")
	)
	(segment
		(start 8.4074 17.7419)
		(end 7.874 17.1069)
		(width 0.099314)
		(layer "B.Cu")
		(net "NFP_SERDES1_RX0_P")
	)
	(segment
		(start 32.645325 3.16865)
		(end 30.48635 3.16865)
		(width 0.096012)
		(layer "In6.Cu")
		(net "NFP_SERDES1_RX0_P")
	)
	(segment
		(start 38.086665 2.599639)
		(end 37.797054 2.88925)
		(width 0.096012)
		(layer "In6.Cu")
		(net "NFP_SERDES1_RX0_P")
	)
	(segment
		(start 13.281406 14.290396)
		(end 13.281406 14.744624)
		(width 0.096012)
		(layer "In6.Cu")
		(net "NFP_SERDES1_RX0_P")
	)
	(segment
		(start 13.030124 14.995906)
		(end 12.718466 14.995906)
		(width 0.096012)
		(layer "In6.Cu")
		(net "NFP_SERDES1_RX0_P")
	)
	(segment
		(start 46.736991 6.541999)
		(end 46.736991 6.738849)
		(width 0.095758)
		(layer "In6.Cu")
		(net "NFP_SERDES1_RX0_P")
	)
	(segment
		(start 8.104149 17.629149)
		(end 7.874 17.399)
		(width 0.096012)
		(layer "In6.Cu")
		(net "NFP_SERDES1_RX0_P")
	)
	(segment
		(start 46.34418 6.74304)
		(end 46.34418 1.758137)
		(width 0.095758)
		(layer "In6.Cu")
		(net "NFP_SERDES1_RX0_P")
	)
	(segment
		(start 23.412552 7.08025)
		(end 21.40331 9.089492)
		(width 0.096012)
		(layer "In6.Cu")
		(net "NFP_SERDES1_RX0_P")
	)
	(segment
		(start 46.299526 1.622069)
		(end 46.291043 1.613586)
		(width 0.095758)
		(layer "In6.Cu")
		(net "NFP_SERDES1_RX0_P")
	)
	(segment
		(start 19.291884 13.73124)
		(end 18.964935 13.73124)
		(width 0.096012)
		(layer "In6.Cu")
		(net "NFP_SERDES1_RX0_P")
	)
	(segment
		(start 32.679869 3.134106)
		(end 32.645325 3.16865)
		(width 0.096012)
		(layer "In6.Cu")
		(net "NFP_SERDES1_RX0_P")
	)
	(segment
		(start 18.744844 13.951331)
		(end 18.339156 13.951331)
		(width 0.096012)
		(layer "In6.Cu")
		(net "NFP_SERDES1_RX0_P")
	)
	(segment
		(start 46.34418 1.758137)
		(end 46.321218 1.735176)
		(width 0.095758)
		(layer "In6.Cu")
		(net "NFP_SERDES1_RX0_P")
	)
	(segment
		(start 46.291043 1.613586)
		(end 45.312457 0.635)
		(width 0.096012)
		(layer "In6.Cu")
		(net "NFP_SERDES1_RX0_P")
	)
	(segment
		(start 46.444129 6.842989)
		(end 46.34418 6.74304)
		(width 0.095758)
		(layer "In6.Cu")
		(net "NFP_SERDES1_RX0_P")
	)
	(segment
		(start 21.40331 11.619814)
		(end 19.291884 13.73124)
		(width 0.096012)
		(layer "In6.Cu")
		(net "NFP_SERDES1_RX0_P")
	)
	(segment
		(start 45.312457 0.635)
		(end 39.636802 0.635)
		(width 0.096012)
		(layer "In6.Cu")
		(net "NFP_SERDES1_RX0_P")
	)
	(segment
		(start 46.299526 1.687246)
		(end 46.299526 1.622069)
		(width 0.095758)
		(layer "In6.Cu")
		(net "NFP_SERDES1_RX0_P")
	)
	(segment
		(start 46.321218 1.735176)
		(end 46.321218 1.708937)
		(width 0.095758)
		(layer "In6.Cu")
		(net "NFP_SERDES1_RX0_P")
	)
	(segment
		(start 18.964935 13.73124)
		(end 18.744844 13.951331)
		(width 0.096012)
		(layer "In6.Cu")
		(net "NFP_SERDES1_RX0_P")
	)
	(segment
		(start 24.725782 7.08025)
		(end 23.412552 7.08025)
		(width 0.096012)
		(layer "In6.Cu")
		(net "NFP_SERDES1_RX0_P")
	)
	(segment
		(start 30.48635 3.16865)
		(end 28.57246 5.08254)
		(width 0.096012)
		(layer "In6.Cu")
		(net "NFP_SERDES1_RX0_P")
	)
	(segment
		(start 46.321218 1.708937)
		(end 46.299526 1.687246)
		(width 0.095758)
		(layer "In6.Cu")
		(net "NFP_SERDES1_RX0_P")
	)
	(segment
		(start 46.632851 6.842989)
		(end 46.444129 6.842989)
		(width 0.095758)
		(layer "In6.Cu")
		(net "NFP_SERDES1_RX0_P")
	)
	(segment
		(start 28.57246 5.08254)
		(end 26.723492 5.08254)
		(width 0.096012)
		(layer "In6.Cu")
		(net "NFP_SERDES1_RX0_P")
	)
	(segment
		(start 13.840562 13.73124)
		(end 13.281406 14.290396)
		(width 0.096012)
		(layer "In6.Cu")
		(net "NFP_SERDES1_RX0_P")
	)
	(segment
		(start 10.893044 16.821328)
		(end 10.893044 17.173981)
		(width 0.096012)
		(layer "In6.Cu")
		(net "NFP_SERDES1_RX0_P")
	)
	(segment
		(start 38.086665 2.185137)
		(end 38.086665 2.599639)
		(width 0.096012)
		(layer "In6.Cu")
		(net "NFP_SERDES1_RX0_P")
	)
	(segment
		(start 13.281406 14.744624)
		(end 13.030124 14.995906)
		(width 0.096012)
		(layer "In6.Cu")
		(net "NFP_SERDES1_RX0_P")
	)
	(segment
		(start 10.893044 17.173981)
		(end 10.437876 17.629149)
		(width 0.096012)
		(layer "In6.Cu")
		(net "NFP_SERDES1_RX0_P")
	)
	(segment
		(start 10.437876 17.629149)
		(end 8.104149 17.629149)
		(width 0.096012)
		(layer "In6.Cu")
		(net "NFP_SERDES1_RX0_P")
	)
	(segment
		(start 26.723492 5.08254)
		(end 24.725782 7.08025)
		(width 0.096012)
		(layer "In6.Cu")
		(net "NFP_SERDES1_RX0_P")
	)
	(segment
		(start 21.40331 9.089492)
		(end 21.40331 11.619814)
		(width 0.096012)
		(layer "In6.Cu")
		(net "NFP_SERDES1_RX0_P")
	)
	(segment
		(start 7.874 17.399)
		(end 7.874 17.1069)
		(width 0.096012)
		(layer "In6.Cu")
		(net "NFP_SERDES1_RX0_P")
	)
	(segment
		(start 46.736991 6.738849)
		(end 46.632851 6.842989)
		(width 0.095758)
		(layer "In6.Cu")
		(net "NFP_SERDES1_RX0_P")
	)
	(segment
		(start 18.119065 13.73124)
		(end 13.840562 13.73124)
		(width 0.096012)
		(layer "In6.Cu")
		(net "NFP_SERDES1_RX0_P")
	)
	(segment
		(start 33.69658 2.88925)
		(end 33.451724 3.134106)
		(width 0.096012)
		(layer "In6.Cu")
		(net "NFP_SERDES1_RX0_P")
	)
	(segment
		(start 37.797054 2.88925)
		(end 33.69658 2.88925)
		(width 0.096012)
		(layer "In6.Cu")
		(net "NFP_SERDES1_RX0_P")
	)
	(segment
		(start 33.451724 3.134106)
		(end 32.679869 3.134106)
		(width 0.096012)
		(layer "In6.Cu")
		(net "NFP_SERDES1_RX0_P")
	)
	(segment
		(start 39.636802 0.635)
		(end 38.086665 2.185137)
		(width 0.096012)
		(layer "In6.Cu")
		(net "NFP_SERDES1_RX0_P")
	)
	(segment
		(start 12.718466 14.995906)
		(end 10.893044 16.821328)
		(width 0.096012)
		(layer "In6.Cu")
		(net "NFP_SERDES1_RX0_P")
	)
	(segment
		(start 18.339156 13.951331)
		(end 18.119065 13.73124)
		(width 0.096012)
		(layer "In6.Cu")
		(net "NFP_SERDES1_RX0_P")
	)
	(segment
		(start 47.23699 8.041996)
		(end 46.736991 7.541997)
		(width 0.099314)
		(layer "F.Cu")
		(net "NFP_SERDES1_RX0_N")
	)
	(via
		(at 46.736991 7.541997)
		(size 0.4826)
		(drill 0.25654)
		(layers "F.Cu" "B.Cu")
		(net "NFP_SERDES1_RX0_N")
	)
	(via
		(at 7.7724 18.3769)
		(size 0.508)
		(drill 0.254)
		(layers "F.Cu" "B.Cu")
		(net "NFP_SERDES1_RX0_N")
	)
	(segment
		(start 8.4074 19.0119)
		(end 7.7724 18.3769)
		(width 0.099314)
		(layer "B.Cu")
		(net "NFP_SERDES1_RX0_N")
	)
	(segment
		(start 11.153394 16.929176)
		(end 11.153394 17.28183)
		(width 0.096012)
		(layer "In6.Cu")
		(net "NFP_SERDES1_RX0_N")
	)
	(segment
		(start 38.057404 2.997098)
		(end 38.057404 2.997175)
		(width 0.096012)
		(layer "In6.Cu")
		(net "NFP_SERDES1_RX0_N")
	)
	(segment
		(start 13.94841 13.99159)
		(end 13.541756 14.398244)
		(width 0.096012)
		(layer "In6.Cu")
		(net "NFP_SERDES1_RX0_N")
	)
	(segment
		(start 46.736991 7.541997)
		(end 46.130058 6.935064)
		(width 0.095758)
		(layer "In6.Cu")
		(net "NFP_SERDES1_RX0_N")
	)
	(segment
		(start 18.231307 14.211681)
		(end 18.011216 13.99159)
		(width 0.096012)
		(layer "In6.Cu")
		(net "NFP_SERDES1_RX0_N")
	)
	(segment
		(start 11.153394 17.28183)
		(end 10.545724 17.889499)
		(width 0.096012)
		(layer "In6.Cu")
		(net "NFP_SERDES1_RX0_N")
	)
	(segment
		(start 37.904979 3.1496)
		(end 33.804428 3.1496)
		(width 0.096012)
		(layer "In6.Cu")
		(net "NFP_SERDES1_RX0_N")
	)
	(segment
		(start 28.680308 5.34289)
		(end 26.831341 5.34289)
		(width 0.096012)
		(layer "In6.Cu")
		(net "NFP_SERDES1_RX0_N")
	)
	(segment
		(start 46.107096 1.797837)
		(end 46.106944 1.797685)
		(width 0.095758)
		(layer "In6.Cu")
		(net "NFP_SERDES1_RX0_N")
	)
	(segment
		(start 46.130058 1.846834)
		(end 46.107096 1.823872)
		(width 0.095758)
		(layer "In6.Cu")
		(net "NFP_SERDES1_RX0_N")
	)
	(segment
		(start 38.347015 2.292985)
		(end 38.347015 2.707488)
		(width 0.096012)
		(layer "In6.Cu")
		(net "NFP_SERDES1_RX0_N")
	)
	(segment
		(start 19.399733 13.99159)
		(end 19.072784 13.99159)
		(width 0.096012)
		(layer "In6.Cu")
		(net "NFP_SERDES1_RX0_N")
	)
	(segment
		(start 12.826314 15.256256)
		(end 11.153394 16.929176)
		(width 0.096012)
		(layer "In6.Cu")
		(net "NFP_SERDES1_RX0_N")
	)
	(segment
		(start 23.5204 7.3406)
		(end 21.66366 9.19734)
		(width 0.096012)
		(layer "In6.Cu")
		(net "NFP_SERDES1_RX0_N")
	)
	(segment
		(start 46.107096 1.823872)
		(end 46.107096 1.797837)
		(width 0.095758)
		(layer "In6.Cu")
		(net "NFP_SERDES1_RX0_N")
	)
	(segment
		(start 13.541756 14.852472)
		(end 13.137972 15.256256)
		(width 0.096012)
		(layer "In6.Cu")
		(net "NFP_SERDES1_RX0_N")
	)
	(segment
		(start 19.072784 13.99159)
		(end 18.852693 14.211681)
		(width 0.096012)
		(layer "In6.Cu")
		(net "NFP_SERDES1_RX0_N")
	)
	(segment
		(start 26.831341 5.34289)
		(end 24.833631 7.3406)
		(width 0.096012)
		(layer "In6.Cu")
		(net "NFP_SERDES1_RX0_N")
	)
	(segment
		(start 46.130058 6.935064)
		(end 46.130058 1.846834)
		(width 0.095758)
		(layer "In6.Cu")
		(net "NFP_SERDES1_RX0_N")
	)
	(segment
		(start 39.74465 0.89535)
		(end 38.347015 2.292985)
		(width 0.096012)
		(layer "In6.Cu")
		(net "NFP_SERDES1_RX0_N")
	)
	(segment
		(start 38.347015 2.707488)
		(end 38.057404 2.997098)
		(width 0.096012)
		(layer "In6.Cu")
		(net "NFP_SERDES1_RX0_N")
	)
	(segment
		(start 38.057404 2.997175)
		(end 37.904979 3.1496)
		(width 0.096012)
		(layer "In6.Cu")
		(net "NFP_SERDES1_RX0_N")
	)
	(segment
		(start 18.852693 14.211681)
		(end 18.231307 14.211681)
		(width 0.096012)
		(layer "In6.Cu")
		(net "NFP_SERDES1_RX0_N")
	)
	(segment
		(start 8.259801 17.889499)
		(end 7.7724 18.3769)
		(width 0.096012)
		(layer "In6.Cu")
		(net "NFP_SERDES1_RX0_N")
	)
	(segment
		(start 13.541756 14.398244)
		(end 13.541756 14.852472)
		(width 0.096012)
		(layer "In6.Cu")
		(net "NFP_SERDES1_RX0_N")
	)
	(segment
		(start 32.787717 3.394456)
		(end 32.753173 3.429)
		(width 0.096012)
		(layer "In6.Cu")
		(net "NFP_SERDES1_RX0_N")
	)
	(segment
		(start 30.594198 3.429)
		(end 28.680308 5.34289)
		(width 0.096012)
		(layer "In6.Cu")
		(net "NFP_SERDES1_RX0_N")
	)
	(segment
		(start 33.804428 3.1496)
		(end 33.559572 3.394456)
		(width 0.096012)
		(layer "In6.Cu")
		(net "NFP_SERDES1_RX0_N")
	)
	(segment
		(start 33.559572 3.394456)
		(end 32.787717 3.394456)
		(width 0.096012)
		(layer "In6.Cu")
		(net "NFP_SERDES1_RX0_N")
	)
	(segment
		(start 32.753173 3.429)
		(end 30.594198 3.429)
		(width 0.096012)
		(layer "In6.Cu")
		(net "NFP_SERDES1_RX0_N")
	)
	(segment
		(start 46.106944 1.797685)
		(end 45.204609 0.89535)
		(width 0.096012)
		(layer "In6.Cu")
		(net "NFP_SERDES1_RX0_N")
	)
	(segment
		(start 13.137972 15.256256)
		(end 12.826314 15.256256)
		(width 0.096012)
		(layer "In6.Cu")
		(net "NFP_SERDES1_RX0_N")
	)
	(segment
		(start 24.833631 7.3406)
		(end 23.5204 7.3406)
		(width 0.096012)
		(layer "In6.Cu")
		(net "NFP_SERDES1_RX0_N")
	)
	(segment
		(start 10.545724 17.889499)
		(end 8.259801 17.889499)
		(width 0.096012)
		(layer "In6.Cu")
		(net "NFP_SERDES1_RX0_N")
	)
	(segment
		(start 18.011216 13.99159)
		(end 13.94841 13.99159)
		(width 0.096012)
		(layer "In6.Cu")
		(net "NFP_SERDES1_RX0_N")
	)
	(segment
		(start 21.66366 9.19734)
		(end 21.66366 11.727663)
		(width 0.096012)
		(layer "In6.Cu")
		(net "NFP_SERDES1_RX0_N")
	)
	(segment
		(start 45.204609 0.89535)
		(end 39.74465 0.89535)
		(width 0.096012)
		(layer "In6.Cu")
		(net "NFP_SERDES1_RX0_N")
	)
	(segment
		(start 21.66366 11.727663)
		(end 19.399733 13.99159)
		(width 0.096012)
		(layer "In6.Cu")
		(net "NFP_SERDES1_RX0_N")
	)
	(via
		(at 34.544 30.48)
		(size 0.4572)
		(drill 0.20574)
		(layers "F.Cu" "B.Cu")
		(net "NWK0_LED_LINK_G_L")
	)
	(via
		(at 10.3124 18.3769)
		(size 0.508)
		(drill 0.254)
		(layers "F.Cu" "B.Cu")
		(net "NWK0_LED_LINK_G_L")
	)
	(segment
		(start 10.9474 19.0119)
		(end 10.3124 18.3769)
		(width 0.254)
		(layer "B.Cu")
		(net "NWK0_LED_LINK_G_L")
	)
	(segment
		(start 34.417 30.353)
		(end 34.417 29.7942)
		(width 0.12065)
		(layer "In1.Cu")
		(net "NWK0_LED_LINK_G_L")
	)
	(segment
		(start 33.746008 29.123208)
		(end 33.746008 28.048407)
		(width 0.12065)
		(layer "In1.Cu")
		(net "NWK0_LED_LINK_G_L")
	)
	(segment
		(start 34.417 29.7942)
		(end 33.746008 29.123208)
		(width 0.12065)
		(layer "In1.Cu")
		(net "NWK0_LED_LINK_G_L")
	)
	(segment
		(start 34.544 30.48)
		(end 34.417 30.353)
		(width 0.12065)
		(layer "In1.Cu")
		(net "NWK0_LED_LINK_G_L")
	)
	(segment
		(start 25.943941 28.793059)
		(end 25.943941 29.065245)
		(width 0.12065)
		(layer "In2.Cu")
		(net "NWK0_LED_LINK_G_L")
	)
	(segment
		(start 9.779 19.431)
		(end 10.3124 18.8976)
		(width 0.12065)
		(layer "In2.Cu")
		(net "NWK0_LED_LINK_G_L")
	)
	(segment
		(start 21.142325 25.079325)
		(end 20.259675 24.196675)
		(width 0.12065)
		(layer "In2.Cu")
		(net "NWK0_LED_LINK_G_L")
	)
	(segment
		(start 20.259675 24.196675)
		(end 19.375171 24.196675)
		(width 0.12065)
		(layer "In2.Cu")
		(net "NWK0_LED_LINK_G_L")
	)
	(segment
		(start 34.544 29.9212)
		(end 32.653859 28.031059)
		(width 0.12065)
		(layer "In2.Cu")
		(net "NWK0_LED_LINK_G_L")
	)
	(segment
		(start 26.705941 28.031059)
		(end 25.943941 28.793059)
		(width 0.12065)
		(layer "In2.Cu")
		(net "NWK0_LED_LINK_G_L")
	)
	(segment
		(start 21.971 28.956)
		(end 21.142325 28.127325)
		(width 0.12065)
		(layer "In2.Cu")
		(net "NWK0_LED_LINK_G_L")
	)
	(segment
		(start 34.544 30.48)
		(end 34.544 29.9212)
		(width 0.12065)
		(layer "In2.Cu")
		(net "NWK0_LED_LINK_G_L")
	)
	(segment
		(start 25.943941 29.065245)
		(end 25.699745 29.309441)
		(width 0.12065)
		(layer "In2.Cu")
		(net "NWK0_LED_LINK_G_L")
	)
	(segment
		(start 32.653859 28.031059)
		(end 26.705941 28.031059)
		(width 0.12065)
		(layer "In2.Cu")
		(net "NWK0_LED_LINK_G_L")
	)
	(segment
		(start 25.699745 29.309441)
		(end 22.705466 29.309441)
		(width 0.12065)
		(layer "In2.Cu")
		(net "NWK0_LED_LINK_G_L")
	)
	(segment
		(start 10.3124 18.8976)
		(end 10.3124 18.3769)
		(width 0.12065)
		(layer "In2.Cu")
		(net "NWK0_LED_LINK_G_L")
	)
	(segment
		(start 10.061575 24.285575)
		(end 9.779 24.003)
		(width 0.12065)
		(layer "In2.Cu")
		(net "NWK0_LED_LINK_G_L")
	)
	(segment
		(start 19.375171 24.196675)
		(end 19.286271 24.285575)
		(width 0.12065)
		(layer "In2.Cu")
		(net "NWK0_LED_LINK_G_L")
	)
	(segment
		(start 22.705466 29.309441)
		(end 22.352025 28.956)
		(width 0.12065)
		(layer "In2.Cu")
		(net "NWK0_LED_LINK_G_L")
	)
	(segment
		(start 9.779 24.003)
		(end 9.779 19.431)
		(width 0.12065)
		(layer "In2.Cu")
		(net "NWK0_LED_LINK_G_L")
	)
	(segment
		(start 21.142325 28.127325)
		(end 21.142325 25.079325)
		(width 0.12065)
		(layer "In2.Cu")
		(net "NWK0_LED_LINK_G_L")
	)
	(segment
		(start 22.352025 28.956)
		(end 21.971 28.956)
		(width 0.12065)
		(layer "In2.Cu")
		(net "NWK0_LED_LINK_G_L")
	)
	(segment
		(start 19.286271 24.285575)
		(end 10.061575 24.285575)
		(width 0.12065)
		(layer "In2.Cu")
		(net "NWK0_LED_LINK_G_L")
	)
	(segment
		(start 32.927239 27.229638)
		(end 33.246009 27.548408)
		(width 0.127)
		(layer "F.Cu")
		(net "NWK0_LED_ACT_G_L")
	)
	(segment
		(start 31.7627 26.4795)
		(end 32.330034 26.4795)
		(width 0.127)
		(layer "F.Cu")
		(net "NWK0_LED_ACT_G_L")
	)
	(segment
		(start 31.3436 26.0604)
		(end 31.7627 26.4795)
		(width 0.127)
		(layer "F.Cu")
		(net "NWK0_LED_ACT_G_L")
	)
	(segment
		(start 32.330034 26.4795)
		(end 32.5755 26.724966)
		(width 0.127)
		(layer "F.Cu")
		(net "NWK0_LED_ACT_G_L")
	)
	(segment
		(start 32.5755 26.724966)
		(end 32.5755 26.951254)
		(width 0.127)
		(layer "F.Cu")
		(net "NWK0_LED_ACT_G_L")
	)
	(segment
		(start 32.853884 27.229638)
		(end 32.927239 27.229638)
		(width 0.127)
		(layer "F.Cu")
		(net "NWK0_LED_ACT_G_L")
	)
	(segment
		(start 32.5755 26.951254)
		(end 32.853884 27.229638)
		(width 0.127)
		(layer "F.Cu")
		(net "NWK0_LED_ACT_G_L")
	)
	(via
		(at 31.3436 26.0604)
		(size 0.4572)
		(drill 0.20574)
		(layers "F.Cu" "B.Cu")
		(net "NWK0_LED_ACT_G_L")
	)
	(via
		(at 10.3124 17.1069)
		(size 0.508)
		(drill 0.254)
		(layers "F.Cu" "B.Cu")
		(net "NWK0_LED_ACT_G_L")
	)
	(via
		(at 34.544 27.686)
		(size 0.762)
		(drill 0.381)
		(layers "F.Cu" "B.Cu")
		(net "NWK0_LED_ACT_G_L")
	)
	(segment
		(start 34.544 27.686)
		(end 34.097798 27.239798)
		(width 0.14732)
		(layer "B.Cu")
		(net "NWK0_LED_ACT_G_L")
	)
	(segment
		(start 31.925285 26.0604)
		(end 31.3436 26.0604)
		(width 0.14732)
		(layer "B.Cu")
		(net "NWK0_LED_ACT_G_L")
	)
	(segment
		(start 32.849693 27.239798)
		(end 32.598258 26.988364)
		(width 0.14732)
		(layer "B.Cu")
		(net "NWK0_LED_ACT_G_L")
	)
	(segment
		(start 34.097798 27.239798)
		(end 32.849693 27.239798)
		(width 0.14732)
		(layer "B.Cu")
		(net "NWK0_LED_ACT_G_L")
	)
	(segment
		(start 32.598258 26.988364)
		(end 32.598258 26.733373)
		(width 0.14732)
		(layer "B.Cu")
		(net "NWK0_LED_ACT_G_L")
	)
	(segment
		(start 10.9474 17.7419)
		(end 10.3124 17.1069)
		(width 0.254)
		(layer "B.Cu")
		(net "NWK0_LED_ACT_G_L")
	)
	(segment
		(start 32.598258 26.733373)
		(end 31.925285 26.0604)
		(width 0.14732)
		(layer "B.Cu")
		(net "NWK0_LED_ACT_G_L")
	)
	(segment
		(start 22.435871 28.711525)
		(end 21.59 27.865654)
		(width 0.12065)
		(layer "In2.Cu")
		(net "NWK0_LED_ACT_G_L")
	)
	(segment
		(start 26.782141 27.192859)
		(end 26.761796 27.192859)
		(width 0.12065)
		(layer "In2.Cu")
		(net "NWK0_LED_ACT_G_L")
	)
	(segment
		(start 22.733 28.956)
		(end 22.488525 28.711525)
		(width 0.12065)
		(layer "In2.Cu")
		(net "NWK0_LED_ACT_G_L")
	)
	(segment
		(start 25.499441 28.475559)
		(end 25.354255 28.475559)
		(width 0.12065)
		(layer "In2.Cu")
		(net "NWK0_LED_ACT_G_L")
	)
	(segment
		(start 30.896941 26.507059)
		(end 30.134941 26.507059)
		(width 0.12065)
		(layer "In2.Cu")
		(net "NWK0_LED_ACT_G_L")
	)
	(segment
		(start 11.229975 23.929975)
		(end 10.795 23.495)
		(width 0.12065)
		(layer "In2.Cu")
		(net "NWK0_LED_ACT_G_L")
	)
	(segment
		(start 30.134941 26.507059)
		(end 29.464 27.178)
		(width 0.12065)
		(layer "In2.Cu")
		(net "NWK0_LED_ACT_G_L")
	)
	(segment
		(start 26.532459 27.422196)
		(end 26.532459 27.442541)
		(width 0.12065)
		(layer "In2.Cu")
		(net "NWK0_LED_ACT_G_L")
	)
	(segment
		(start 26.532459 27.442541)
		(end 25.499441 28.475559)
		(width 0.12065)
		(layer "In2.Cu")
		(net "NWK0_LED_ACT_G_L")
	)
	(segment
		(start 21.59 25.019)
		(end 20.500975 23.929975)
		(width 0.12065)
		(layer "In2.Cu")
		(net "NWK0_LED_ACT_G_L")
	)
	(segment
		(start 26.797 27.178)
		(end 26.782141 27.192859)
		(width 0.12065)
		(layer "In2.Cu")
		(net "NWK0_LED_ACT_G_L")
	)
	(segment
		(start 24.873814 28.956)
		(end 22.733 28.956)
		(width 0.12065)
		(layer "In2.Cu")
		(net "NWK0_LED_ACT_G_L")
	)
	(segment
		(start 20.500975 23.929975)
		(end 11.229975 23.929975)
		(width 0.12065)
		(layer "In2.Cu")
		(net "NWK0_LED_ACT_G_L")
	)
	(segment
		(start 31.3436 26.0604)
		(end 30.896941 26.507059)
		(width 0.12065)
		(layer "In2.Cu")
		(net "NWK0_LED_ACT_G_L")
	)
	(segment
		(start 22.488525 28.711525)
		(end 22.435871 28.711525)
		(width 0.12065)
		(layer "In2.Cu")
		(net "NWK0_LED_ACT_G_L")
	)
	(segment
		(start 10.795 23.495)
		(end 10.795 17.5895)
		(width 0.12065)
		(layer "In2.Cu")
		(net "NWK0_LED_ACT_G_L")
	)
	(segment
		(start 26.761796 27.192859)
		(end 26.532459 27.422196)
		(width 0.12065)
		(layer "In2.Cu")
		(net "NWK0_LED_ACT_G_L")
	)
	(segment
		(start 25.354255 28.475559)
		(end 24.873814 28.956)
		(width 0.12065)
		(layer "In2.Cu")
		(net "NWK0_LED_ACT_G_L")
	)
	(segment
		(start 10.795 17.5895)
		(end 10.3124 17.1069)
		(width 0.12065)
		(layer "In2.Cu")
		(net "NWK0_LED_ACT_G_L")
	)
	(segment
		(start 29.464 27.178)
		(end 26.797 27.178)
		(width 0.12065)
		(layer "In2.Cu")
		(net "NWK0_LED_ACT_G_L")
	)
	(segment
		(start 21.59 27.865654)
		(end 21.59 25.019)
		(width 0.12065)
		(layer "In2.Cu")
		(net "NWK0_LED_ACT_G_L")
	)
	(segment
		(start 81.915 37.084)
		(end 82.296 36.703)
		(width 0.14732)
		(layer "F.Cu")
		(net "VDDQ_VTT_PGOOD")
	)
	(segment
		(start 81.915 37.973)
		(end 81.915 37.084)
		(width 0.14732)
		(layer "F.Cu")
		(net "VDDQ_VTT_PGOOD")
	)
	(segment
		(start 36.2458 25.6794)
		(end 35.8267 26.0985)
		(width 0.127)
		(layer "F.Cu")
		(net "VDDQ_VTT_PGOOD")
	)
	(segment
		(start 81.407 38.735)
		(end 80.835602 39.306398)
		(width 0.14732)
		(layer "F.Cu")
		(net "VDDQ_VTT_PGOOD")
	)
	(segment
		(start 81.4959 38.3921)
		(end 81.915 37.973)
		(width 0.14732)
		(layer "F.Cu")
		(net "VDDQ_VTT_PGOOD")
	)
	(segment
		(start 81.407 38.3921)
		(end 81.407 38.735)
		(width 0.14732)
		(layer "F.Cu")
		(net "VDDQ_VTT_PGOOD")
	)
	(segment
		(start 81.407 38.3921)
		(end 81.4959 38.3921)
		(width 0.14732)
		(layer "F.Cu")
		(net "VDDQ_VTT_PGOOD")
	)
	(segment
		(start 82.296 36.703)
		(end 82.931 36.703)
		(width 0.14732)
		(layer "F.Cu")
		(net "VDDQ_VTT_PGOOD")
	)
	(segment
		(start 35.8267 26.0985)
		(end 35.195916 26.0985)
		(width 0.127)
		(layer "F.Cu")
		(net "VDDQ_VTT_PGOOD")
	)
	(segment
		(start 80.835602 39.306398)
		(end 80.835602 40.0304)
		(width 0.14732)
		(layer "F.Cu")
		(net "VDDQ_VTT_PGOOD")
	)
	(segment
		(start 35.195916 26.0985)
		(end 34.746006 26.54841)
		(width 0.127)
		(layer "F.Cu")
		(net "VDDQ_VTT_PGOOD")
	)
	(segment
		(start 83.312 36.322)
		(end 83.82 35.306)
		(width 0.14732)
		(layer "F.Cu")
		(net "VDDQ_VTT_PGOOD")
	)
	(segment
		(start 82.931 36.703)
		(end 83.312 36.322)
		(width 0.14732)
		(layer "F.Cu")
		(net "VDDQ_VTT_PGOOD")
	)
	(via
		(at 81.407 38.3921)
		(size 0.508)
		(drill 0.25654)
		(layers "F.Cu" "B.Cu")
		(net "VDDQ_VTT_PGOOD")
	)
	(via
		(at 79.502 34.417)
		(size 0.508)
		(drill 0.254)
		(layers "F.Cu" "B.Cu")
		(net "VDDQ_VTT_PGOOD")
	)
	(via
		(at 36.2458 25.6794)
		(size 0.4572)
		(drill 0.20574)
		(layers "F.Cu" "B.Cu")
		(net "VDDQ_VTT_PGOOD")
	)
	(segment
		(start 41.926281 28.194)
		(end 42.164 28.194)
		(width 0.12065)
		(layer "In2.Cu")
		(net "VDDQ_VTT_PGOOD")
	)
	(segment
		(start 41.904056 28.171775)
		(end 41.926281 28.194)
		(width 0.12065)
		(layer "In2.Cu")
		(net "VDDQ_VTT_PGOOD")
	)
	(segment
		(start 38.989 28.194)
		(end 41.54772 28.194)
		(width 0.12065)
		(layer "In2.Cu")
		(net "VDDQ_VTT_PGOOD")
	)
	(segment
		(start 37.6174 27.051)
		(end 37.846 27.051)
		(width 0.12065)
		(layer "In2.Cu")
		(net "VDDQ_VTT_PGOOD")
	)
	(segment
		(start 41.569945 28.171775)
		(end 41.904056 28.171775)
		(width 0.12065)
		(layer "In2.Cu")
		(net "VDDQ_VTT_PGOOD")
	)
	(segment
		(start 69.072582 29.067582)
		(end 74.422 34.417)
		(width 0.12065)
		(layer "In2.Cu")
		(net "VDDQ_VTT_PGOOD")
	)
	(segment
		(start 36.2458 25.6794)
		(end 37.6174 27.051)
		(width 0.12065)
		(layer "In2.Cu")
		(net "VDDQ_VTT_PGOOD")
	)
	(segment
		(start 41.54772 28.194)
		(end 41.569945 28.171775)
		(width 0.12065)
		(layer "In2.Cu")
		(net "VDDQ_VTT_PGOOD")
	)
	(segment
		(start 74.422 34.417)
		(end 79.502 34.417)
		(width 0.12065)
		(layer "In2.Cu")
		(net "VDDQ_VTT_PGOOD")
	)
	(segment
		(start 37.846 27.051)
		(end 38.989 28.194)
		(width 0.12065)
		(layer "In2.Cu")
		(net "VDDQ_VTT_PGOOD")
	)
	(segment
		(start 42.164 28.194)
		(end 43.037582 29.067582)
		(width 0.12065)
		(layer "In2.Cu")
		(net "VDDQ_VTT_PGOOD")
	)
	(segment
		(start 43.037582 29.067582)
		(end 69.072582 29.067582)
		(width 0.12065)
		(layer "In2.Cu")
		(net "VDDQ_VTT_PGOOD")
	)
	(segment
		(start 80.645 37.6301)
		(end 81.407 38.3921)
		(width 0.12065)
		(layer "In6.Cu")
		(net "VDDQ_VTT_PGOOD")
	)
	(segment
		(start 79.502 34.417)
		(end 80.645 35.56)
		(width 0.12065)
		(layer "In6.Cu")
		(net "VDDQ_VTT_PGOOD")
	)
	(segment
		(start 80.645 35.56)
		(end 80.645 37.6301)
		(width 0.12065)
		(layer "In6.Cu")
		(net "VDDQ_VTT_PGOOD")
	)
	(segment
		(start 84.201 38.3921)
		(end 83.692949 38.900151)
		(width 0.14732)
		(layer "F.Cu")
		(net "VDDQ_VTT_EN")
	)
	(segment
		(start 30.3149 24.8793)
		(end 30.7086 25.273)
		(width 0.127)
		(layer "F.Cu")
		(net "VDDQ_VTT_EN")
	)
	(segment
		(start 82.169 39.37)
		(end 82.035599 39.503401)
		(width 0.14732)
		(layer "F.Cu")
		(net "VDDQ_VTT_EN")
	)
	(segment
		(start 82.296 39.37)
		(end 82.169 39.37)
		(width 0.14732)
		(layer "F.Cu")
		(net "VDDQ_VTT_EN")
	)
	(segment
		(start 84.836 37.7571)
		(end 85.344 35.306)
		(width 0.14732)
		(layer "F.Cu")
		(net "VDDQ_VTT_EN")
	)
	(segment
		(start 29.245992 25.048388)
		(end 29.41508 24.8793)
		(width 0.127)
		(layer "F.Cu")
		(net "VDDQ_VTT_EN")
	)
	(segment
		(start 29.41508 24.8793)
		(end 30.3149 24.8793)
		(width 0.127)
		(layer "F.Cu")
		(net "VDDQ_VTT_EN")
	)
	(segment
		(start 82.435598 39.509598)
		(end 82.296 39.37)
		(width 0.14732)
		(layer "F.Cu")
		(net "VDDQ_VTT_EN")
	)
	(segment
		(start 83.2866 40.0304)
		(end 82.435598 40.0304)
		(width 0.14732)
		(layer "F.Cu")
		(net "VDDQ_VTT_EN")
	)
	(segment
		(start 83.692949 39.624051)
		(end 83.2866 40.0304)
		(width 0.14732)
		(layer "F.Cu")
		(net "VDDQ_VTT_EN")
	)
	(segment
		(start 84.201 38.3921)
		(end 84.836 37.7571)
		(width 0.14732)
		(layer "F.Cu")
		(net "VDDQ_VTT_EN")
	)
	(segment
		(start 82.035599 39.503401)
		(end 82.035599 40.0304)
		(width 0.14732)
		(layer "F.Cu")
		(net "VDDQ_VTT_EN")
	)
	(segment
		(start 83.692949 38.900151)
		(end 83.692949 39.624051)
		(width 0.14732)
		(layer "F.Cu")
		(net "VDDQ_VTT_EN")
	)
	(segment
		(start 82.435598 40.0304)
		(end 82.435598 39.509598)
		(width 0.14732)
		(layer "F.Cu")
		(net "VDDQ_VTT_EN")
	)
	(via
		(at 79.502 35.687)
		(size 0.508)
		(drill 0.254)
		(layers "F.Cu" "B.Cu")
		(net "VDDQ_VTT_EN")
	)
	(via
		(at 84.201 38.3921)
		(size 0.508)
		(drill 0.25654)
		(layers "F.Cu" "B.Cu")
		(net "VDDQ_VTT_EN")
	)
	(via
		(at 30.7086 25.273)
		(size 0.4572)
		(drill 0.20574)
		(layers "F.Cu" "B.Cu")
		(net "VDDQ_VTT_EN")
	)
	(segment
		(start 31.104459 25.643459)
		(end 30.734 25.273)
		(width 0.12065)
		(layer "In2.Cu")
		(net "VDDQ_VTT_EN")
	)
	(segment
		(start 32.258 27.686)
		(end 31.75 27.178)
		(width 0.12065)
		(layer "In2.Cu")
		(net "VDDQ_VTT_EN")
	)
	(segment
		(start 70.612 31.115)
		(end 42.164 31.115)
		(width 0.12065)
		(layer "In2.Cu")
		(net "VDDQ_VTT_EN")
	)
	(segment
		(start 42.164 31.115)
		(end 41.656 30.607)
		(width 0.12065)
		(layer "In2.Cu")
		(net "VDDQ_VTT_EN")
	)
	(segment
		(start 31.496 25.643459)
		(end 31.104459 25.643459)
		(width 0.12065)
		(layer "In2.Cu")
		(net "VDDQ_VTT_EN")
	)
	(segment
		(start 36.83 30.607)
		(end 33.909 27.686)
		(width 0.12065)
		(layer "In2.Cu")
		(net "VDDQ_VTT_EN")
	)
	(segment
		(start 33.909 27.686)
		(end 32.258 27.686)
		(width 0.12065)
		(layer "In2.Cu")
		(net "VDDQ_VTT_EN")
	)
	(segment
		(start 31.75 25.897459)
		(end 31.496 25.643459)
		(width 0.12065)
		(layer "In2.Cu")
		(net "VDDQ_VTT_EN")
	)
	(segment
		(start 31.75 27.178)
		(end 31.75 25.897459)
		(width 0.12065)
		(layer "In2.Cu")
		(net "VDDQ_VTT_EN")
	)
	(segment
		(start 30.734 25.273)
		(end 30.7086 25.273)
		(width 0.12065)
		(layer "In2.Cu")
		(net "VDDQ_VTT_EN")
	)
	(segment
		(start 79.502 35.687)
		(end 75.184 35.687)
		(width 0.12065)
		(layer "In2.Cu")
		(net "VDDQ_VTT_EN")
	)
	(segment
		(start 41.656 30.607)
		(end 36.83 30.607)
		(width 0.12065)
		(layer "In2.Cu")
		(net "VDDQ_VTT_EN")
	)
	(segment
		(start 75.184 35.687)
		(end 70.612 31.115)
		(width 0.12065)
		(layer "In2.Cu")
		(net "VDDQ_VTT_EN")
	)
	(segment
		(start 82.814846 38.862)
		(end 82.875171 38.801675)
		(width 0.12065)
		(layer "In6.Cu")
		(net "VDDQ_VTT_EN")
	)
	(segment
		(start 82.875171 38.801675)
		(end 83.791425 38.801675)
		(width 0.12065)
		(layer "In6.Cu")
		(net "VDDQ_VTT_EN")
	)
	(segment
		(start 83.791425 38.801675)
		(end 84.201 38.3921)
		(width 0.12065)
		(layer "In6.Cu")
		(net "VDDQ_VTT_EN")
	)
	(segment
		(start 80.137 36.322)
		(end 80.137 37.846)
		(width 0.12065)
		(layer "In6.Cu")
		(net "VDDQ_VTT_EN")
	)
	(segment
		(start 80.137 37.846)
		(end 81.153 38.862)
		(width 0.12065)
		(layer "In6.Cu")
		(net "VDDQ_VTT_EN")
	)
	(segment
		(start 79.502 35.687)
		(end 80.137 36.322)
		(width 0.12065)
		(layer "In6.Cu")
		(net "VDDQ_VTT_EN")
	)
	(segment
		(start 81.153 38.862)
		(end 82.814846 38.862)
		(width 0.12065)
		(layer "In6.Cu")
		(net "VDDQ_VTT_EN")
	)
	(segment
		(start 17.272 2.413)
		(end 17.399 1.8161)
		(width 0.14732)
		(layer "F.Cu")
		(net "PCIE0_RST_L")
	)
	(segment
		(start 15.3924 3.1369)
		(end 15.8623 2.667)
		(width 0.14732)
		(layer "F.Cu")
		(net "PCIE0_RST_L")
	)
	(segment
		(start 41.237002 21.041995)
		(end 40.737003 21.541994)
		(width 0.13208)
		(layer "F.Cu")
		(net "PCIE0_RST_L")
	)
	(segment
		(start 15.8623 2.667)
		(end 17.018 2.667)
		(width 0.14732)
		(layer "F.Cu")
		(net "PCIE0_RST_L")
	)
	(segment
		(start 17.018 2.667)
		(end 17.272 2.413)
		(width 0.14732)
		(layer "F.Cu")
		(net "PCIE0_RST_L")
	)
	(via
		(at 15.3924 3.1369)
		(size 0.762)
		(drill 0.2667)
		(layers "F.Cu" "B.Cu")
		(net "PCIE0_RST_L")
	)
	(via
		(at 18.415 23.241)
		(size 0.508)
		(drill 0.254)
		(layers "F.Cu" "B.Cu")
		(net "PCIE0_RST_L")
	)
	(via
		(at 35.4584 22.1234)
		(size 0.4572)
		(drill 0.20574)
		(layers "F.Cu" "B.Cu")
		(net "PCIE0_RST_L")
	)
	(via
		(at 19.177 12.827)
		(size 0.508)
		(drill 0.254)
		(layers "F.Cu" "B.Cu")
		(net "PCIE0_RST_L")
	)
	(via
		(at 40.737003 21.541994)
		(size 0.4826)
		(drill 0.20574)
		(layers "F.Cu" "B.Cu")
		(net "PCIE0_RST_L")
	)
	(segment
		(start 16.0274 3.7719)
		(end 15.3924 3.1369)
		(width 0.254)
		(layer "B.Cu")
		(net "PCIE0_RST_L")
	)
	(segment
		(start 35.170999 22.1234)
		(end 34.246007 23.048392)
		(width 0.127)
		(layer "In1.Cu")
		(net "PCIE0_RST_L")
	)
	(segment
		(start 35.4584 22.1234)
		(end 35.170999 22.1234)
		(width 0.127)
		(layer "In1.Cu")
		(net "PCIE0_RST_L")
	)
	(segment
		(start 32.664425 23.113975)
		(end 33.655 22.1234)
		(width 0.12065)
		(layer "In3.Cu")
		(net "PCIE0_RST_L")
	)
	(segment
		(start 19.375171 25.079325)
		(end 21.6567 25.079325)
		(width 0.12065)
		(layer "In3.Cu")
		(net "PCIE0_RST_L")
	)
	(segment
		(start 19.116675 24.820829)
		(end 19.375171 25.079325)
		(width 0.12065)
		(layer "In3.Cu")
		(net "PCIE0_RST_L")
	)
	(segment
		(start 27.03642 23.053675)
		(end 27.09672 23.113975)
		(width 0.12065)
		(layer "In3.Cu")
		(net "PCIE0_RST_L")
	)
	(segment
		(start 26.736675 23.053675)
		(end 27.03642 23.053675)
		(width 0.12065)
		(layer "In3.Cu")
		(net "PCIE0_RST_L")
	)
	(segment
		(start 24.130025 22.606)
		(end 26.289 22.606)
		(width 0.12065)
		(layer "In3.Cu")
		(net "PCIE0_RST_L")
	)
	(segment
		(start 19.116675 23.942675)
		(end 19.116675 24.820829)
		(width 0.12065)
		(layer "In3.Cu")
		(net "PCIE0_RST_L")
	)
	(segment
		(start 27.09672 23.113975)
		(end 32.664425 23.113975)
		(width 0.12065)
		(layer "In3.Cu")
		(net "PCIE0_RST_L")
	)
	(segment
		(start 21.6567 25.079325)
		(end 24.130025 22.606)
		(width 0.12065)
		(layer "In3.Cu")
		(net "PCIE0_RST_L")
	)
	(segment
		(start 18.415 23.241)
		(end 19.116675 23.942675)
		(width 0.12065)
		(layer "In3.Cu")
		(net "PCIE0_RST_L")
	)
	(segment
		(start 26.289 22.606)
		(end 26.736675 23.053675)
		(width 0.12065)
		(layer "In3.Cu")
		(net "PCIE0_RST_L")
	)
	(segment
		(start 33.655 22.1234)
		(end 35.4584 22.1234)
		(width 0.12065)
		(layer "In3.Cu")
		(net "PCIE0_RST_L")
	)
	(segment
		(start 17.659299 11.309299)
		(end 19.177 12.827)
		(width 0.12065)
		(layer "In6.Cu")
		(net "PCIE0_RST_L")
	)
	(segment
		(start 40.464994 21.541994)
		(end 40.005 21.082)
		(width 0.12065)
		(layer "In6.Cu")
		(net "PCIE0_RST_L")
	)
	(segment
		(start 35.9918 21.59)
		(end 35.4584 22.1234)
		(width 0.12065)
		(layer "In6.Cu")
		(net "PCIE0_RST_L")
	)
	(segment
		(start 16.568953 11.309299)
		(end 17.659299 11.309299)
		(width 0.12065)
		(layer "In6.Cu")
		(net "PCIE0_RST_L")
	)
	(segment
		(start 37.000155 21.59)
		(end 35.9918 21.59)
		(width 0.12065)
		(layer "In6.Cu")
		(net "PCIE0_RST_L")
	)
	(segment
		(start 37.832563 21.082)
		(end 37.335104 21.579459)
		(width 0.12065)
		(layer "In6.Cu")
		(net "PCIE0_RST_L")
	)
	(segment
		(start 40.737003 21.541994)
		(end 40.464994 21.541994)
		(width 0.12065)
		(layer "In6.Cu")
		(net "PCIE0_RST_L")
	)
	(segment
		(start 15.575229 10.315575)
		(end 16.568953 11.309299)
		(width 0.12065)
		(layer "In6.Cu")
		(net "PCIE0_RST_L")
	)
	(segment
		(start 15.522575 10.315575)
		(end 15.575229 10.315575)
		(width 0.12065)
		(layer "In6.Cu")
		(net "PCIE0_RST_L")
	)
	(segment
		(start 14.859 3.683)
		(end 14.859 9.652)
		(width 0.12065)
		(layer "In6.Cu")
		(net "PCIE0_RST_L")
	)
	(segment
		(start 15.3924 3.1369)
		(end 15.3924 3.1496)
		(width 0.12065)
		(layer "In6.Cu")
		(net "PCIE0_RST_L")
	)
	(segment
		(start 14.859 9.652)
		(end 15.522575 10.315575)
		(width 0.12065)
		(layer "In6.Cu")
		(net "PCIE0_RST_L")
	)
	(segment
		(start 40.005 21.082)
		(end 37.832563 21.082)
		(width 0.12065)
		(layer "In6.Cu")
		(net "PCIE0_RST_L")
	)
	(segment
		(start 37.335104 21.579459)
		(end 37.010696 21.579459)
		(width 0.12065)
		(layer "In6.Cu")
		(net "PCIE0_RST_L")
	)
	(segment
		(start 37.010696 21.579459)
		(end 37.000155 21.59)
		(width 0.12065)
		(layer "In6.Cu")
		(net "PCIE0_RST_L")
	)
	(segment
		(start 15.3924 3.1496)
		(end 14.859 3.683)
		(width 0.12065)
		(layer "In6.Cu")
		(net "PCIE0_RST_L")
	)
	(segment
		(start 18.669 22.987)
		(end 18.669 16.129)
		(width 0.12065)
		(layer "In7.Cu")
		(net "PCIE0_RST_L")
	)
	(segment
		(start 18.288 12.827)
		(end 19.177 12.827)
		(width 0.12065)
		(layer "In7.Cu")
		(net "PCIE0_RST_L")
	)
	(segment
		(start 17.907 13.208)
		(end 18.288 12.827)
		(width 0.12065)
		(layer "In7.Cu")
		(net "PCIE0_RST_L")
	)
	(segment
		(start 18.669 16.129)
		(end 17.907 15.367)
		(width 0.12065)
		(layer "In7.Cu")
		(net "PCIE0_RST_L")
	)
	(segment
		(start 17.907 15.367)
		(end 17.907 13.208)
		(width 0.12065)
		(layer "In7.Cu")
		(net "PCIE0_RST_L")
	)
	(segment
		(start 18.415 23.241)
		(end 18.669 22.987)
		(width 0.12065)
		(layer "In7.Cu")
		(net "PCIE0_RST_L")
	)
	(segment
		(start 27.051 16.256)
		(end 27.305 16.002)
		(width 0.14732)
		(layer "F.Cu")
		(net "NFP_CPLD_INT_L")
	)
	(segment
		(start 27.773503 23.0759)
		(end 26.5303 23.0759)
		(width 0.127)
		(layer "F.Cu")
		(net "NFP_CPLD_INT_L")
	)
	(segment
		(start 26.1112 23.495)
		(end 25.654 23.495)
		(width 0.14732)
		(layer "F.Cu")
		(net "NFP_CPLD_INT_L")
	)
	(segment
		(start 28.245994 23.548391)
		(end 27.773503 23.0759)
		(width 0.127)
		(layer "F.Cu")
		(net "NFP_CPLD_INT_L")
	)
	(segment
		(start 26.035 18.415)
		(end 26.67 18.415)
		(width 0.14732)
		(layer "F.Cu")
		(net "NFP_CPLD_INT_L")
	)
	(segment
		(start 27.051 18.034)
		(end 27.051 16.256)
		(width 0.14732)
		(layer "F.Cu")
		(net "NFP_CPLD_INT_L")
	)
	(segment
		(start 26.67 18.415)
		(end 27.051 18.034)
		(width 0.14732)
		(layer "F.Cu")
		(net "NFP_CPLD_INT_L")
	)
	(segment
		(start 25.399949 20.83501)
		(end 25.42032 20.81464)
		(width 0.14732)
		(layer "F.Cu")
		(net "NFP_CPLD_INT_L")
	)
	(segment
		(start 26.5303 23.0759)
		(end 26.1112 23.495)
		(width 0.127)
		(layer "F.Cu")
		(net "NFP_CPLD_INT_L")
	)
	(segment
		(start 25.654 23.495)
		(end 25.399949 23.240949)
		(width 0.14732)
		(layer "F.Cu")
		(net "NFP_CPLD_INT_L")
	)
	(segment
		(start 25.42032 19.02968)
		(end 26.035 18.415)
		(width 0.14732)
		(layer "F.Cu")
		(net "NFP_CPLD_INT_L")
	)
	(segment
		(start 25.399949 23.240949)
		(end 25.399949 20.83501)
		(width 0.14732)
		(layer "F.Cu")
		(net "NFP_CPLD_INT_L")
	)
	(segment
		(start 25.42032 20.81464)
		(end 25.42032 19.02968)
		(width 0.14732)
		(layer "F.Cu")
		(net "NFP_CPLD_INT_L")
	)
	(segment
		(start 43.236998 14.042009)
		(end 42.736999 13.54201)
		(width 0.13208)
		(layer "F.Cu")
		(net "NFP_CPLD_INT_L")
	)
	(via
		(at 26.1112 23.495)
		(size 0.4572)
		(drill 0.20574)
		(layers "F.Cu" "B.Cu")
		(net "NFP_CPLD_INT_L")
	)
	(via
		(at 42.736999 13.54201)
		(size 0.4826)
		(drill 0.20574)
		(layers "F.Cu" "B.Cu")
		(net "NFP_CPLD_INT_L")
	)
	(via
		(at 27.305 16.002)
		(size 0.762)
		(drill 0.381)
		(layers "F.Cu" "B.Cu")
		(net "NFP_CPLD_INT_L")
	)
	(segment
		(start 27.186534 24.003)
		(end 27.097634 23.9141)
		(width 0.127)
		(layer "B.Cu")
		(net "NFP_CPLD_INT_L")
	)
	(segment
		(start 27.097634 23.9141)
		(end 26.5303 23.9141)
		(width 0.127)
		(layer "B.Cu")
		(net "NFP_CPLD_INT_L")
	)
	(segment
		(start 27.7749 24.003)
		(end 27.186534 24.003)
		(width 0.127)
		(layer "B.Cu")
		(net "NFP_CPLD_INT_L")
	)
	(segment
		(start 26.5303 23.9141)
		(end 26.1112 23.495)
		(width 0.127)
		(layer "B.Cu")
		(net "NFP_CPLD_INT_L")
	)
	(segment
		(start 43.333772 16.610228)
		(end 43.333772 16.374948)
		(width 0.12065)
		(layer "In2.Cu")
		(net "NFP_CPLD_INT_L")
	)
	(segment
		(start 35.296196 20.919059)
		(end 35.595941 20.919059)
		(width 0.12065)
		(layer "In2.Cu")
		(net "NFP_CPLD_INT_L")
	)
	(segment
		(start 43.333772 16.374948)
		(end 43.569941 16.138779)
		(width 0.12065)
		(layer "In2.Cu")
		(net "NFP_CPLD_INT_L")
	)
	(segment
		(start 26.1112 22.9108)
		(end 26.797 22.225)
		(width 0.12065)
		(layer "In2.Cu")
		(net "NFP_CPLD_INT_L")
	)
	(segment
		(start 26.797 22.225)
		(end 27.178 22.225)
		(width 0.12065)
		(layer "In2.Cu")
		(net "NFP_CPLD_INT_L")
	)
	(segment
		(start 42.569943 17.138777)
		(end 42.805223 17.138777)
		(width 0.12065)
		(layer "In2.Cu")
		(net "NFP_CPLD_INT_L")
	)
	(segment
		(start 44.323 15.621)
		(end 44.323 15.41239)
		(width 0.12065)
		(layer "In2.Cu")
		(net "NFP_CPLD_INT_L")
	)
	(segment
		(start 43.434 14.986)
		(end 43.338471 14.890471)
		(width 0.104648)
		(layer "In2.Cu")
		(net "NFP_CPLD_INT_L")
	)
	(segment
		(start 42.736999 13.691362)
		(end 42.736999 13.54201)
		(width 0.104648)
		(layer "In2.Cu")
		(net "NFP_CPLD_INT_L")
	)
	(segment
		(start 27.178 22.225)
		(end 27.432 21.971)
		(width 0.12065)
		(layer "In2.Cu")
		(net "NFP_CPLD_INT_L")
	)
	(segment
		(start 42.333774 17.374946)
		(end 42.569943 17.138777)
		(width 0.12065)
		(layer "In2.Cu")
		(net "NFP_CPLD_INT_L")
	)
	(segment
		(start 44.323 15.41239)
		(end 43.89661 14.986)
		(width 0.104648)
		(layer "In2.Cu")
		(net "NFP_CPLD_INT_L")
	)
	(segment
		(start 26.1112 23.495)
		(end 26.1112 22.9108)
		(width 0.12065)
		(layer "In2.Cu")
		(net "NFP_CPLD_INT_L")
	)
	(segment
		(start 41.783076 18.160924)
		(end 42.333774 17.610226)
		(width 0.12065)
		(layer "In2.Cu")
		(net "NFP_CPLD_INT_L")
	)
	(segment
		(start 39.5478 18.160924)
		(end 41.783076 18.160924)
		(width 0.12065)
		(layer "In2.Cu")
		(net "NFP_CPLD_INT_L")
	)
	(segment
		(start 43.805221 16.138779)
		(end 44.323 15.621)
		(width 0.12065)
		(layer "In2.Cu")
		(net "NFP_CPLD_INT_L")
	)
	(segment
		(start 43.569941 16.138779)
		(end 43.805221 16.138779)
		(width 0.12065)
		(layer "In2.Cu")
		(net "NFP_CPLD_INT_L")
	)
	(segment
		(start 42.805223 17.138777)
		(end 43.333772 16.610228)
		(width 0.12065)
		(layer "In2.Cu")
		(net "NFP_CPLD_INT_L")
	)
	(segment
		(start 35.824541 20.690459)
		(end 37.229186 20.690459)
		(width 0.12065)
		(layer "In2.Cu")
		(net "NFP_CPLD_INT_L")
	)
	(segment
		(start 37.229186 20.690459)
		(end 37.564441 20.355204)
		(width 0.12065)
		(layer "In2.Cu")
		(net "NFP_CPLD_INT_L")
	)
	(segment
		(start 37.564441 20.144283)
		(end 39.5478 18.160924)
		(width 0.12065)
		(layer "In2.Cu")
		(net "NFP_CPLD_INT_L")
	)
	(segment
		(start 43.338471 14.292834)
		(end 42.736999 13.691362)
		(width 0.104648)
		(layer "In2.Cu")
		(net "NFP_CPLD_INT_L")
	)
	(segment
		(start 34.244255 21.971)
		(end 35.296196 20.919059)
		(width 0.12065)
		(layer "In2.Cu")
		(net "NFP_CPLD_INT_L")
	)
	(segment
		(start 42.333774 17.610226)
		(end 42.333774 17.374946)
		(width 0.12065)
		(layer "In2.Cu")
		(net "NFP_CPLD_INT_L")
	)
	(segment
		(start 43.89661 14.986)
		(end 43.434 14.986)
		(width 0.104648)
		(layer "In2.Cu")
		(net "NFP_CPLD_INT_L")
	)
	(segment
		(start 43.338471 14.890471)
		(end 43.338471 14.292834)
		(width 0.104648)
		(layer "In2.Cu")
		(net "NFP_CPLD_INT_L")
	)
	(segment
		(start 37.564441 20.355204)
		(end 37.564441 20.144283)
		(width 0.12065)
		(layer "In2.Cu")
		(net "NFP_CPLD_INT_L")
	)
	(segment
		(start 35.595941 20.919059)
		(end 35.824541 20.690459)
		(width 0.12065)
		(layer "In2.Cu")
		(net "NFP_CPLD_INT_L")
	)
	(segment
		(start 27.432 21.971)
		(end 34.244255 21.971)
		(width 0.12065)
		(layer "In2.Cu")
		(net "NFP_CPLD_INT_L")
	)
	(segment
		(start 23.356011 34.416695)
		(end 23.633176 34.69386)
		(width 0.14732)
		(layer "F.Cu")
		(net "DEBUG_CPLD_PGRM_JTAG_TMS")
	)
	(segment
		(start 23.633176 34.69386)
		(end 24.06396 34.69386)
		(width 0.14732)
		(layer "F.Cu")
		(net "DEBUG_CPLD_PGRM_JTAG_TMS")
	)
	(segment
		(start 23.356011 34.0868)
		(end 23.356011 34.416695)
		(width 0.14732)
		(layer "F.Cu")
		(net "DEBUG_CPLD_PGRM_JTAG_TMS")
	)
	(segment
		(start 24.06396 34.69386)
		(end 24.638 35.2679)
		(width 0.14732)
		(layer "F.Cu")
		(net "DEBUG_CPLD_PGRM_JTAG_TMS")
	)
	(via
		(at 22.86 44.7675)
		(size 0.508)
		(drill 0.25654)
		(layers "F.Cu" "B.Cu")
		(net "DEBUG_CPLD_PGRM_JTAG_TMS")
	)
	(via
		(at 24.638 35.3568)
		(size 0.508)
		(drill 0.25654)
		(layers "F.Cu" "B.Cu")
		(net "DEBUG_CPLD_PGRM_JTAG_TMS")
	)
	(via
		(at 38.1 43.434)
		(size 0.508)
		(drill 0.254)
		(layers "F.Cu" "B.Cu")
		(net "DEBUG_CPLD_PGRM_JTAG_TMS")
	)
	(segment
		(start 38.1 43.434)
		(end 38.1 43.942)
		(width 0.14732)
		(layer "B.Cu")
		(net "DEBUG_CPLD_PGRM_JTAG_TMS")
	)
	(segment
		(start 38.1 43.942)
		(end 38.989 44.831)
		(width 0.14732)
		(layer "B.Cu")
		(net "DEBUG_CPLD_PGRM_JTAG_TMS")
	)
	(segment
		(start 38.1 44.439129)
		(end 38.1 43.434)
		(width 0.12065)
		(layer "In6.Cu")
		(net "DEBUG_CPLD_PGRM_JTAG_TMS")
	)
	(segment
		(start 30.984596 43.462575)
		(end 31.215025 43.232146)
		(width 0.12065)
		(layer "In6.Cu")
		(net "DEBUG_CPLD_PGRM_JTAG_TMS")
	)
	(segment
		(start 31.267908 43.232146)
		(end 31.666129 42.833925)
		(width 0.12065)
		(layer "In6.Cu")
		(net "DEBUG_CPLD_PGRM_JTAG_TMS")
	)
	(segment
		(start 35.496754 44.196)
		(end 36.573079 45.272325)
		(width 0.12065)
		(layer "In6.Cu")
		(net "DEBUG_CPLD_PGRM_JTAG_TMS")
	)
	(segment
		(start 31.666129 42.833925)
		(end 32.900696 42.833925)
		(width 0.12065)
		(layer "In6.Cu")
		(net "DEBUG_CPLD_PGRM_JTAG_TMS")
	)
	(segment
		(start 22.86 44.7675)
		(end 22.86 43.664048)
		(width 0.12065)
		(layer "In6.Cu")
		(net "DEBUG_CPLD_PGRM_JTAG_TMS")
	)
	(segment
		(start 22.86 43.664048)
		(end 24.388623 42.135425)
		(width 0.12065)
		(layer "In6.Cu")
		(net "DEBUG_CPLD_PGRM_JTAG_TMS")
	)
	(segment
		(start 29.162146 43.894248)
		(end 29.865498 43.894248)
		(width 0.12065)
		(layer "In6.Cu")
		(net "DEBUG_CPLD_PGRM_JTAG_TMS")
	)
	(segment
		(start 24.388623 42.135425)
		(end 27.403323 42.135425)
		(width 0.12065)
		(layer "In6.Cu")
		(net "DEBUG_CPLD_PGRM_JTAG_TMS")
	)
	(segment
		(start 33.84235 42.986325)
		(end 35.052025 44.196)
		(width 0.12065)
		(layer "In6.Cu")
		(net "DEBUG_CPLD_PGRM_JTAG_TMS")
	)
	(segment
		(start 35.052025 44.196)
		(end 35.496754 44.196)
		(width 0.12065)
		(layer "In6.Cu")
		(net "DEBUG_CPLD_PGRM_JTAG_TMS")
	)
	(segment
		(start 37.266804 45.272325)
		(end 38.1 44.439129)
		(width 0.12065)
		(layer "In6.Cu")
		(net "DEBUG_CPLD_PGRM_JTAG_TMS")
	)
	(segment
		(start 27.403323 42.135425)
		(end 29.162146 43.894248)
		(width 0.12065)
		(layer "In6.Cu")
		(net "DEBUG_CPLD_PGRM_JTAG_TMS")
	)
	(segment
		(start 31.215025 43.232146)
		(end 31.267908 43.232146)
		(width 0.12065)
		(layer "In6.Cu")
		(net "DEBUG_CPLD_PGRM_JTAG_TMS")
	)
	(segment
		(start 36.573079 45.272325)
		(end 37.266804 45.272325)
		(width 0.12065)
		(layer "In6.Cu")
		(net "DEBUG_CPLD_PGRM_JTAG_TMS")
	)
	(segment
		(start 32.900696 42.833925)
		(end 33.053096 42.986325)
		(width 0.12065)
		(layer "In6.Cu")
		(net "DEBUG_CPLD_PGRM_JTAG_TMS")
	)
	(segment
		(start 30.297171 43.462575)
		(end 30.984596 43.462575)
		(width 0.12065)
		(layer "In6.Cu")
		(net "DEBUG_CPLD_PGRM_JTAG_TMS")
	)
	(segment
		(start 33.053096 42.986325)
		(end 33.84235 42.986325)
		(width 0.12065)
		(layer "In6.Cu")
		(net "DEBUG_CPLD_PGRM_JTAG_TMS")
	)
	(segment
		(start 29.865498 43.894248)
		(end 30.297171 43.462575)
		(width 0.12065)
		(layer "In6.Cu")
		(net "DEBUG_CPLD_PGRM_JTAG_TMS")
	)
	(segment
		(start 23.749 37.211)
		(end 23.749 39.751025)
		(width 0.12065)
		(layer "In7.Cu")
		(net "DEBUG_CPLD_PGRM_JTAG_TMS")
	)
	(segment
		(start 23.749 39.751025)
		(end 23.12035 40.379675)
		(width 0.12065)
		(layer "In7.Cu")
		(net "DEBUG_CPLD_PGRM_JTAG_TMS")
	)
	(segment
		(start 24.638 36.322)
		(end 23.749 37.211)
		(width 0.12065)
		(layer "In7.Cu")
		(net "DEBUG_CPLD_PGRM_JTAG_TMS")
	)
	(segment
		(start 24.638 35.3568)
		(end 24.638 36.322)
		(width 0.12065)
		(layer "In7.Cu")
		(net "DEBUG_CPLD_PGRM_JTAG_TMS")
	)
	(segment
		(start 23.12035 40.379675)
		(end 23.12035 44.50715)
		(width 0.12065)
		(layer "In7.Cu")
		(net "DEBUG_CPLD_PGRM_JTAG_TMS")
	)
	(segment
		(start 23.12035 44.50715)
		(end 22.86 44.7675)
		(width 0.12065)
		(layer "In7.Cu")
		(net "DEBUG_CPLD_PGRM_JTAG_TMS")
	)
	(segment
		(start 21.855989 34.0868)
		(end 21.855989 35.152889)
		(width 0.14732)
		(layer "F.Cu")
		(net "DEBUG_CPLD_PGRM_JTAG_TDO")
	)
	(segment
		(start 21.855989 35.152889)
		(end 21.971 35.2679)
		(width 0.14732)
		(layer "F.Cu")
		(net "DEBUG_CPLD_PGRM_JTAG_TDO")
	)
	(via
		(at 21.59 45.0215)
		(size 0.508)
		(drill 0.25654)
		(layers "F.Cu" "B.Cu")
		(net "DEBUG_CPLD_PGRM_JTAG_TDO")
	)
	(via
		(at 21.971 35.2425)
		(size 0.508)
		(drill 0.25654)
		(layers "F.Cu" "B.Cu")
		(net "DEBUG_CPLD_PGRM_JTAG_TDO")
	)
	(via
		(at 37.084 44.831)
		(size 0.508)
		(drill 0.25654)
		(layers "F.Cu" "B.Cu")
		(net "DEBUG_CPLD_PGRM_JTAG_TDO")
	)
	(segment
		(start 29.994225 43.134229)
		(end 29.994225 43.030775)
		(width 0.12065)
		(layer "In6.Cu")
		(net "DEBUG_CPLD_PGRM_JTAG_TDO")
	)
	(segment
		(start 22.35835 44.25315)
		(end 22.35835 43.45625)
		(width 0.12065)
		(layer "In6.Cu")
		(net "DEBUG_CPLD_PGRM_JTAG_TDO")
	)
	(segment
		(start 29.370071 43.392725)
		(end 29.735729 43.392725)
		(width 0.12065)
		(layer "In6.Cu")
		(net "DEBUG_CPLD_PGRM_JTAG_TDO")
	)
	(segment
		(start 22.35835 43.45625)
		(end 24.7936 41.021)
		(width 0.12065)
		(layer "In6.Cu")
		(net "DEBUG_CPLD_PGRM_JTAG_TDO")
	)
	(segment
		(start 22.098 40.894)
		(end 21.209 41.783)
		(width 0.12065)
		(layer "In6.Cu")
		(net "DEBUG_CPLD_PGRM_JTAG_TDO")
	)
	(segment
		(start 21.209 44.6405)
		(end 21.59 45.0215)
		(width 0.12065)
		(layer "In6.Cu")
		(net "DEBUG_CPLD_PGRM_JTAG_TDO")
	)
	(segment
		(start 24.7936 41.021)
		(end 25.873126 41.021)
		(width 0.12065)
		(layer "In6.Cu")
		(net "DEBUG_CPLD_PGRM_JTAG_TDO")
	)
	(segment
		(start 29.111575 43.134204)
		(end 29.111575 43.134229)
		(width 0.12065)
		(layer "In6.Cu")
		(net "DEBUG_CPLD_PGRM_JTAG_TDO")
	)
	(segment
		(start 35.220402 43.654929)
		(end 35.372675 43.654929)
		(width 0.12065)
		(layer "In6.Cu")
		(net "DEBUG_CPLD_PGRM_JTAG_TDO")
	)
	(segment
		(start 29.994225 43.030775)
		(end 30.921325 42.103675)
		(width 0.12065)
		(layer "In6.Cu")
		(net "DEBUG_CPLD_PGRM_JTAG_TDO")
	)
	(segment
		(start 21.209 41.783)
		(end 21.209 44.6405)
		(width 0.12065)
		(layer "In6.Cu")
		(net "DEBUG_CPLD_PGRM_JTAG_TDO")
	)
	(segment
		(start 25.873126 41.021)
		(end 26.060451 40.833675)
		(width 0.12065)
		(layer "In6.Cu")
		(net "DEBUG_CPLD_PGRM_JTAG_TDO")
	)
	(segment
		(start 33.669148 42.103675)
		(end 35.220402 43.654929)
		(width 0.12065)
		(layer "In6.Cu")
		(net "DEBUG_CPLD_PGRM_JTAG_TDO")
	)
	(segment
		(start 27.271904 40.833675)
		(end 27.530425 41.092196)
		(width 0.12065)
		(layer "In6.Cu")
		(net "DEBUG_CPLD_PGRM_JTAG_TDO")
	)
	(segment
		(start 35.372675 43.654929)
		(end 36.548746 44.831)
		(width 0.12065)
		(layer "In6.Cu")
		(net "DEBUG_CPLD_PGRM_JTAG_TDO")
	)
	(segment
		(start 21.971 36.449)
		(end 22.098 36.576)
		(width 0.12065)
		(layer "In6.Cu")
		(net "DEBUG_CPLD_PGRM_JTAG_TDO")
	)
	(segment
		(start 27.530425 41.553054)
		(end 29.111575 43.134204)
		(width 0.12065)
		(layer "In6.Cu")
		(net "DEBUG_CPLD_PGRM_JTAG_TDO")
	)
	(segment
		(start 29.735729 43.392725)
		(end 29.994225 43.134229)
		(width 0.12065)
		(layer "In6.Cu")
		(net "DEBUG_CPLD_PGRM_JTAG_TDO")
	)
	(segment
		(start 29.111575 43.134229)
		(end 29.370071 43.392725)
		(width 0.12065)
		(layer "In6.Cu")
		(net "DEBUG_CPLD_PGRM_JTAG_TDO")
	)
	(segment
		(start 21.59 45.0215)
		(end 22.35835 44.25315)
		(width 0.12065)
		(layer "In6.Cu")
		(net "DEBUG_CPLD_PGRM_JTAG_TDO")
	)
	(segment
		(start 27.530425 41.092196)
		(end 27.530425 41.553054)
		(width 0.12065)
		(layer "In6.Cu")
		(net "DEBUG_CPLD_PGRM_JTAG_TDO")
	)
	(segment
		(start 36.548746 44.831)
		(end 37.084 44.831)
		(width 0.12065)
		(layer "In6.Cu")
		(net "DEBUG_CPLD_PGRM_JTAG_TDO")
	)
	(segment
		(start 30.921325 42.103675)
		(end 33.669148 42.103675)
		(width 0.12065)
		(layer "In6.Cu")
		(net "DEBUG_CPLD_PGRM_JTAG_TDO")
	)
	(segment
		(start 26.060451 40.833675)
		(end 27.271904 40.833675)
		(width 0.12065)
		(layer "In6.Cu")
		(net "DEBUG_CPLD_PGRM_JTAG_TDO")
	)
	(segment
		(start 21.971 35.2425)
		(end 21.971 36.449)
		(width 0.12065)
		(layer "In6.Cu")
		(net "DEBUG_CPLD_PGRM_JTAG_TDO")
	)
	(segment
		(start 22.098 36.576)
		(end 22.098 40.894)
		(width 0.12065)
		(layer "In6.Cu")
		(net "DEBUG_CPLD_PGRM_JTAG_TDO")
	)
	(segment
		(start 21.44268 30.58668)
		(end 20.955 30.099)
		(width 0.14732)
		(layer "F.Cu")
		(net "DEBUG_CPLD_PGRM_JTAG_TDI")
	)
	(segment
		(start 22.355988 31.6992)
		(end 22.352 31.695212)
		(width 0.14732)
		(layer "F.Cu")
		(net "DEBUG_CPLD_PGRM_JTAG_TDI")
	)
	(segment
		(start 21.95068 30.58668)
		(end 21.44268 30.58668)
		(width 0.14732)
		(layer "F.Cu")
		(net "DEBUG_CPLD_PGRM_JTAG_TDI")
	)
	(segment
		(start 20.955 30.099)
		(end 20.955 29.7815)
		(width 0.14732)
		(layer "F.Cu")
		(net "DEBUG_CPLD_PGRM_JTAG_TDI")
	)
	(segment
		(start 22.352 30.988)
		(end 21.95068 30.58668)
		(width 0.14732)
		(layer "F.Cu")
		(net "DEBUG_CPLD_PGRM_JTAG_TDI")
	)
	(segment
		(start 22.352 31.695212)
		(end 22.352 30.988)
		(width 0.14732)
		(layer "F.Cu")
		(net "DEBUG_CPLD_PGRM_JTAG_TDI")
	)
	(segment
		(start 20.955 29.7815)
		(end 20.955 29.7561)
		(width 0.14732)
		(layer "F.Cu")
		(net "DEBUG_CPLD_PGRM_JTAG_TDI")
	)
	(via
		(at 21.59 45.9105)
		(size 0.508)
		(drill 0.254)
		(layers "F.Cu" "B.Cu")
		(net "DEBUG_CPLD_PGRM_JTAG_TDI")
	)
	(via
		(at 35.179 45.212)
		(size 0.508)
		(drill 0.25654)
		(layers "F.Cu" "B.Cu")
		(net "DEBUG_CPLD_PGRM_JTAG_TDI")
	)
	(via
		(at 20.955 29.7815)
		(size 0.508)
		(drill 0.25654)
		(layers "F.Cu" "B.Cu")
		(net "DEBUG_CPLD_PGRM_JTAG_TDI")
	)
	(segment
		(start 21.1455 45.9105)
		(end 21.59 45.9105)
		(width 0.14732)
		(layer "B.Cu")
		(net "DEBUG_CPLD_PGRM_JTAG_TDI")
	)
	(segment
		(start 20.32 45.085)
		(end 21.1455 45.9105)
		(width 0.14732)
		(layer "B.Cu")
		(net "DEBUG_CPLD_PGRM_JTAG_TDI")
	)
	(segment
		(start 20.32 43.8785)
		(end 20.32 45.085)
		(width 0.14732)
		(layer "B.Cu")
		(net "DEBUG_CPLD_PGRM_JTAG_TDI")
	)
	(segment
		(start 32.908875 46.466125)
		(end 34.163 45.212)
		(width 0.12065)
		(layer "In3.Cu")
		(net "DEBUG_CPLD_PGRM_JTAG_TDI")
	)
	(segment
		(start 25.586004 46.355)
		(end 26.426846 46.355)
		(width 0.12065)
		(layer "In3.Cu")
		(net "DEBUG_CPLD_PGRM_JTAG_TDI")
	)
	(segment
		(start 26.426846 46.355)
		(end 26.537971 46.466125)
		(width 0.12065)
		(layer "In3.Cu")
		(net "DEBUG_CPLD_PGRM_JTAG_TDI")
	)
	(segment
		(start 34.163 45.212)
		(end 35.179 45.212)
		(width 0.12065)
		(layer "In3.Cu")
		(net "DEBUG_CPLD_PGRM_JTAG_TDI")
	)
	(segment
		(start 25.582829 46.351825)
		(end 25.586004 46.355)
		(width 0.12065)
		(layer "In3.Cu")
		(net "DEBUG_CPLD_PGRM_JTAG_TDI")
	)
	(segment
		(start 21.59 45.9105)
		(end 22.031325 46.351825)
		(width 0.12065)
		(layer "In3.Cu")
		(net "DEBUG_CPLD_PGRM_JTAG_TDI")
	)
	(segment
		(start 22.031325 46.351825)
		(end 25.582829 46.351825)
		(width 0.12065)
		(layer "In3.Cu")
		(net "DEBUG_CPLD_PGRM_JTAG_TDI")
	)
	(segment
		(start 26.537971 46.466125)
		(end 32.908875 46.466125)
		(width 0.12065)
		(layer "In3.Cu")
		(net "DEBUG_CPLD_PGRM_JTAG_TDI")
	)
	(segment
		(start 22.11705 43.086477)
		(end 19.81835 45.385177)
		(width 0.12065)
		(layer "In7.Cu")
		(net "DEBUG_CPLD_PGRM_JTAG_TDI")
	)
	(segment
		(start 22.418675 34.229675)
		(end 22.418675 38.847878)
		(width 0.12065)
		(layer "In7.Cu")
		(net "DEBUG_CPLD_PGRM_JTAG_TDI")
	)
	(segment
		(start 22.11705 39.149503)
		(end 22.11705 43.086477)
		(width 0.12065)
		(layer "In7.Cu")
		(net "DEBUG_CPLD_PGRM_JTAG_TDI")
	)
	(segment
		(start 21.0185 45.9105)
		(end 21.59 45.9105)
		(width 0.12065)
		(layer "In7.Cu")
		(net "DEBUG_CPLD_PGRM_JTAG_TDI")
	)
	(segment
		(start 20.955 29.7815)
		(end 21.209 30.0355)
		(width 0.12065)
		(layer "In7.Cu")
		(net "DEBUG_CPLD_PGRM_JTAG_TDI")
	)
	(segment
		(start 20.11205 46.41215)
		(end 20.52795 46.41215)
		(width 0.12065)
		(layer "In7.Cu")
		(net "DEBUG_CPLD_PGRM_JTAG_TDI")
	)
	(segment
		(start 20.52795 46.41215)
		(end 20.82165 46.11845)
		(width 0.12065)
		(layer "In7.Cu")
		(net "DEBUG_CPLD_PGRM_JTAG_TDI")
	)
	(segment
		(start 21.209 33.02)
		(end 22.418675 34.229675)
		(width 0.12065)
		(layer "In7.Cu")
		(net "DEBUG_CPLD_PGRM_JTAG_TDI")
	)
	(segment
		(start 19.81835 45.385177)
		(end 19.81835 46.11845)
		(width 0.12065)
		(layer "In7.Cu")
		(net "DEBUG_CPLD_PGRM_JTAG_TDI")
	)
	(segment
		(start 22.418675 38.847878)
		(end 22.11705 39.149503)
		(width 0.12065)
		(layer "In7.Cu")
		(net "DEBUG_CPLD_PGRM_JTAG_TDI")
	)
	(segment
		(start 21.209 30.0355)
		(end 21.209 33.02)
		(width 0.12065)
		(layer "In7.Cu")
		(net "DEBUG_CPLD_PGRM_JTAG_TDI")
	)
	(segment
		(start 20.82165 46.11845)
		(end 20.82165 46.10735)
		(width 0.12065)
		(layer "In7.Cu")
		(net "DEBUG_CPLD_PGRM_JTAG_TDI")
	)
	(segment
		(start 20.82165 46.10735)
		(end 21.0185 45.9105)
		(width 0.12065)
		(layer "In7.Cu")
		(net "DEBUG_CPLD_PGRM_JTAG_TDI")
	)
	(segment
		(start 19.81835 46.11845)
		(end 20.11205 46.41215)
		(width 0.12065)
		(layer "In7.Cu")
		(net "DEBUG_CPLD_PGRM_JTAG_TDI")
	)
	(segment
		(start 23.85601 30.28409)
		(end 24.384 29.7561)
		(width 0.14732)
		(layer "F.Cu")
		(net "DEBUG_CPLD_PGRM_JTAG_TCK")
	)
	(segment
		(start 23.85601 31.6992)
		(end 23.85601 30.28409)
		(width 0.14732)
		(layer "F.Cu")
		(net "DEBUG_CPLD_PGRM_JTAG_TCK")
	)
	(via
		(at 20.32 45.9105)
		(size 0.508)
		(drill 0.25654)
		(layers "F.Cu" "B.Cu")
		(net "DEBUG_CPLD_PGRM_JTAG_TCK")
	)
	(via
		(at 33.274 45.212)
		(size 0.508)
		(drill 0.25654)
		(layers "F.Cu" "B.Cu")
		(net "DEBUG_CPLD_PGRM_JTAG_TCK")
	)
	(via
		(at 24.384 29.7561)
		(size 0.508)
		(drill 0.25654)
		(layers "F.Cu" "B.Cu")
		(net "DEBUG_CPLD_PGRM_JTAG_TCK")
	)
	(segment
		(start 19.05 43.8785)
		(end 19.05 44.958)
		(width 0.14732)
		(layer "B.Cu")
		(net "DEBUG_CPLD_PGRM_JTAG_TCK")
	)
	(segment
		(start 19.05 44.958)
		(end 20.0025 45.9105)
		(width 0.14732)
		(layer "B.Cu")
		(net "DEBUG_CPLD_PGRM_JTAG_TCK")
	)
	(segment
		(start 20.0025 45.9105)
		(end 20.32 45.9105)
		(width 0.14732)
		(layer "B.Cu")
		(net "DEBUG_CPLD_PGRM_JTAG_TCK")
	)
	(segment
		(start 26.797025 45.339)
		(end 22.531654 45.339)
		(width 0.12065)
		(layer "In3.Cu")
		(net "DEBUG_CPLD_PGRM_JTAG_TCK")
	)
	(segment
		(start 22.531654 45.339)
		(end 21.772829 44.580175)
		(width 0.12065)
		(layer "In3.Cu")
		(net "DEBUG_CPLD_PGRM_JTAG_TCK")
	)
	(segment
		(start 32.893 45.593)
		(end 31.877 45.593)
		(width 0.12065)
		(layer "In3.Cu")
		(net "DEBUG_CPLD_PGRM_JTAG_TCK")
	)
	(segment
		(start 30.235525 45.964475)
		(end 27.4225 45.964475)
		(width 0.12065)
		(layer "In3.Cu")
		(net "DEBUG_CPLD_PGRM_JTAG_TCK")
	)
	(segment
		(start 21.407171 44.580175)
		(end 20.767675 45.219671)
		(width 0.12065)
		(layer "In3.Cu")
		(net "DEBUG_CPLD_PGRM_JTAG_TCK")
	)
	(segment
		(start 20.767675 45.219671)
		(end 20.767675 45.462825)
		(width 0.12065)
		(layer "In3.Cu")
		(net "DEBUG_CPLD_PGRM_JTAG_TCK")
	)
	(segment
		(start 27.4225 45.964475)
		(end 26.797025 45.339)
		(width 0.12065)
		(layer "In3.Cu")
		(net "DEBUG_CPLD_PGRM_JTAG_TCK")
	)
	(segment
		(start 21.772829 44.580175)
		(end 21.407171 44.580175)
		(width 0.12065)
		(layer "In3.Cu")
		(net "DEBUG_CPLD_PGRM_JTAG_TCK")
	)
	(segment
		(start 30.988 45.212)
		(end 30.235525 45.964475)
		(width 0.12065)
		(layer "In3.Cu")
		(net "DEBUG_CPLD_PGRM_JTAG_TCK")
	)
	(segment
		(start 31.877 45.593)
		(end 31.496 45.212)
		(width 0.12065)
		(layer "In3.Cu")
		(net "DEBUG_CPLD_PGRM_JTAG_TCK")
	)
	(segment
		(start 33.274 45.212)
		(end 32.893 45.593)
		(width 0.12065)
		(layer "In3.Cu")
		(net "DEBUG_CPLD_PGRM_JTAG_TCK")
	)
	(segment
		(start 20.767675 45.462825)
		(end 20.32 45.9105)
		(width 0.12065)
		(layer "In3.Cu")
		(net "DEBUG_CPLD_PGRM_JTAG_TCK")
	)
	(segment
		(start 31.496 45.212)
		(end 30.988 45.212)
		(width 0.12065)
		(layer "In3.Cu")
		(net "DEBUG_CPLD_PGRM_JTAG_TCK")
	)
	(segment
		(start 23.241 38.735)
		(end 22.6187 39.3573)
		(width 0.12065)
		(layer "In7.Cu")
		(net "DEBUG_CPLD_PGRM_JTAG_TCK")
	)
	(segment
		(start 23.301325 35.425329)
		(end 23.241 35.485654)
		(width 0.12065)
		(layer "In7.Cu")
		(net "DEBUG_CPLD_PGRM_JTAG_TCK")
	)
	(segment
		(start 23.301325 34.350325)
		(end 23.301325 35.425329)
		(width 0.12065)
		(layer "In7.Cu")
		(net "DEBUG_CPLD_PGRM_JTAG_TCK")
	)
	(segment
		(start 23.241 35.485654)
		(end 23.241 38.735)
		(width 0.12065)
		(layer "In7.Cu")
		(net "DEBUG_CPLD_PGRM_JTAG_TCK")
	)
	(segment
		(start 22.479 31.623)
		(end 22.479 33.528)
		(width 0.12065)
		(layer "In7.Cu")
		(net "DEBUG_CPLD_PGRM_JTAG_TCK")
	)
	(segment
		(start 22.6187 39.3573)
		(end 22.6187 43.294275)
		(width 0.12065)
		(layer "In7.Cu")
		(net "DEBUG_CPLD_PGRM_JTAG_TCK")
	)
	(segment
		(start 22.479 33.528)
		(end 23.301325 34.350325)
		(width 0.12065)
		(layer "In7.Cu")
		(net "DEBUG_CPLD_PGRM_JTAG_TCK")
	)
	(segment
		(start 24.3459 29.7561)
		(end 22.479 31.623)
		(width 0.12065)
		(layer "In7.Cu")
		(net "DEBUG_CPLD_PGRM_JTAG_TCK")
	)
	(segment
		(start 22.6187 43.294275)
		(end 20.32 45.592975)
		(width 0.12065)
		(layer "In7.Cu")
		(net "DEBUG_CPLD_PGRM_JTAG_TCK")
	)
	(segment
		(start 24.384 29.7561)
		(end 24.3459 29.7561)
		(width 0.12065)
		(layer "In7.Cu")
		(net "DEBUG_CPLD_PGRM_JTAG_TCK")
	)
	(segment
		(start 20.32 45.592975)
		(end 20.32 45.9105)
		(width 0.12065)
		(layer "In7.Cu")
		(net "DEBUG_CPLD_PGRM_JTAG_TCK")
	)
	(via
		(at 29.7561 19.3421)
		(size 0.762)
		(drill 0.381)
		(layers "F.Cu" "B.Cu")
		(net "CPLD_VERSION_2")
	)
	(via
		(at 30.3022 21.1074)
		(size 0.4572)
		(drill 0.20574)
		(layers "F.Cu" "B.Cu")
		(net "CPLD_VERSION_2")
	)
	(segment
		(start 29.8831 20.6883)
		(end 30.3022 21.1074)
		(width 0.127)
		(layer "B.Cu")
		(net "CPLD_VERSION_2")
	)
	(segment
		(start 28.829 21.9329)
		(end 28.829 21.496934)
		(width 0.127)
		(layer "B.Cu")
		(net "CPLD_VERSION_2")
	)
	(segment
		(start 29.7561 19.3421)
		(end 29.8831 19.4691)
		(width 0.127)
		(layer "B.Cu")
		(net "CPLD_VERSION_2")
	)
	(segment
		(start 29.290366 20.6883)
		(end 29.8831 20.6883)
		(width 0.127)
		(layer "B.Cu")
		(net "CPLD_VERSION_2")
	)
	(segment
		(start 28.829 21.496934)
		(end 29.0449 21.281034)
		(width 0.127)
		(layer "B.Cu")
		(net "CPLD_VERSION_2")
	)
	(segment
		(start 29.8831 19.4691)
		(end 29.8831 20.6883)
		(width 0.127)
		(layer "B.Cu")
		(net "CPLD_VERSION_2")
	)
	(segment
		(start 29.0449 20.933766)
		(end 29.290366 20.6883)
		(width 0.127)
		(layer "B.Cu")
		(net "CPLD_VERSION_2")
	)
	(segment
		(start 29.0449 21.281034)
		(end 29.0449 20.933766)
		(width 0.127)
		(layer "B.Cu")
		(net "CPLD_VERSION_2")
	)
	(segment
		(start 28.702 19.3421)
		(end 29.7561 19.3421)
		(width 0.127)
		(layer "B.Cu")
		(net "CPLD_VERSION_2")
	)
	(segment
		(start 30.3022 21.602192)
		(end 30.24599 21.658402)
		(width 0.127)
		(layer "In1.Cu")
		(net "CPLD_VERSION_2")
	)
	(segment
		(start 30.24599 21.658402)
		(end 30.24599 22.548393)
		(width 0.127)
		(layer "In1.Cu")
		(net "CPLD_VERSION_2")
	)
	(segment
		(start 30.3022 21.1074)
		(end 30.3022 21.602192)
		(width 0.127)
		(layer "In1.Cu")
		(net "CPLD_VERSION_2")
	)
	(segment
		(start 30.745989 23.610011)
		(end 30.745989 23.048392)
		(width 0.14732)
		(layer "F.Cu")
		(net "CPLD_VERSION_1")
	)
	(segment
		(start 30.7086 23.6474)
		(end 30.745989 23.610011)
		(width 0.14732)
		(layer "F.Cu")
		(net "CPLD_VERSION_1")
	)
	(via
		(at 30.7086 23.6474)
		(size 0.4572)
		(drill 0.20574)
		(layers "F.Cu" "B.Cu")
		(net "CPLD_VERSION_1")
	)
	(segment
		(start 29.8958 21.8059)
		(end 30.734 22.6441)
		(width 0.127)
		(layer "B.Cu")
		(net "CPLD_VERSION_1")
	)
	(segment
		(start 29.845 21.8059)
		(end 29.8958 21.8059)
		(width 0.127)
		(layer "B.Cu")
		(net "CPLD_VERSION_1")
	)
	(segment
		(start 30.734 23.622)
		(end 30.734 22.6441)
		(width 0.127)
		(layer "B.Cu")
		(net "CPLD_VERSION_1")
	)
	(segment
		(start 30.7086 23.6474)
		(end 30.734 23.622)
		(width 0.127)
		(layer "B.Cu")
		(net "CPLD_VERSION_1")
	)
	(via
		(at 31.1404 21.1074)
		(size 0.4572)
		(drill 0.20574)
		(layers "F.Cu" "B.Cu")
		(net "CPLD_VERSION_0")
	)
	(segment
		(start 33.87852 23.622)
		(end 33.45942 23.2029)
		(width 0.127)
		(layer "B.Cu")
		(net "CPLD_VERSION_0")
	)
	(segment
		(start 33.45942 23.2029)
		(end 32.892797 23.2029)
		(width 0.127)
		(layer "B.Cu")
		(net "CPLD_VERSION_0")
	)
	(segment
		(start 32.385 22.733)
		(end 32.385 21.971)
		(width 0.127)
		(layer "B.Cu")
		(net "CPLD_VERSION_0")
	)
	(segment
		(start 32.385 21.971)
		(end 32.258 21.844)
		(width 0.127)
		(layer "B.Cu")
		(net "CPLD_VERSION_0")
	)
	(segment
		(start 31.9151 21.844)
		(end 31.877 21.8059)
		(width 0.127)
		(layer "B.Cu")
		(net "CPLD_VERSION_0")
	)
	(segment
		(start 31.8389 21.8059)
		(end 31.877 21.8059)
		(width 0.127)
		(layer "B.Cu")
		(net "CPLD_VERSION_0")
	)
	(segment
		(start 32.422897 22.733)
		(end 32.385 22.733)
		(width 0.127)
		(layer "B.Cu")
		(net "CPLD_VERSION_0")
	)
	(segment
		(start 32.258 21.844)
		(end 31.9151 21.844)
		(width 0.127)
		(layer "B.Cu")
		(net "CPLD_VERSION_0")
	)
	(segment
		(start 31.1404 21.1074)
		(end 31.8389 21.8059)
		(width 0.127)
		(layer "B.Cu")
		(net "CPLD_VERSION_0")
	)
	(segment
		(start 32.892797 23.2029)
		(end 32.422897 22.733)
		(width 0.127)
		(layer "B.Cu")
		(net "CPLD_VERSION_0")
	)
	(segment
		(start 31.245988 21.717)
		(end 31.245988 22.548393)
		(width 0.127)
		(layer "In1.Cu")
		(net "CPLD_VERSION_0")
	)
	(segment
		(start 31.1404 21.611412)
		(end 31.245988 21.717)
		(width 0.127)
		(layer "In1.Cu")
		(net "CPLD_VERSION_0")
	)
	(segment
		(start 31.1404 21.1074)
		(end 31.1404 21.611412)
		(width 0.127)
		(layer "In1.Cu")
		(net "CPLD_VERSION_0")
	)
	(segment
		(start 32.246011 28.548406)
		(end 32.246011 28.586989)
		(width 0.127)
		(layer "F.Cu")
		(net "CPLD_PGRM_JTAG_TMS")
	)
	(segment
		(start 22.355988 34.0868)
		(end 22.355988 34.763888)
		(width 0.14732)
		(layer "F.Cu")
		(net "CPLD_PGRM_JTAG_TMS")
	)
	(segment
		(start 32.246011 28.586989)
		(end 31.75 29.083)
		(width 0.127)
		(layer "F.Cu")
		(net "CPLD_PGRM_JTAG_TMS")
	)
	(segment
		(start 30.6451 29.569766)
		(end 30.6451 30.1371)
		(width 0.127)
		(layer "F.Cu")
		(net "CPLD_PGRM_JTAG_TMS")
	)
	(segment
		(start 31.75 29.083)
		(end 31.131866 29.083)
		(width 0.127)
		(layer "F.Cu")
		(net "CPLD_PGRM_JTAG_TMS")
	)
	(segment
		(start 22.355988 34.763888)
		(end 22.86 35.2679)
		(width 0.14732)
		(layer "F.Cu")
		(net "CPLD_PGRM_JTAG_TMS")
	)
	(segment
		(start 31.131866 29.083)
		(end 30.6451 29.569766)
		(width 0.127)
		(layer "F.Cu")
		(net "CPLD_PGRM_JTAG_TMS")
	)
	(segment
		(start 30.6451 30.1371)
		(end 31.0642 30.5562)
		(width 0.14732)
		(layer "F.Cu")
		(net "CPLD_PGRM_JTAG_TMS")
	)
	(via
		(at 31.0642 30.5562)
		(size 0.4572)
		(drill 0.20574)
		(layers "F.Cu" "B.Cu")
		(net "CPLD_PGRM_JTAG_TMS")
	)
	(via
		(at 22.86 35.2425)
		(size 0.508)
		(drill 0.25654)
		(layers "F.Cu" "B.Cu")
		(net "CPLD_PGRM_JTAG_TMS")
	)
	(segment
		(start 23.368 34.671)
		(end 28.702 34.671)
		(width 0.12065)
		(layer "In2.Cu")
		(net "CPLD_PGRM_JTAG_TMS")
	)
	(segment
		(start 30.540325 31.080075)
		(end 31.0642 30.5562)
		(width 0.12065)
		(layer "In2.Cu")
		(net "CPLD_PGRM_JTAG_TMS")
	)
	(segment
		(start 30.540325 31.683325)
		(end 30.540325 31.080075)
		(width 0.12065)
		(layer "In2.Cu")
		(net "CPLD_PGRM_JTAG_TMS")
	)
	(segment
		(start 22.86 35.2425)
		(end 22.86 35.179)
		(width 0.12065)
		(layer "In2.Cu")
		(net "CPLD_PGRM_JTAG_TMS")
	)
	(segment
		(start 30.734 32.639)
		(end 30.734 31.877)
		(width 0.12065)
		(layer "In2.Cu")
		(net "CPLD_PGRM_JTAG_TMS")
	)
	(segment
		(start 28.702 34.671)
		(end 30.734 32.639)
		(width 0.12065)
		(layer "In2.Cu")
		(net "CPLD_PGRM_JTAG_TMS")
	)
	(segment
		(start 30.734 31.877)
		(end 30.540325 31.683325)
		(width 0.12065)
		(layer "In2.Cu")
		(net "CPLD_PGRM_JTAG_TMS")
	)
	(segment
		(start 22.86 35.179)
		(end 23.368 34.671)
		(width 0.12065)
		(layer "In2.Cu")
		(net "CPLD_PGRM_JTAG_TMS")
	)
	(segment
		(start 20.9042 34.5567)
		(end 20.193 35.2679)
		(width 0.14732)
		(layer "F.Cu")
		(net "CPLD_PGRM_JTAG_TDO")
	)
	(segment
		(start 20.9042 33.143012)
		(end 20.9042 34.5567)
		(width 0.14732)
		(layer "F.Cu")
		(net "CPLD_PGRM_JTAG_TDO")
	)
	(via
		(at 30.226 29.7434)
		(size 0.4572)
		(drill 0.20574)
		(layers "F.Cu" "B.Cu")
		(net "CPLD_PGRM_JTAG_TDO")
	)
	(via
		(at 20.0914 35.2425)
		(size 0.508)
		(drill 0.25654)
		(layers "F.Cu" "B.Cu")
		(net "CPLD_PGRM_JTAG_TDO")
	)
	(segment
		(start 33.401 27.9019)
		(end 32.512 27.9019)
		(width 0.14732)
		(layer "B.Cu")
		(net "CPLD_PGRM_JTAG_TDO")
	)
	(segment
		(start 31.242 28.829)
		(end 31.1404 28.829)
		(width 0.14732)
		(layer "B.Cu")
		(net "CPLD_PGRM_JTAG_TDO")
	)
	(segment
		(start 31.1404 28.829)
		(end 30.226 29.7434)
		(width 0.14732)
		(layer "B.Cu")
		(net "CPLD_PGRM_JTAG_TDO")
	)
	(segment
		(start 31.9151 28.1559)
		(end 31.242 28.829)
		(width 0.14732)
		(layer "B.Cu")
		(net "CPLD_PGRM_JTAG_TDO")
	)
	(segment
		(start 32.512 27.9019)
		(end 31.9151 28.1559)
		(width 0.14732)
		(layer "B.Cu")
		(net "CPLD_PGRM_JTAG_TDO")
	)
	(segment
		(start 27.249171 33.340675)
		(end 28.127325 33.340675)
		(width 0.12065)
		(layer "In2.Cu")
		(net "CPLD_PGRM_JTAG_TDO")
	)
	(segment
		(start 30.226 30.490846)
		(end 30.226 29.7434)
		(width 0.12065)
		(layer "In2.Cu")
		(net "CPLD_PGRM_JTAG_TDO")
	)
	(segment
		(start 21.717 33.655)
		(end 26.934846 33.655)
		(width 0.12065)
		(layer "In2.Cu")
		(net "CPLD_PGRM_JTAG_TDO")
	)
	(segment
		(start 28.127325 33.340675)
		(end 29.657675 31.810325)
		(width 0.12065)
		(layer "In2.Cu")
		(net "CPLD_PGRM_JTAG_TDO")
	)
	(segment
		(start 26.934846 33.655)
		(end 27.249171 33.340675)
		(width 0.12065)
		(layer "In2.Cu")
		(net "CPLD_PGRM_JTAG_TDO")
	)
	(segment
		(start 29.657675 31.810325)
		(end 29.657675 31.059171)
		(width 0.12065)
		(layer "In2.Cu")
		(net "CPLD_PGRM_JTAG_TDO")
	)
	(segment
		(start 20.0914 35.2425)
		(end 21.717 33.655)
		(width 0.12065)
		(layer "In2.Cu")
		(net "CPLD_PGRM_JTAG_TDO")
	)
	(segment
		(start 29.657675 31.059171)
		(end 30.226 30.490846)
		(width 0.12065)
		(layer "In2.Cu")
		(net "CPLD_PGRM_JTAG_TDO")
	)
	(segment
		(start 21.35599 31.6992)
		(end 21.35599 31.515964)
		(width 0.14732)
		(layer "F.Cu")
		(net "CPLD_PGRM_JTAG_TDI")
	)
	(segment
		(start 21.35599 31.515964)
		(end 20.066 30.225975)
		(width 0.14732)
		(layer "F.Cu")
		(net "CPLD_PGRM_JTAG_TDI")
	)
	(segment
		(start 20.066 29.706291)
		(end 19.823709 29.464)
		(width 0.14732)
		(layer "F.Cu")
		(net "CPLD_PGRM_JTAG_TDI")
	)
	(segment
		(start 20.066 30.225975)
		(end 20.066 29.706291)
		(width 0.14732)
		(layer "F.Cu")
		(net "CPLD_PGRM_JTAG_TDI")
	)
	(segment
		(start 19.823709 29.464)
		(end 19.4691 29.464)
		(width 0.14732)
		(layer "F.Cu")
		(net "CPLD_PGRM_JTAG_TDI")
	)
	(via
		(at 19.4691 29.464)
		(size 0.508)
		(drill 0.25654)
		(layers "F.Cu" "B.Cu")
		(net "CPLD_PGRM_JTAG_TDI")
	)
	(via
		(at 33.528 30.353)
		(size 0.4572)
		(drill 0.20574)
		(layers "F.Cu" "B.Cu")
		(net "CPLD_PGRM_JTAG_TDI")
	)
	(segment
		(start 33.528 29.7434)
		(end 33.401 29.6164)
		(width 0.14732)
		(layer "B.Cu")
		(net "CPLD_PGRM_JTAG_TDI")
	)
	(segment
		(start 33.401 29.6164)
		(end 33.401 28.7401)
		(width 0.14732)
		(layer "B.Cu")
		(net "CPLD_PGRM_JTAG_TDI")
	)
	(segment
		(start 33.528 30.353)
		(end 33.528 29.7434)
		(width 0.14732)
		(layer "B.Cu")
		(net "CPLD_PGRM_JTAG_TDI")
	)
	(segment
		(start 33.528 29.7434)
		(end 33.246009 29.461409)
		(width 0.12065)
		(layer "In1.Cu")
		(net "CPLD_PGRM_JTAG_TDI")
	)
	(segment
		(start 33.528 30.353)
		(end 33.528 29.7434)
		(width 0.12065)
		(layer "In1.Cu")
		(net "CPLD_PGRM_JTAG_TDI")
	)
	(segment
		(start 33.246009 29.461409)
		(end 33.246009 28.048407)
		(width 0.12065)
		(layer "In1.Cu")
		(net "CPLD_PGRM_JTAG_TDI")
	)
	(segment
		(start 22.329775 29.314775)
		(end 21.915171 29.314775)
		(width 0.12065)
		(layer "In2.Cu")
		(net "CPLD_PGRM_JTAG_TDI")
	)
	(segment
		(start 33.528 30.353)
		(end 33.528 29.7434)
		(width 0.12065)
		(layer "In2.Cu")
		(net "CPLD_PGRM_JTAG_TDI")
	)
	(segment
		(start 22.799675 29.784675)
		(end 22.329775 29.314775)
		(width 0.12065)
		(layer "In2.Cu")
		(net "CPLD_PGRM_JTAG_TDI")
	)
	(segment
		(start 27.178 28.829)
		(end 25.809575 30.197425)
		(width 0.12065)
		(layer "In2.Cu")
		(net "CPLD_PGRM_JTAG_TDI")
	)
	(segment
		(start 22.799675 29.938929)
		(end 22.799675 29.784675)
		(width 0.12065)
		(layer "In2.Cu")
		(net "CPLD_PGRM_JTAG_TDI")
	)
	(segment
		(start 32.6136 28.829)
		(end 27.178 28.829)
		(width 0.12065)
		(layer "In2.Cu")
		(net "CPLD_PGRM_JTAG_TDI")
	)
	(segment
		(start 21.896121 29.333825)
		(end 19.638137 29.333825)
		(width 0.12065)
		(layer "In2.Cu")
		(net "CPLD_PGRM_JTAG_TDI")
	)
	(segment
		(start 19.638137 29.333825)
		(end 19.4691 29.464)
		(width 0.12065)
		(layer "In2.Cu")
		(net "CPLD_PGRM_JTAG_TDI")
	)
	(segment
		(start 33.528 29.7434)
		(end 32.6136 28.829)
		(width 0.12065)
		(layer "In2.Cu")
		(net "CPLD_PGRM_JTAG_TDI")
	)
	(segment
		(start 25.809575 30.197425)
		(end 23.058171 30.197425)
		(width 0.12065)
		(layer "In2.Cu")
		(net "CPLD_PGRM_JTAG_TDI")
	)
	(segment
		(start 23.058171 30.197425)
		(end 22.799675 29.938929)
		(width 0.12065)
		(layer "In2.Cu")
		(net "CPLD_PGRM_JTAG_TDI")
	)
	(segment
		(start 21.915171 29.314775)
		(end 21.896121 29.333825)
		(width 0.12065)
		(layer "In2.Cu")
		(net "CPLD_PGRM_JTAG_TDI")
	)
	(segment
		(start 22.856012 30.857012)
		(end 22.856012 31.6992)
		(width 0.14732)
		(layer "F.Cu")
		(net "CPLD_PGRM_JTAG_TCK")
	)
	(segment
		(start 22.098 29.7561)
		(end 22.098 30.099)
		(width 0.14732)
		(layer "F.Cu")
		(net "CPLD_PGRM_JTAG_TCK")
	)
	(segment
		(start 22.098 30.099)
		(end 22.856012 30.857012)
		(width 0.14732)
		(layer "F.Cu")
		(net "CPLD_PGRM_JTAG_TCK")
	)
	(via
		(at 22.098 29.7561)
		(size 0.508)
		(drill 0.25654)
		(layers "F.Cu" "B.Cu")
		(net "CPLD_PGRM_JTAG_TCK")
	)
	(via
		(at 31.0642 29.7434)
		(size 0.4572)
		(drill 0.20574)
		(layers "F.Cu" "B.Cu")
		(net "CPLD_PGRM_JTAG_TCK")
	)
	(segment
		(start 32.246011 28.048407)
		(end 32.246011 28.561589)
		(width 0.12065)
		(layer "In1.Cu")
		(net "CPLD_PGRM_JTAG_TCK")
	)
	(segment
		(start 32.246011 28.561589)
		(end 31.0642 29.7434)
		(width 0.12065)
		(layer "In1.Cu")
		(net "CPLD_PGRM_JTAG_TCK")
	)
	(segment
		(start 22.098 29.7561)
		(end 22.098 29.972)
		(width 0.12065)
		(layer "In2.Cu")
		(net "CPLD_PGRM_JTAG_TCK")
	)
	(segment
		(start 31.0642 29.712107)
		(end 31.0642 29.7434)
		(width 0.12065)
		(layer "In2.Cu")
		(net "CPLD_PGRM_JTAG_TCK")
	)
	(segment
		(start 22.098 29.972)
		(end 22.733 30.607)
		(width 0.12065)
		(layer "In2.Cu")
		(net "CPLD_PGRM_JTAG_TCK")
	)
	(segment
		(start 22.850373 30.699075)
		(end 25.942925 30.699075)
		(width 0.12065)
		(layer "In2.Cu")
		(net "CPLD_PGRM_JTAG_TCK")
	)
	(segment
		(start 22.733 30.607)
		(end 22.758298 30.607)
		(width 0.12065)
		(layer "In2.Cu")
		(net "CPLD_PGRM_JTAG_TCK")
	)
	(segment
		(start 30.480686 29.128593)
		(end 31.0642 29.712107)
		(width 0.12065)
		(layer "In2.Cu")
		(net "CPLD_PGRM_JTAG_TCK")
	)
	(segment
		(start 27.513407 29.128593)
		(end 30.480686 29.128593)
		(width 0.12065)
		(layer "In2.Cu")
		(net "CPLD_PGRM_JTAG_TCK")
	)
	(segment
		(start 25.942925 30.699075)
		(end 27.513407 29.128593)
		(width 0.12065)
		(layer "In2.Cu")
		(net "CPLD_PGRM_JTAG_TCK")
	)
	(segment
		(start 22.758298 30.607)
		(end 22.850373 30.699075)
		(width 0.12065)
		(layer "In2.Cu")
		(net "CPLD_PGRM_JTAG_TCK")
	)
	(segment
		(start 25.146 30.1371)
		(end 25.146 32.385)
		(width 0.14732)
		(layer "F.Cu")
		(net "CPLD_PGRM_JTAG_SEL")
	)
	(segment
		(start 44.236996 13.042011)
		(end 43.736997 12.542012)
		(width 0.13208)
		(layer "F.Cu")
		(net "CPLD_PGRM_JTAG_SEL")
	)
	(segment
		(start 24.888012 32.642988)
		(end 24.3078 32.642988)
		(width 0.14732)
		(layer "F.Cu")
		(net "CPLD_PGRM_JTAG_SEL")
	)
	(segment
		(start 25.146 32.385)
		(end 24.888012 32.642988)
		(width 0.14732)
		(layer "F.Cu")
		(net "CPLD_PGRM_JTAG_SEL")
	)
	(segment
		(start 25.527 29.7561)
		(end 25.146 30.1371)
		(width 0.14732)
		(layer "F.Cu")
		(net "CPLD_PGRM_JTAG_SEL")
	)
	(via
		(at 25.527 29.7561)
		(size 0.508)
		(drill 0.25654)
		(layers "F.Cu" "B.Cu")
		(net "CPLD_PGRM_JTAG_SEL")
	)
	(via
		(at 43.736997 12.542012)
		(size 0.4826)
		(drill 0.20574)
		(layers "F.Cu" "B.Cu")
		(net "CPLD_PGRM_JTAG_SEL")
	)
	(segment
		(start 42.728769 15.945231)
		(end 42.904054 15.945231)
		(width 0.12065)
		(layer "In3.Cu")
		(net "CPLD_PGRM_JTAG_SEL")
	)
	(segment
		(start 34.085886 23.064089)
		(end 35.54857 23.064089)
		(width 0.12065)
		(layer "In3.Cu")
		(net "CPLD_PGRM_JTAG_SEL")
	)
	(segment
		(start 36.514659 22.544659)
		(end 36.83 22.86)
		(width 0.12065)
		(layer "In3.Cu")
		(net "CPLD_PGRM_JTAG_SEL")
	)
	(segment
		(start 41.148 17.560722)
		(end 41.763493 16.945229)
		(width 0.12065)
		(layer "In3.Cu")
		(net "CPLD_PGRM_JTAG_SEL")
	)
	(segment
		(start 26.3271 28.956)
		(end 31.435802 28.956)
		(width 0.12065)
		(layer "In3.Cu")
		(net "CPLD_PGRM_JTAG_SEL")
	)
	(segment
		(start 43.307 15.542285)
		(end 43.307 13.335)
		(width 0.12065)
		(layer "In3.Cu")
		(net "CPLD_PGRM_JTAG_SEL")
	)
	(segment
		(start 36.83 22.86)
		(end 36.957 22.86)
		(width 0.12065)
		(layer "In3.Cu")
		(net "CPLD_PGRM_JTAG_SEL")
	)
	(segment
		(start 35.54857 23.064089)
		(end 36.068 22.544659)
		(width 0.12065)
		(layer "In3.Cu")
		(net "CPLD_PGRM_JTAG_SEL")
	)
	(segment
		(start 43.736997 12.905003)
		(end 43.736997 12.542012)
		(width 0.12065)
		(layer "In3.Cu")
		(net "CPLD_PGRM_JTAG_SEL")
	)
	(segment
		(start 42.164 16.51)
		(end 42.728769 15.945231)
		(width 0.12065)
		(layer "In3.Cu")
		(net "CPLD_PGRM_JTAG_SEL")
	)
	(segment
		(start 33.614741 26.777061)
		(end 33.614741 23.535234)
		(width 0.12065)
		(layer "In3.Cu")
		(net "CPLD_PGRM_JTAG_SEL")
	)
	(segment
		(start 43.307 13.335)
		(end 43.736997 12.905003)
		(width 0.12065)
		(layer "In3.Cu")
		(net "CPLD_PGRM_JTAG_SEL")
	)
	(segment
		(start 36.068 22.544659)
		(end 36.514659 22.544659)
		(width 0.12065)
		(layer "In3.Cu")
		(net "CPLD_PGRM_JTAG_SEL")
	)
	(segment
		(start 42.904054 15.945231)
		(end 43.307 15.542285)
		(width 0.12065)
		(layer "In3.Cu")
		(net "CPLD_PGRM_JTAG_SEL")
	)
	(segment
		(start 36.957 22.86)
		(end 37.084 22.987)
		(width 0.12065)
		(layer "In3.Cu")
		(net "CPLD_PGRM_JTAG_SEL")
	)
	(segment
		(start 42.164 16.685285)
		(end 42.164 16.51)
		(width 0.12065)
		(layer "In3.Cu")
		(net "CPLD_PGRM_JTAG_SEL")
	)
	(segment
		(start 25.527 29.7561)
		(end 26.3271 28.956)
		(width 0.12065)
		(layer "In3.Cu")
		(net "CPLD_PGRM_JTAG_SEL")
	)
	(segment
		(start 41.904056 16.945229)
		(end 42.164 16.685285)
		(width 0.12065)
		(layer "In3.Cu")
		(net "CPLD_PGRM_JTAG_SEL")
	)
	(segment
		(start 31.435802 28.956)
		(end 33.614741 26.777061)
		(width 0.12065)
		(layer "In3.Cu")
		(net "CPLD_PGRM_JTAG_SEL")
	)
	(segment
		(start 41.763493 16.945229)
		(end 41.904056 16.945229)
		(width 0.12065)
		(layer "In3.Cu")
		(net "CPLD_PGRM_JTAG_SEL")
	)
	(segment
		(start 33.614741 23.535234)
		(end 34.085886 23.064089)
		(width 0.12065)
		(layer "In3.Cu")
		(net "CPLD_PGRM_JTAG_SEL")
	)
	(segment
		(start 41.148 22.733)
		(end 41.148 17.560722)
		(width 0.12065)
		(layer "In3.Cu")
		(net "CPLD_PGRM_JTAG_SEL")
	)
	(segment
		(start 37.084 22.987)
		(end 40.894 22.987)
		(width 0.12065)
		(layer "In3.Cu")
		(net "CPLD_PGRM_JTAG_SEL")
	)
	(segment
		(start 40.894 22.987)
		(end 41.148 22.733)
		(width 0.12065)
		(layer "In3.Cu")
		(net "CPLD_PGRM_JTAG_SEL")
	)
	(segment
		(start 33.746008 23.048392)
		(end 33.2232 23.622)
		(width 0.14732)
		(layer "F.Cu")
		(net "CPLD_GPIO_3")
	)
	(via
		(at 27.94 48.9585)
		(size 0.508)
		(drill 0.25654)
		(layers "F.Cu" "B.Cu")
		(net "CPLD_GPIO_3")
	)
	(via
		(at 7.112 40.64)
		(size 0.508)
		(drill 0.25654)
		(layers "F.Cu" "B.Cu")
		(net "CPLD_GPIO_3")
	)
	(via
		(at 33.2232 23.622)
		(size 0.4572)
		(drill 0.20574)
		(layers "F.Cu" "B.Cu")
		(net "CPLD_GPIO_3")
	)
	(segment
		(start 13.831672 49.264672)
		(end 10.795 46.228)
		(width 0.12065)
		(layer "In7.Cu")
		(net "CPLD_GPIO_3")
	)
	(segment
		(start 27.94 48.895)
		(end 27.305 48.26)
		(width 0.12065)
		(layer "In7.Cu")
		(net "CPLD_GPIO_3")
	)
	(segment
		(start 33.2232 23.622)
		(end 33.2232 23.6982)
		(width 0.12065)
		(layer "In7.Cu")
		(net "CPLD_GPIO_3")
	)
	(segment
		(start 34.417 29.083)
		(end 34.732341 29.398341)
		(width 0.12065)
		(layer "In7.Cu")
		(net "CPLD_GPIO_3")
	)
	(segment
		(start 34.732341 29.398341)
		(end 34.732341 29.926686)
		(width 0.12065)
		(layer "In7.Cu")
		(net "CPLD_GPIO_3")
	)
	(segment
		(start 27.94 48.9585)
		(end 27.94 48.895)
		(width 0.12065)
		(layer "In7.Cu")
		(net "CPLD_GPIO_3")
	)
	(segment
		(start 20.32 48.26)
		(end 19.315328 49.264672)
		(width 0.12065)
		(layer "In7.Cu")
		(net "CPLD_GPIO_3")
	)
	(segment
		(start 34.732341 29.926686)
		(end 34.991675 30.18602)
		(width 0.12065)
		(layer "In7.Cu")
		(net "CPLD_GPIO_3")
	)
	(segment
		(start 31.772225 44.883121)
		(end 31.753175 44.902171)
		(width 0.12065)
		(layer "In7.Cu")
		(net "CPLD_GPIO_3")
	)
	(segment
		(start 31.772225 39.220775)
		(end 31.772225 44.883121)
		(width 0.12065)
		(layer "In7.Cu")
		(net "CPLD_GPIO_3")
	)
	(segment
		(start 32.258 38.735)
		(end 31.772225 39.220775)
		(width 0.12065)
		(layer "In7.Cu")
		(net "CPLD_GPIO_3")
	)
	(segment
		(start 33.2232 23.6982)
		(end 34.417 24.892)
		(width 0.12065)
		(layer "In7.Cu")
		(net "CPLD_GPIO_3")
	)
	(segment
		(start 31.810325 45.324979)
		(end 31.810325 47.056675)
		(width 0.12065)
		(layer "In7.Cu")
		(net "CPLD_GPIO_3")
	)
	(segment
		(start 33.147 38.354)
		(end 32.766 38.735)
		(width 0.12065)
		(layer "In7.Cu")
		(net "CPLD_GPIO_3")
	)
	(segment
		(start 34.036 34.798)
		(end 33.147 35.687)
		(width 0.12065)
		(layer "In7.Cu")
		(net "CPLD_GPIO_3")
	)
	(segment
		(start 19.315328 49.264672)
		(end 13.831672 49.264672)
		(width 0.12065)
		(layer "In7.Cu")
		(net "CPLD_GPIO_3")
	)
	(segment
		(start 32.766 38.735)
		(end 32.258 38.735)
		(width 0.12065)
		(layer "In7.Cu")
		(net "CPLD_GPIO_3")
	)
	(segment
		(start 29.9085 48.9585)
		(end 27.94 48.9585)
		(width 0.12065)
		(layer "In7.Cu")
		(net "CPLD_GPIO_3")
	)
	(segment
		(start 34.744025 32.60758)
		(end 34.036 33.315605)
		(width 0.12065)
		(layer "In7.Cu")
		(net "CPLD_GPIO_3")
	)
	(segment
		(start 31.753175 45.267829)
		(end 31.810325 45.324979)
		(width 0.12065)
		(layer "In7.Cu")
		(net "CPLD_GPIO_3")
	)
	(segment
		(start 10.795 44.323)
		(end 7.112 40.64)
		(width 0.12065)
		(layer "In7.Cu")
		(net "CPLD_GPIO_3")
	)
	(segment
		(start 34.036 33.315605)
		(end 34.036 34.798)
		(width 0.12065)
		(layer "In7.Cu")
		(net "CPLD_GPIO_3")
	)
	(segment
		(start 34.744025 31.93448)
		(end 34.744025 32.60758)
		(width 0.12065)
		(layer "In7.Cu")
		(net "CPLD_GPIO_3")
	)
	(segment
		(start 33.147 35.687)
		(end 33.147 38.354)
		(width 0.12065)
		(layer "In7.Cu")
		(net "CPLD_GPIO_3")
	)
	(segment
		(start 10.795 46.228)
		(end 10.795 44.323)
		(width 0.12065)
		(layer "In7.Cu")
		(net "CPLD_GPIO_3")
	)
	(segment
		(start 31.810325 47.056675)
		(end 29.9085 48.9585)
		(width 0.12065)
		(layer "In7.Cu")
		(net "CPLD_GPIO_3")
	)
	(segment
		(start 31.753175 44.902171)
		(end 31.753175 45.267829)
		(width 0.12065)
		(layer "In7.Cu")
		(net "CPLD_GPIO_3")
	)
	(segment
		(start 34.417 24.892)
		(end 34.417 29.083)
		(width 0.12065)
		(layer "In7.Cu")
		(net "CPLD_GPIO_3")
	)
	(segment
		(start 34.991675 30.18602)
		(end 34.991675 31.68683)
		(width 0.12065)
		(layer "In7.Cu")
		(net "CPLD_GPIO_3")
	)
	(segment
		(start 34.991675 31.68683)
		(end 34.744025 31.93448)
		(width 0.12065)
		(layer "In7.Cu")
		(net "CPLD_GPIO_3")
	)
	(segment
		(start 27.305 48.26)
		(end 20.32 48.26)
		(width 0.12065)
		(layer "In7.Cu")
		(net "CPLD_GPIO_3")
	)
	(segment
		(start 34.0741 21.281034)
		(end 33.746008 21.609126)
		(width 0.127)
		(layer "F.Cu")
		(net "CPLD_GPIO_2")
	)
	(segment
		(start 34.0741 20.5867)
		(end 34.0741 21.281034)
		(width 0.127)
		(layer "F.Cu")
		(net "CPLD_GPIO_2")
	)
	(segment
		(start 34.3916 20.2946)
		(end 34.0741 20.5867)
		(width 0.127)
		(layer "F.Cu")
		(net "CPLD_GPIO_2")
	)
	(segment
		(start 33.746008 21.609126)
		(end 33.746008 22.048394)
		(width 0.127)
		(layer "F.Cu")
		(net "CPLD_GPIO_2")
	)
	(via
		(at 6.985 38.608)
		(size 0.508)
		(drill 0.25654)
		(layers "F.Cu" "B.Cu")
		(net "CPLD_GPIO_2")
	)
	(via
		(at 34.3916 20.2946)
		(size 0.4572)
		(drill 0.20574)
		(layers "F.Cu" "B.Cu")
		(net "CPLD_GPIO_2")
	)
	(via
		(at 27.94 45.0215)
		(size 0.508)
		(drill 0.25654)
		(layers "F.Cu" "B.Cu")
		(net "CPLD_GPIO_2")
	)
	(via
		(at 19.558 24.638)
		(size 0.508)
		(drill 0.254)
		(layers "F.Cu" "B.Cu")
		(net "CPLD_GPIO_2")
	)
	(via
		(at 31.9278 30.607)
		(size 0.508)
		(drill 0.254)
		(layers "F.Cu" "B.Cu")
		(net "CPLD_GPIO_2")
	)
	(segment
		(start 25.430429 31.200725)
		(end 24.820829 31.810325)
		(width 0.12065)
		(layer "In2.Cu")
		(net "CPLD_GPIO_2")
	)
	(segment
		(start 20.066 25.146)
		(end 19.558 24.638)
		(width 0.12065)
		(layer "In2.Cu")
		(net "CPLD_GPIO_2")
	)
	(segment
		(start 28.65567 31.054675)
		(end 26.296772 31.054675)
		(width 0.12065)
		(layer "In2.Cu")
		(net "CPLD_GPIO_2")
	)
	(segment
		(start 29.804741 29.610914)
		(end 29.804741 29.905604)
		(width 0.12065)
		(layer "In2.Cu")
		(net "CPLD_GPIO_2")
	)
	(segment
		(start 29.804741 29.905604)
		(end 28.65567 31.054675)
		(width 0.12065)
		(layer "In2.Cu")
		(net "CPLD_GPIO_2")
	)
	(segment
		(start 19.055944 29.204056)
		(end 19.304 28.956)
		(width 0.12065)
		(layer "In2.Cu")
		(net "CPLD_GPIO_2")
	)
	(segment
		(start 30.388204 29.351859)
		(end 30.063796 29.351859)
		(width 0.12065)
		(layer "In2.Cu")
		(net "CPLD_GPIO_2")
	)
	(segment
		(start 20.066 28.475254)
		(end 20.066 25.146)
		(width 0.12065)
		(layer "In2.Cu")
		(net "CPLD_GPIO_2")
	)
	(segment
		(start 26.296772 31.054675)
		(end 26.150722 31.200725)
		(width 0.12065)
		(layer "In2.Cu")
		(net "CPLD_GPIO_2")
	)
	(segment
		(start 19.027775 29.773829)
		(end 19.027775 29.243858)
		(width 0.12065)
		(layer "In2.Cu")
		(net "CPLD_GPIO_2")
	)
	(segment
		(start 30.617541 29.905604)
		(end 30.617541 29.581196)
		(width 0.12065)
		(layer "In2.Cu")
		(net "CPLD_GPIO_2")
	)
	(segment
		(start 24.820829 31.810325)
		(end 21.064271 31.810325)
		(width 0.12065)
		(layer "In2.Cu")
		(net "CPLD_GPIO_2")
	)
	(segment
		(start 30.617541 29.581196)
		(end 30.388204 29.351859)
		(width 0.12065)
		(layer "In2.Cu")
		(net "CPLD_GPIO_2")
	)
	(segment
		(start 19.054267 29.207638)
		(end 19.055944 29.204056)
		(width 0.12065)
		(layer "In2.Cu")
		(net "CPLD_GPIO_2")
	)
	(segment
		(start 19.304 28.956)
		(end 19.585254 28.956)
		(width 0.12065)
		(layer "In2.Cu")
		(net "CPLD_GPIO_2")
	)
	(segment
		(start 26.150722 31.200725)
		(end 25.430429 31.200725)
		(width 0.12065)
		(layer "In2.Cu")
		(net "CPLD_GPIO_2")
	)
	(segment
		(start 19.585254 28.956)
		(end 20.066 28.475254)
		(width 0.12065)
		(layer "In2.Cu")
		(net "CPLD_GPIO_2")
	)
	(segment
		(start 31.9278 30.607)
		(end 31.455741 30.134941)
		(width 0.12065)
		(layer "In2.Cu")
		(net "CPLD_GPIO_2")
	)
	(segment
		(start 21.064271 31.810325)
		(end 19.027775 29.773829)
		(width 0.12065)
		(layer "In2.Cu")
		(net "CPLD_GPIO_2")
	)
	(segment
		(start 30.063796 29.351859)
		(end 29.804741 29.610914)
		(width 0.12065)
		(layer "In2.Cu")
		(net "CPLD_GPIO_2")
	)
	(segment
		(start 19.027775 29.243858)
		(end 19.054267 29.207638)
		(width 0.12065)
		(layer "In2.Cu")
		(net "CPLD_GPIO_2")
	)
	(segment
		(start 31.455741 30.134941)
		(end 30.846878 30.134941)
		(width 0.12065)
		(layer "In2.Cu")
		(net "CPLD_GPIO_2")
	)
	(segment
		(start 30.846878 30.134941)
		(end 30.617541 29.905604)
		(width 0.12065)
		(layer "In2.Cu")
		(net "CPLD_GPIO_2")
	)
	(segment
		(start 34.046541 21.325459)
		(end 34.046541 20.639659)
		(width 0.12065)
		(layer "In3.Cu")
		(net "CPLD_GPIO_2")
	)
	(segment
		(start 19.558 24.638)
		(end 21.463 24.638)
		(width 0.12065)
		(layer "In3.Cu")
		(net "CPLD_GPIO_2")
	)
	(segment
		(start 8.382 45.466)
		(end 11.60968 45.466)
		(width 0.12065)
		(layer "In3.Cu")
		(net "CPLD_GPIO_2")
	)
	(segment
		(start 6.670675 38.922325)
		(end 6.670675 45.024675)
		(width 0.12065)
		(layer "In3.Cu")
		(net "CPLD_GPIO_2")
	)
	(segment
		(start 34.046541 20.639659)
		(end 34.3916 20.2946)
		(width 0.12065)
		(layer "In3.Cu")
		(net "CPLD_GPIO_2")
	)
	(segment
		(start 18.923 43.942)
		(end 27.178 43.942)
		(width 0.12065)
		(layer "In3.Cu")
		(net "CPLD_GPIO_2")
	)
	(segment
		(start 27.432 22.479)
		(end 32.766 22.479)
		(width 0.12065)
		(layer "In3.Cu")
		(net "CPLD_GPIO_2")
	)
	(segment
		(start 6.985 38.608)
		(end 6.670675 38.922325)
		(width 0.12065)
		(layer "In3.Cu")
		(net "CPLD_GPIO_2")
	)
	(segment
		(start 8.128 45.72)
		(end 8.382 45.466)
		(width 0.12065)
		(layer "In3.Cu")
		(net "CPLD_GPIO_2")
	)
	(segment
		(start 16.689654 46.355)
		(end 16.951325 46.093329)
		(width 0.12065)
		(layer "In3.Cu")
		(net "CPLD_GPIO_2")
	)
	(segment
		(start 6.670675 45.024675)
		(end 7.366 45.72)
		(width 0.12065)
		(layer "In3.Cu")
		(net "CPLD_GPIO_2")
	)
	(segment
		(start 11.60968 45.466)
		(end 11.871325 45.727645)
		(width 0.12065)
		(layer "In3.Cu")
		(net "CPLD_GPIO_2")
	)
	(segment
		(start 7.366 45.72)
		(end 8.128 45.72)
		(width 0.12065)
		(layer "In3.Cu")
		(net "CPLD_GPIO_2")
	)
	(segment
		(start 33.528 21.717)
		(end 33.655 21.717)
		(width 0.12065)
		(layer "In3.Cu")
		(net "CPLD_GPIO_2")
	)
	(segment
		(start 11.871325 45.727645)
		(end 11.871325 45.780325)
		(width 0.12065)
		(layer "In3.Cu")
		(net "CPLD_GPIO_2")
	)
	(segment
		(start 16.951325 46.093329)
		(end 16.951325 45.913675)
		(width 0.12065)
		(layer "In3.Cu")
		(net "CPLD_GPIO_2")
	)
	(segment
		(start 33.655 21.717)
		(end 34.046541 21.325459)
		(width 0.12065)
		(layer "In3.Cu")
		(net "CPLD_GPIO_2")
	)
	(segment
		(start 12.446 46.355)
		(end 16.689654 46.355)
		(width 0.12065)
		(layer "In3.Cu")
		(net "CPLD_GPIO_2")
	)
	(segment
		(start 23.876 22.225)
		(end 27.178 22.225)
		(width 0.12065)
		(layer "In3.Cu")
		(net "CPLD_GPIO_2")
	)
	(segment
		(start 27.178 43.942)
		(end 27.94 44.704)
		(width 0.12065)
		(layer "In3.Cu")
		(net "CPLD_GPIO_2")
	)
	(segment
		(start 32.766 22.479)
		(end 33.528 21.717)
		(width 0.12065)
		(layer "In3.Cu")
		(net "CPLD_GPIO_2")
	)
	(segment
		(start 11.871325 45.780325)
		(end 12.446 46.355)
		(width 0.12065)
		(layer "In3.Cu")
		(net "CPLD_GPIO_2")
	)
	(segment
		(start 27.178 22.225)
		(end 27.432 22.479)
		(width 0.12065)
		(layer "In3.Cu")
		(net "CPLD_GPIO_2")
	)
	(segment
		(start 27.94 44.704)
		(end 27.94 45.0215)
		(width 0.12065)
		(layer "In3.Cu")
		(net "CPLD_GPIO_2")
	)
	(segment
		(start 21.463 24.638)
		(end 23.876 22.225)
		(width 0.12065)
		(layer "In3.Cu")
		(net "CPLD_GPIO_2")
	)
	(segment
		(start 16.951325 45.913675)
		(end 18.923 43.942)
		(width 0.12065)
		(layer "In3.Cu")
		(net "CPLD_GPIO_2")
	)
	(segment
		(start 28.573959 41.127604)
		(end 28.573959 38.990041)
		(width 0.12065)
		(layer "In7.Cu")
		(net "CPLD_GPIO_2")
	)
	(segment
		(start 28.956 38.608)
		(end 28.956 34.29)
		(width 0.12065)
		(layer "In7.Cu")
		(net "CPLD_GPIO_2")
	)
	(segment
		(start 31.435675 31.810325)
		(end 31.435675 31.099125)
		(width 0.12065)
		(layer "In7.Cu")
		(net "CPLD_GPIO_2")
	)
	(segment
		(start 28.573959 38.990041)
		(end 28.956 38.608)
		(width 0.12065)
		(layer "In7.Cu")
		(net "CPLD_GPIO_2")
	)
	(segment
		(start 27.94 41.761562)
		(end 28.573959 41.127604)
		(width 0.12065)
		(layer "In7.Cu")
		(net "CPLD_GPIO_2")
	)
	(segment
		(start 27.94 45.0215)
		(end 27.94 41.761562)
		(width 0.12065)
		(layer "In7.Cu")
		(net "CPLD_GPIO_2")
	)
	(segment
		(start 31.435675 31.099125)
		(end 31.9278 30.607)
		(width 0.12065)
		(layer "In7.Cu")
		(net "CPLD_GPIO_2")
	)
	(segment
		(start 28.956 34.29)
		(end 31.435675 31.810325)
		(width 0.12065)
		(layer "In7.Cu")
		(net "CPLD_GPIO_2")
	)
	(segment
		(start 31.245988 23.048392)
		(end 31.245988 23.371988)
		(width 0.14732)
		(layer "F.Cu")
		(net "CPLD_GPIO_1")
	)
	(segment
		(start 31.245988 23.371988)
		(end 31.5214 23.6474)
		(width 0.14732)
		(layer "F.Cu")
		(net "CPLD_GPIO_1")
	)
	(via
		(at 31.5214 23.6474)
		(size 0.4572)
		(drill 0.20574)
		(layers "F.Cu" "B.Cu")
		(net "CPLD_GPIO_1")
	)
	(via
		(at 8.636 38.735)
		(size 0.508)
		(drill 0.25654)
		(layers "F.Cu" "B.Cu")
		(net "CPLD_GPIO_1")
	)
	(segment
		(start 8.8265 47.8155)
		(end 8.382 47.371)
		(width 0.14732)
		(layer "B.Cu")
		(net "CPLD_GPIO_1")
	)
	(segment
		(start 8.382 47.371)
		(end 8.382 38.989)
		(width 0.14732)
		(layer "B.Cu")
		(net "CPLD_GPIO_1")
	)
	(segment
		(start 10.16 47.8155)
		(end 8.8265 47.8155)
		(width 0.14732)
		(layer "B.Cu")
		(net "CPLD_GPIO_1")
	)
	(segment
		(start 8.382 38.989)
		(end 8.636 38.735)
		(width 0.14732)
		(layer "B.Cu")
		(net "CPLD_GPIO_1")
	)
	(segment
		(start 7.430465 25.208535)
		(end 7.936611 25.208535)
		(width 0.12065)
		(layer "In3.Cu")
		(net "CPLD_GPIO_1")
	)
	(segment
		(start 26.532459 23.230459)
		(end 26.532459 23.657204)
		(width 0.12065)
		(layer "In3.Cu")
		(net "CPLD_GPIO_1")
	)
	(segment
		(start 0.127 35.433)
		(end 0.127 32.765975)
		(width 0.12065)
		(layer "In3.Cu")
		(net "CPLD_GPIO_1")
	)
	(segment
		(start 26.532459 23.657204)
		(end 26.543 23.667745)
		(width 0.12065)
		(layer "In3.Cu")
		(net "CPLD_GPIO_1")
	)
	(segment
		(start 4.119829 29.143325)
		(end 6.985 26.278154)
		(width 0.12065)
		(layer "In3.Cu")
		(net "CPLD_GPIO_1")
	)
	(segment
		(start 0.127 32.765975)
		(end 3.74965 29.143325)
		(width 0.12065)
		(layer "In3.Cu")
		(net "CPLD_GPIO_1")
	)
	(segment
		(start 8.382 24.510975)
		(end 8.6074 24.285575)
		(width 0.12065)
		(layer "In3.Cu")
		(net "CPLD_GPIO_1")
	)
	(segment
		(start 26.543 23.749)
		(end 26.735659 23.941659)
		(width 0.12065)
		(layer "In3.Cu")
		(net "CPLD_GPIO_1")
	)
	(segment
		(start 26.735659 23.941659)
		(end 27.086204 23.941659)
		(width 0.12065)
		(layer "In3.Cu")
		(net "CPLD_GPIO_1")
	)
	(segment
		(start 26.289 22.987)
		(end 26.532459 23.230459)
		(width 0.12065)
		(layer "In3.Cu")
		(net "CPLD_GPIO_1")
	)
	(segment
		(start 8.255 38.735)
		(end 5.842 36.322)
		(width 0.12065)
		(layer "In3.Cu")
		(net "CPLD_GPIO_1")
	)
	(segment
		(start 26.543 23.667745)
		(end 26.543 23.749)
		(width 0.12065)
		(layer "In3.Cu")
		(net "CPLD_GPIO_1")
	)
	(segment
		(start 27.086204 23.941659)
		(end 27.183486 24.038941)
		(width 0.12065)
		(layer "In3.Cu")
		(net "CPLD_GPIO_1")
	)
	(segment
		(start 31.4706 23.6474)
		(end 31.5214 23.6474)
		(width 0.12065)
		(layer "In3.Cu")
		(net "CPLD_GPIO_1")
	)
	(segment
		(start 19.46242 25.346025)
		(end 19.516395 25.4)
		(width 0.12065)
		(layer "In3.Cu")
		(net "CPLD_GPIO_1")
	)
	(segment
		(start 31.079059 24.038941)
		(end 31.4706 23.6474)
		(width 0.12065)
		(layer "In3.Cu")
		(net "CPLD_GPIO_1")
	)
	(segment
		(start 1.016 36.322)
		(end 0.127 35.433)
		(width 0.12065)
		(layer "In3.Cu")
		(net "CPLD_GPIO_1")
	)
	(segment
		(start 27.183486 24.038941)
		(end 31.079059 24.038941)
		(width 0.12065)
		(layer "In3.Cu")
		(net "CPLD_GPIO_1")
	)
	(segment
		(start 18.669 25.4)
		(end 18.837605 25.4)
		(width 0.12065)
		(layer "In3.Cu")
		(net "CPLD_GPIO_1")
	)
	(segment
		(start 22.671659 25.4)
		(end 25.084659 22.987)
		(width 0.12065)
		(layer "In3.Cu")
		(net "CPLD_GPIO_1")
	)
	(segment
		(start 3.74965 29.143325)
		(end 4.119829 29.143325)
		(width 0.12065)
		(layer "In3.Cu")
		(net "CPLD_GPIO_1")
	)
	(segment
		(start 17.554575 24.285575)
		(end 18.669 25.4)
		(width 0.12065)
		(layer "In3.Cu")
		(net "CPLD_GPIO_1")
	)
	(segment
		(start 7.936611 25.208535)
		(end 8.382 24.763146)
		(width 0.12065)
		(layer "In3.Cu")
		(net "CPLD_GPIO_1")
	)
	(segment
		(start 8.6074 24.285575)
		(end 17.554575 24.285575)
		(width 0.12065)
		(layer "In3.Cu")
		(net "CPLD_GPIO_1")
	)
	(segment
		(start 18.89158 25.346025)
		(end 19.46242 25.346025)
		(width 0.12065)
		(layer "In3.Cu")
		(net "CPLD_GPIO_1")
	)
	(segment
		(start 6.985 26.278154)
		(end 6.985 25.654)
		(width 0.12065)
		(layer "In3.Cu")
		(net "CPLD_GPIO_1")
	)
	(segment
		(start 6.985 25.654)
		(end 7.430465 25.208535)
		(width 0.12065)
		(layer "In3.Cu")
		(net "CPLD_GPIO_1")
	)
	(segment
		(start 25.084659 22.987)
		(end 26.289 22.987)
		(width 0.12065)
		(layer "In3.Cu")
		(net "CPLD_GPIO_1")
	)
	(segment
		(start 19.516395 25.4)
		(end 22.671659 25.4)
		(width 0.12065)
		(layer "In3.Cu")
		(net "CPLD_GPIO_1")
	)
	(segment
		(start 8.636 38.735)
		(end 8.255 38.735)
		(width 0.12065)
		(layer "In3.Cu")
		(net "CPLD_GPIO_1")
	)
	(segment
		(start 5.842 36.322)
		(end 1.016 36.322)
		(width 0.12065)
		(layer "In3.Cu")
		(net "CPLD_GPIO_1")
	)
	(segment
		(start 18.837605 25.4)
		(end 18.89158 25.346025)
		(width 0.12065)
		(layer "In3.Cu")
		(net "CPLD_GPIO_1")
	)
	(segment
		(start 8.382 24.763146)
		(end 8.382 24.510975)
		(width 0.12065)
		(layer "In3.Cu")
		(net "CPLD_GPIO_1")
	)
	(segment
		(start 30.7213 21.523706)
		(end 31.245988 22.048394)
		(width 0.127)
		(layer "F.Cu")
		(net "CPLD_GPIO_0")
	)
	(segment
		(start 31.1404 20.2946)
		(end 30.7213 20.6883)
		(width 0.127)
		(layer "F.Cu")
		(net "CPLD_GPIO_0")
	)
	(segment
		(start 30.7213 20.6883)
		(end 30.7213 21.523706)
		(width 0.127)
		(layer "F.Cu")
		(net "CPLD_GPIO_0")
	)
	(via
		(at 31.1404 20.2946)
		(size 0.4572)
		(drill 0.20574)
		(layers "F.Cu" "B.Cu")
		(net "CPLD_GPIO_0")
	)
	(via
		(at 5.715 36.957)
		(size 0.508)
		(drill 0.25654)
		(layers "F.Cu" "B.Cu")
		(net "CPLD_GPIO_0")
	)
	(segment
		(start 10.16 41.656)
		(end 10.16 43.8785)
		(width 0.14732)
		(layer "B.Cu")
		(net "CPLD_GPIO_0")
	)
	(segment
		(start 8.8265 37.9095)
		(end 9.779 38.862)
		(width 0.14732)
		(layer "B.Cu")
		(net "CPLD_GPIO_0")
	)
	(segment
		(start 6.6675 37.9095)
		(end 8.8265 37.9095)
		(width 0.14732)
		(layer "B.Cu")
		(net "CPLD_GPIO_0")
	)
	(segment
		(start 5.715 36.957)
		(end 6.6675 37.9095)
		(width 0.14732)
		(layer "B.Cu")
		(net "CPLD_GPIO_0")
	)
	(segment
		(start 9.779 41.275)
		(end 10.16 41.656)
		(width 0.14732)
		(layer "B.Cu")
		(net "CPLD_GPIO_0")
	)
	(segment
		(start 9.779 38.862)
		(end 9.779 41.275)
		(width 0.14732)
		(layer "B.Cu")
		(net "CPLD_GPIO_0")
	)
	(segment
		(start 1.016 36.957)
		(end 5.715 36.957)
		(width 0.12065)
		(layer "In3.Cu")
		(net "CPLD_GPIO_0")
	)
	(segment
		(start 26.662355 20.701)
		(end 24.003 20.701)
		(width 0.12065)
		(layer "In3.Cu")
		(net "CPLD_GPIO_0")
	)
	(segment
		(start 7.591425 24.285575)
		(end 7.589571 24.285575)
		(width 0.12065)
		(layer "In3.Cu")
		(net "CPLD_GPIO_0")
	)
	(segment
		(start -0.254 35.687)
		(end 1.016 36.957)
		(width 0.12065)
		(layer "In3.Cu")
		(net "CPLD_GPIO_0")
	)
	(segment
		(start 7.589571 24.285575)
		(end 7.331075 24.544071)
		(width 0.12065)
		(layer "In3.Cu")
		(net "CPLD_GPIO_0")
	)
	(segment
		(start 17.854244 22.733)
		(end 17.103725 23.483519)
		(width 0.12065)
		(layer "In3.Cu")
		(net "CPLD_GPIO_0")
	)
	(segment
		(start 7.918475 23.958525)
		(end 7.591425 24.285575)
		(width 0.12065)
		(layer "In3.Cu")
		(net "CPLD_GPIO_0")
	)
	(segment
		(start 16.78493 23.958525)
		(end 7.918475 23.958525)
		(width 0.12065)
		(layer "In3.Cu")
		(net "CPLD_GPIO_0")
	)
	(segment
		(start 7.331075 24.545925)
		(end -0.254 32.131)
		(width 0.12065)
		(layer "In3.Cu")
		(net "CPLD_GPIO_0")
	)
	(segment
		(start 23.749 21.463)
		(end 22.479 22.733)
		(width 0.12065)
		(layer "In3.Cu")
		(net "CPLD_GPIO_0")
	)
	(segment
		(start 27.086204 20.601559)
		(end 26.761796 20.601559)
		(width 0.12065)
		(layer "In3.Cu")
		(net "CPLD_GPIO_0")
	)
	(segment
		(start 30.693741 20.741259)
		(end 30.693741 21.269604)
		(width 0.12065)
		(layer "In3.Cu")
		(net "CPLD_GPIO_0")
	)
	(segment
		(start 22.479 22.733)
		(end 17.854244 22.733)
		(width 0.12065)
		(layer "In3.Cu")
		(net "CPLD_GPIO_0")
	)
	(segment
		(start 7.331075 24.544071)
		(end 7.331075 24.545925)
		(width 0.12065)
		(layer "In3.Cu")
		(net "CPLD_GPIO_0")
	)
	(segment
		(start 30.693741 21.269604)
		(end 30.119345 21.844)
		(width 0.12065)
		(layer "In3.Cu")
		(net "CPLD_GPIO_0")
	)
	(segment
		(start 17.103725 23.639729)
		(end 16.78493 23.958525)
		(width 0.12065)
		(layer "In3.Cu")
		(net "CPLD_GPIO_0")
	)
	(segment
		(start 24.003 20.701)
		(end 23.749 20.955)
		(width 0.12065)
		(layer "In3.Cu")
		(net "CPLD_GPIO_0")
	)
	(segment
		(start 30.119345 21.844)
		(end 27.818893 21.844)
		(width 0.12065)
		(layer "In3.Cu")
		(net "CPLD_GPIO_0")
	)
	(segment
		(start 17.103725 23.483519)
		(end 17.103725 23.639729)
		(width 0.12065)
		(layer "In3.Cu")
		(net "CPLD_GPIO_0")
	)
	(segment
		(start 27.315541 20.830896)
		(end 27.086204 20.601559)
		(width 0.12065)
		(layer "In3.Cu")
		(net "CPLD_GPIO_0")
	)
	(segment
		(start -0.254 32.131)
		(end -0.254 35.687)
		(width 0.12065)
		(layer "In3.Cu")
		(net "CPLD_GPIO_0")
	)
	(segment
		(start 23.749 20.955)
		(end 23.749 21.463)
		(width 0.12065)
		(layer "In3.Cu")
		(net "CPLD_GPIO_0")
	)
	(segment
		(start 26.761796 20.601559)
		(end 26.662355 20.701)
		(width 0.12065)
		(layer "In3.Cu")
		(net "CPLD_GPIO_0")
	)
	(segment
		(start 31.1404 20.2946)
		(end 30.693741 20.741259)
		(width 0.12065)
		(layer "In3.Cu")
		(net "CPLD_GPIO_0")
	)
	(segment
		(start 27.315541 21.340648)
		(end 27.315541 20.830896)
		(width 0.12065)
		(layer "In3.Cu")
		(net "CPLD_GPIO_0")
	)
	(segment
		(start 27.818893 21.844)
		(end 27.315541 21.340648)
		(width 0.12065)
		(layer "In3.Cu")
		(net "CPLD_GPIO_0")
	)
	(segment
		(start 29.100729 34.49066)
		(end 29.364991 34.754922)
		(width 0.14732)
		(layer "F.Cu")
		(net "CPLD_CORE_PSI_L")
	)
	(segment
		(start 26.3525 34.1884)
		(end 26.640892 34.476792)
		(width 0.14732)
		(layer "F.Cu")
		(net "CPLD_CORE_PSI_L")
	)
	(segment
		(start 26.640892 34.476792)
		(end 27.618792 34.476792)
		(width 0.14732)
		(layer "F.Cu")
		(net "CPLD_CORE_PSI_L")
	)
	(segment
		(start 28.018994 34.49828)
		(end 28.623006 34.49828)
		(width 0.14732)
		(layer "F.Cu")
		(net "CPLD_CORE_PSI_L")
	)
	(segment
		(start 29.620388 25.548412)
		(end 29.245992 25.548412)
		(width 0.14732)
		(layer "F.Cu")
		(net "CPLD_CORE_PSI_L")
	)
	(segment
		(start 28.011374 34.49066)
		(end 28.018994 34.49828)
		(width 0.14732)
		(layer "F.Cu")
		(net "CPLD_CORE_PSI_L")
	)
	(segment
		(start 28.630626 34.49066)
		(end 29.100729 34.49066)
		(width 0.14732)
		(layer "F.Cu")
		(net "CPLD_CORE_PSI_L")
	)
	(segment
		(start 26.3525 34.163)
		(end 26.3525 34.1884)
		(width 0.14732)
		(layer "F.Cu")
		(net "CPLD_CORE_PSI_L")
	)
	(segment
		(start 28.623006 34.49828)
		(end 28.630626 34.49066)
		(width 0.14732)
		(layer "F.Cu")
		(net "CPLD_CORE_PSI_L")
	)
	(segment
		(start 27.63266 34.49066)
		(end 28.011374 34.49066)
		(width 0.14732)
		(layer "F.Cu")
		(net "CPLD_CORE_PSI_L")
	)
	(segment
		(start 29.364991 34.754922)
		(end 29.364991 35.1536)
		(width 0.14732)
		(layer "F.Cu")
		(net "CPLD_CORE_PSI_L")
	)
	(segment
		(start 27.618792 34.476792)
		(end 27.63266 34.49066)
		(width 0.14732)
		(layer "F.Cu")
		(net "CPLD_CORE_PSI_L")
	)
	(segment
		(start 29.8958 25.2984)
		(end 29.620388 25.548412)
		(width 0.14732)
		(layer "F.Cu")
		(net "CPLD_CORE_PSI_L")
	)
	(via
		(at 29.8958 25.2984)
		(size 0.4572)
		(drill 0.20574)
		(layers "F.Cu" "B.Cu")
		(net "CPLD_CORE_PSI_L")
	)
	(via
		(at 26.3525 34.163)
		(size 0.508)
		(drill 0.25654)
		(layers "F.Cu" "B.Cu")
		(net "CPLD_CORE_PSI_L")
	)
	(segment
		(start 25.273 31.242)
		(end 24.892 30.861)
		(width 0.14732)
		(layer "B.Cu")
		(net "CPLD_CORE_PSI_L")
	)
	(segment
		(start 24.892 30.861)
		(end 23.1521 30.861)
		(width 0.14732)
		(layer "B.Cu")
		(net "CPLD_CORE_PSI_L")
	)
	(segment
		(start 25.273 32.639)
		(end 25.273 31.242)
		(width 0.14732)
		(layer "B.Cu")
		(net "CPLD_CORE_PSI_L")
	)
	(segment
		(start 26.3525 33.72546)
		(end 26.26868 33.64164)
		(width 0.14732)
		(layer "B.Cu")
		(net "CPLD_CORE_PSI_L")
	)
	(segment
		(start 26.26868 33.64164)
		(end 26.26868 33.63468)
		(width 0.14732)
		(layer "B.Cu")
		(net "CPLD_CORE_PSI_L")
	)
	(segment
		(start 26.3525 34.163)
		(end 26.3525 33.72546)
		(width 0.14732)
		(layer "B.Cu")
		(net "CPLD_CORE_PSI_L")
	)
	(segment
		(start 26.26868 33.63468)
		(end 25.273 32.639)
		(width 0.14732)
		(layer "B.Cu")
		(net "CPLD_CORE_PSI_L")
	)
	(segment
		(start 26.035 28.183459)
		(end 26.532459 27.686)
		(width 0.12065)
		(layer "In6.Cu")
		(net "CPLD_CORE_PSI_L")
	)
	(segment
		(start 26.532459 27.061541)
		(end 26.797 26.797)
		(width 0.12065)
		(layer "In6.Cu")
		(net "CPLD_CORE_PSI_L")
	)
	(segment
		(start 26.532459 27.686)
		(end 26.532459 27.061541)
		(width 0.12065)
		(layer "In6.Cu")
		(net "CPLD_CORE_PSI_L")
	)
	(segment
		(start 26.797 26.797)
		(end 28.3972 26.797)
		(width 0.12065)
		(layer "In6.Cu")
		(net "CPLD_CORE_PSI_L")
	)
	(segment
		(start 26.3525 32.0675)
		(end 26.035 31.75)
		(width 0.12065)
		(layer "In6.Cu")
		(net "CPLD_CORE_PSI_L")
	)
	(segment
		(start 28.3972 26.797)
		(end 29.8958 25.2984)
		(width 0.12065)
		(layer "In6.Cu")
		(net "CPLD_CORE_PSI_L")
	)
	(segment
		(start 26.3525 34.163)
		(end 26.3525 32.0675)
		(width 0.12065)
		(layer "In6.Cu")
		(net "CPLD_CORE_PSI_L")
	)
	(segment
		(start 26.035 31.75)
		(end 26.035 28.183459)
		(width 0.12065)
		(layer "In6.Cu")
		(net "CPLD_CORE_PSI_L")
	)
	(segment
		(start 39.237006 19.041999)
		(end 38.737007 19.541998)
		(width 0.13208)
		(layer "F.Cu")
		(net "_NFP_CFG_SPI_FLASH_SEL")
	)
	(via
		(at 38.737007 19.541998)
		(size 0.4826)
		(drill 0.20574)
		(layers "F.Cu" "B.Cu")
		(net "_NFP_CFG_SPI_FLASH_SEL")
	)
	(segment
		(start 38.086005 20.193)
		(end 38.737007 19.541998)
		(width 0.14732)
		(layer "B.Cu")
		(net "_NFP_CFG_SPI_FLASH_SEL")
	)
	(segment
		(start 38.0619 20.193)
		(end 38.086005 20.193)
		(width 0.14732)
		(layer "B.Cu")
		(net "_NFP_CFG_SPI_FLASH_SEL")
	)
	(segment
		(start 40.237004 19.041999)
		(end 39.737005 19.541998)
		(width 0.13208)
		(layer "F.Cu")
		(net "_NFP_CFG_SPI_FLASH_SCK")
	)
	(via
		(at 39.737005 19.541998)
		(size 0.4826)
		(drill 0.25654)
		(layers "F.Cu" "B.Cu")
		(net "_NFP_CFG_SPI_FLASH_SCK")
	)
	(segment
		(start 39.237031 20.041972)
		(end 39.737005 19.541998)
		(width 0.14732)
		(layer "B.Cu")
		(net "_NFP_CFG_SPI_FLASH_SCK")
	)
	(segment
		(start 38.1 21.082)
		(end 39.140028 20.041972)
		(width 0.14732)
		(layer "B.Cu")
		(net "_NFP_CFG_SPI_FLASH_SCK")
	)
	(segment
		(start 38.0619 21.082)
		(end 38.1 21.082)
		(width 0.14732)
		(layer "B.Cu")
		(net "_NFP_CFG_SPI_FLASH_SCK")
	)
	(segment
		(start 39.140028 20.041972)
		(end 39.237031 20.041972)
		(width 0.14732)
		(layer "B.Cu")
		(net "_NFP_CFG_SPI_FLASH_SCK")
	)
	(segment
		(start 39.237006 18.042001)
		(end 38.737007 17.542002)
		(width 0.13208)
		(layer "F.Cu")
		(net "_NFP_ARM_SPI_FLASH_SEL")
	)
	(via
		(at 38.737007 17.542002)
		(size 0.4572)
		(drill 0.20574)
		(layers "F.Cu" "B.Cu")
		(net "_NFP_ARM_SPI_FLASH_SEL")
	)
	(segment
		(start 42.237 20.041997)
		(end 41.737001 20.541996)
		(width 0.13208)
		(layer "F.Cu")
		(net "_NFP_ARM_SPI_FLASH_SCK")
	)
	(via
		(at 38.989 21.717)
		(size 0.762)
		(drill 0.381)
		(layers "F.Cu" "B.Cu")
		(net "_NFP_ARM_SPI_FLASH_SCK")
	)
	(via
		(at 41.737001 20.541996)
		(size 0.4826)
		(drill 0.20574)
		(layers "F.Cu" "B.Cu")
		(net "_NFP_ARM_SPI_FLASH_SCK")
	)
	(segment
		(start 41.295041 20.983956)
		(end 41.295041 21.609025)
		(width 0.14732)
		(layer "B.Cu")
		(net "_NFP_ARM_SPI_FLASH_SCK")
	)
	(segment
		(start 38.735 21.971)
		(end 38.989 21.717)
		(width 0.14732)
		(layer "B.Cu")
		(net "_NFP_ARM_SPI_FLASH_SCK")
	)
	(segment
		(start 40.920111 21.983954)
		(end 39.255954 21.983954)
		(width 0.14732)
		(layer "B.Cu")
		(net "_NFP_ARM_SPI_FLASH_SCK")
	)
	(segment
		(start 39.255954 21.983954)
		(end 38.989 21.717)
		(width 0.14732)
		(layer "B.Cu")
		(net "_NFP_ARM_SPI_FLASH_SCK")
	)
	(segment
		(start 41.295041 21.609025)
		(end 40.920111 21.983954)
		(width 0.14732)
		(layer "B.Cu")
		(net "_NFP_ARM_SPI_FLASH_SCK")
	)
	(segment
		(start 41.737001 20.541996)
		(end 41.295041 20.983956)
		(width 0.14732)
		(layer "B.Cu")
		(net "_NFP_ARM_SPI_FLASH_SCK")
	)
	(segment
		(start 38.0111 21.971)
		(end 38.735 21.971)
		(width 0.14732)
		(layer "B.Cu")
		(net "_NFP_ARM_SPI_FLASH_SCK")
	)
	(segment
		(start 28.864992 35.1536)
		(end 28.306192 35.1536)
		(width 0.14732)
		(layer "F.Cu")
		(net "VDD_CORE_PGOOD")
	)
	(segment
		(start 28.306192 35.1536)
		(end 28.194 35.265792)
		(width 0.14732)
		(layer "F.Cu")
		(net "VDD_CORE_PGOOD")
	)
	(segment
		(start 27.980208 35.052)
		(end 28.194 35.265792)
		(width 0.14732)
		(layer "F.Cu")
		(net "VDD_CORE_PGOOD")
	)
	(segment
		(start 43.236998 22.041993)
		(end 42.736999 22.541992)
		(width 0.13208)
		(layer "F.Cu")
		(net "VDD_CORE_PGOOD")
	)
	(segment
		(start 43.236998 21.041995)
		(end 42.736999 21.541994)
		(width 0.13208)
		(layer "F.Cu")
		(net "VDD_CORE_PGOOD")
	)
	(segment
		(start 26.543 46.0375)
		(end 26.67 45.9105)
		(width 0.254)
		(layer "F.Cu")
		(net "VDD_CORE_PGOOD")
	)
	(segment
		(start 26.3779 35.052)
		(end 27.980208 35.052)
		(width 0.14732)
		(layer "F.Cu")
		(net "VDD_CORE_PGOOD")
	)
	(segment
		(start 26.543 46.99)
		(end 26.543 46.0375)
		(width 0.254)
		(layer "F.Cu")
		(net "VDD_CORE_PGOOD")
	)
	(via
		(at 35.433 27.3558)
		(size 0.4572)
		(drill 0.20574)
		(layers "F.Cu" "B.Cu")
		(net "VDD_CORE_PGOOD")
	)
	(via
		(at 42.736999 21.541994)
		(size 0.4826)
		(drill 0.20574)
		(layers "F.Cu" "B.Cu")
		(net "VDD_CORE_PGOOD")
	)
	(via
		(at 42.736999 22.541992)
		(size 0.4826)
		(drill 0.20574)
		(layers "F.Cu" "B.Cu")
		(net "VDD_CORE_PGOOD")
	)
	(via
		(at 26.67 45.9105)
		(size 0.508)
		(drill 0.254)
		(layers "F.Cu" "B.Cu")
		(net "VDD_CORE_PGOOD")
	)
	(via
		(at 28.194 35.265792)
		(size 0.508)
		(drill 0.25654)
		(layers "F.Cu" "B.Cu")
		(net "VDD_CORE_PGOOD")
	)
	(segment
		(start 34.246007 26.54841)
		(end 34.422385 26.54841)
		(width 0.127)
		(layer "In1.Cu")
		(net "VDD_CORE_PGOOD")
	)
	(segment
		(start 34.695663 26.821689)
		(end 34.898889 26.821689)
		(width 0.127)
		(layer "In1.Cu")
		(net "VDD_CORE_PGOOD")
	)
	(segment
		(start 34.422385 26.54841)
		(end 34.695663 26.821689)
		(width 0.127)
		(layer "In1.Cu")
		(net "VDD_CORE_PGOOD")
	)
	(segment
		(start 34.898889 26.821689)
		(end 35.433 27.3558)
		(width 0.127)
		(layer "In1.Cu")
		(net "VDD_CORE_PGOOD")
	)
	(segment
		(start 42.736999 22.541992)
		(end 42.736999 21.541994)
		(width 0.12065)
		(layer "In6.Cu")
		(net "VDD_CORE_PGOOD")
	)
	(segment
		(start 31.429325 33.224521)
		(end 31.429325 30.779314)
		(width 0.12065)
		(layer "In6.Cu")
		(net "VDD_CORE_PGOOD")
	)
	(segment
		(start 30.012208 35.265792)
		(end 31.054675 34.223325)
		(width 0.12065)
		(layer "In6.Cu")
		(net "VDD_CORE_PGOOD")
	)
	(segment
		(start 43.307 23.114)
		(end 42.736999 22.543999)
		(width 0.12065)
		(layer "In6.Cu")
		(net "VDD_CORE_PGOOD")
	)
	(segment
		(start 35.433 27.432)
		(end 35.433 27.3558)
		(width 0.12065)
		(layer "In6.Cu")
		(net "VDD_CORE_PGOOD")
	)
	(segment
		(start 34.417 28.448)
		(end 35.433 27.432)
		(width 0.12065)
		(layer "In6.Cu")
		(net "VDD_CORE_PGOOD")
	)
	(segment
		(start 42.736999 22.543999)
		(end 42.736999 22.541992)
		(width 0.12065)
		(layer "In6.Cu")
		(net "VDD_CORE_PGOOD")
	)
	(segment
		(start 35.433 27.3558)
		(end 35.824541 26.964259)
		(width 0.12065)
		(layer "In6.Cu")
		(net "VDD_CORE_PGOOD")
	)
	(segment
		(start 31.429325 30.779314)
		(end 31.480125 30.728514)
		(width 0.12065)
		(layer "In6.Cu")
		(net "VDD_CORE_PGOOD")
	)
	(segment
		(start 32.131 28.448)
		(end 34.417 28.448)
		(width 0.12065)
		(layer "In6.Cu")
		(net "VDD_CORE_PGOOD")
	)
	(segment
		(start 43.307 25.781)
		(end 43.307 23.114)
		(width 0.12065)
		(layer "In6.Cu")
		(net "VDD_CORE_PGOOD")
	)
	(segment
		(start 31.054675 33.599171)
		(end 31.429325 33.224521)
		(width 0.12065)
		(layer "In6.Cu")
		(net "VDD_CORE_PGOOD")
	)
	(segment
		(start 31.480125 30.728514)
		(end 31.480125 29.098875)
		(width 0.12065)
		(layer "In6.Cu")
		(net "VDD_CORE_PGOOD")
	)
	(segment
		(start 31.054675 34.223325)
		(end 31.054675 33.599171)
		(width 0.12065)
		(layer "In6.Cu")
		(net "VDD_CORE_PGOOD")
	)
	(segment
		(start 35.824541 26.964259)
		(end 42.123741 26.964259)
		(width 0.12065)
		(layer "In6.Cu")
		(net "VDD_CORE_PGOOD")
	)
	(segment
		(start 28.194 35.265792)
		(end 30.012208 35.265792)
		(width 0.12065)
		(layer "In6.Cu")
		(net "VDD_CORE_PGOOD")
	)
	(segment
		(start 42.123741 26.964259)
		(end 43.307 25.781)
		(width 0.12065)
		(layer "In6.Cu")
		(net "VDD_CORE_PGOOD")
	)
	(segment
		(start 31.480125 29.098875)
		(end 32.131 28.448)
		(width 0.12065)
		(layer "In6.Cu")
		(net "VDD_CORE_PGOOD")
	)
	(segment
		(start 26.67 45.9105)
		(end 27.432 45.1485)
		(width 0.12065)
		(layer "In7.Cu")
		(net "VDD_CORE_PGOOD")
	)
	(segment
		(start 27.530425 41.457829)
		(end 27.530425 38.636575)
		(width 0.12065)
		(layer "In7.Cu")
		(net "VDD_CORE_PGOOD")
	)
	(segment
		(start 28.194 37.973)
		(end 28.194 35.265792)
		(width 0.12065)
		(layer "In7.Cu")
		(net "VDD_CORE_PGOOD")
	)
	(segment
		(start 27.530425 38.636575)
		(end 28.194 37.973)
		(width 0.12065)
		(layer "In7.Cu")
		(net "VDD_CORE_PGOOD")
	)
	(segment
		(start 27.432 41.556254)
		(end 27.530425 41.457829)
		(width 0.12065)
		(layer "In7.Cu")
		(net "VDD_CORE_PGOOD")
	)
	(segment
		(start 27.432 45.1485)
		(end 27.432 41.556254)
		(width 0.12065)
		(layer "In7.Cu")
		(net "VDD_CORE_PGOOD")
	)
	(segment
		(start 25.527 25.31618)
		(end 25.80132 25.5905)
		(width 0.127)
		(layer "F.Cu")
		(net "VDD_CORE_EN")
	)
	(segment
		(start 25.146 18.288)
		(end 25.146 20.701)
		(width 0.14732)
		(layer "F.Cu")
		(net "VDD_CORE_EN")
	)
	(segment
		(start 25.146 20.701)
		(end 25.019 20.828)
		(width 0.14732)
		(layer "F.Cu")
		(net "VDD_CORE_EN")
	)
	(segment
		(start 25.019 24.80818)
		(end 25.527 25.31618)
		(width 0.14732)
		(layer "F.Cu")
		(net "VDD_CORE_EN")
	)
	(segment
		(start 25.019 20.828)
		(end 25.019 24.80818)
		(width 0.14732)
		(layer "F.Cu")
		(net "VDD_CORE_EN")
	)
	(segment
		(start 26.883182 25.174118)
		(end 26.924 25.1714)
		(width 0.127)
		(layer "F.Cu")
		(net "VDD_CORE_EN")
	)
	(segment
		(start 26.4668 25.5905)
		(end 26.883182 25.174118)
		(width 0.127)
		(layer "F.Cu")
		(net "VDD_CORE_EN")
	)
	(segment
		(start 27.571014 38.350012)
		(end 28.1686 38.350012)
		(width 0.14732)
		(layer "F.Cu")
		(net "VDD_CORE_EN")
	)
	(segment
		(start 27.03576 38.42766)
		(end 27.493366 38.42766)
		(width 0.14732)
		(layer "F.Cu")
		(net "VDD_CORE_EN")
	)
	(segment
		(start 26.3271 37.719)
		(end 27.03576 38.42766)
		(width 0.14732)
		(layer "F.Cu")
		(net "VDD_CORE_EN")
	)
	(segment
		(start 25.80132 25.5905)
		(end 26.4668 25.5905)
		(width 0.127)
		(layer "F.Cu")
		(net "VDD_CORE_EN")
	)
	(segment
		(start 27.493366 38.42766)
		(end 27.571014 38.350012)
		(width 0.14732)
		(layer "F.Cu")
		(net "VDD_CORE_EN")
	)
	(segment
		(start 26.162 17.272)
		(end 25.146 18.288)
		(width 0.14732)
		(layer "F.Cu")
		(net "VDD_CORE_EN")
	)
	(via
		(at 26.3271 37.719)
		(size 0.508)
		(drill 0.25654)
		(layers "F.Cu" "B.Cu")
		(net "VDD_CORE_EN")
	)
	(via
		(at 26.924 25.1714)
		(size 0.4572)
		(drill 0.20574)
		(layers "F.Cu" "B.Cu")
		(net "VDD_CORE_EN")
	)
	(segment
		(start 28.745993 25.548412)
		(end 27.301012 25.548412)
		(width 0.127)
		(layer "In1.Cu")
		(net "VDD_CORE_EN")
	)
	(segment
		(start 27.301012 25.548412)
		(end 26.924 25.1714)
		(width 0.127)
		(layer "In1.Cu")
		(net "VDD_CORE_EN")
	)
	(segment
		(start 24.892 28.702)
		(end 26.035 27.559)
		(width 0.12065)
		(layer "In6.Cu")
		(net "VDD_CORE_EN")
	)
	(segment
		(start 26.532459 25.562941)
		(end 26.924 25.1714)
		(width 0.12065)
		(layer "In6.Cu")
		(net "VDD_CORE_EN")
	)
	(segment
		(start 26.162 37.719)
		(end 25.273 36.83)
		(width 0.12065)
		(layer "In6.Cu")
		(net "VDD_CORE_EN")
	)
	(segment
		(start 25.146 30.861)
		(end 24.892 30.607)
		(width 0.12065)
		(layer "In6.Cu")
		(net "VDD_CORE_EN")
	)
	(segment
		(start 26.035 27.559)
		(end 26.035 26.67)
		(width 0.12065)
		(layer "In6.Cu")
		(net "VDD_CORE_EN")
	)
	(segment
		(start 26.3271 37.719)
		(end 26.162 37.719)
		(width 0.12065)
		(layer "In6.Cu")
		(net "VDD_CORE_EN")
	)
	(segment
		(start 26.532459 26.172541)
		(end 26.532459 25.562941)
		(width 0.12065)
		(layer "In6.Cu")
		(net "VDD_CORE_EN")
	)
	(segment
		(start 25.904825 34.345829)
		(end 25.904825 32.878979)
		(width 0.12065)
		(layer "In6.Cu")
		(net "VDD_CORE_EN")
	)
	(segment
		(start 24.892 30.607)
		(end 24.892 28.702)
		(width 0.12065)
		(layer "In6.Cu")
		(net "VDD_CORE_EN")
	)
	(segment
		(start 25.273 36.83)
		(end 25.273 34.977654)
		(width 0.12065)
		(layer "In6.Cu")
		(net "VDD_CORE_EN")
	)
	(segment
		(start 25.904825 32.878979)
		(end 25.146 32.120154)
		(width 0.12065)
		(layer "In6.Cu")
		(net "VDD_CORE_EN")
	)
	(segment
		(start 26.035 26.67)
		(end 26.532459 26.172541)
		(width 0.12065)
		(layer "In6.Cu")
		(net "VDD_CORE_EN")
	)
	(segment
		(start 25.273 34.977654)
		(end 25.904825 34.345829)
		(width 0.12065)
		(layer "In6.Cu")
		(net "VDD_CORE_EN")
	)
	(segment
		(start 25.146 32.120154)
		(end 25.146 30.861)
		(width 0.12065)
		(layer "In6.Cu")
		(net "VDD_CORE_EN")
	)
	(segment
		(start 54.237001 20.041997)
		(end 54.737 19.541998)
		(width 0.254)
		(layer "F.Cu")
		(net "VDD_CORE")
	)
	(segment
		(start 53.237003 33.041996)
		(end 52.737004 33.541995)
		(width 0.254)
		(layer "F.Cu")
		(net "VDD_CORE")
	)
	(segment
		(start 45.236968 25.042012)
		(end 44.736995 25.541986)
		(width 0.254)
		(layer "F.Cu")
		(net "VDD_CORE")
	)
	(segment
		(start 49.237011 27.042008)
		(end 48.737012 27.542007)
		(width 0.254)
		(layer "F.Cu")
		(net "VDD_CORE")
	)
	(segment
		(start 60.736988 34.541993)
		(end 60.236989 34.041994)
		(width 0.254)
		(layer "F.Cu")
		(net "VDD_CORE")
	)
	(segment
		(start 50.237009 30.042002)
		(end 49.73701 30.542001)
		(width 0.254)
		(layer "F.Cu")
		(net "VDD_CORE")
	)
	(segment
		(start 55.736998 23.54199)
		(end 55.236999 23.041991)
		(width 0.254)
		(layer "F.Cu")
		(net "VDD_CORE")
	)
	(segment
		(start 54.237001 12.041988)
		(end 53.737002 11.541989)
		(width 0.254)
		(layer "F.Cu")
		(net "VDD_CORE")
	)
	(segment
		(start 50.237009 16.042005)
		(end 49.73701 15.542006)
		(width 0.254)
		(layer "F.Cu")
		(net "VDD_CORE")
	)
	(segment
		(start 48.236988 22.041993)
		(end 47.736989 22.541992)
		(width 0.254)
		(layer "F.Cu")
		(net "VDD_CORE")
	)
	(segment
		(start 47.23699 11.04199)
		(end 46.736991 10.541991)
		(width 0.254)
		(layer "F.Cu")
		(net "VDD_CORE")
	)
	(segment
		(start 56.736996 22.541992)
		(end 56.236997 22.041993)
		(width 0.254)
		(layer "F.Cu")
		(net "VDD_CORE")
	)
	(segment
		(start 56.736996 32.541997)
		(end 56.236997 32.041998)
		(width 0.254)
		(layer "F.Cu")
		(net "VDD_CORE")
	)
	(segment
		(start 58.736992 26.542009)
		(end 58.236993 26.04201)
		(width 0.254)
		(layer "F.Cu")
		(net "VDD_CORE")
	)
	(segment
		(start 41.237002 23.041991)
		(end 40.737003 23.54199)
		(width 0.254)
		(layer "F.Cu")
		(net "VDD_CORE")
	)
	(segment
		(start 50.237009 24.041989)
		(end 49.73701 24.541988)
		(width 0.254)
		(layer "F.Cu")
		(net "VDD_CORE")
	)
	(segment
		(start 56.736996 20.541996)
		(end 56.236997 20.041997)
		(width 0.254)
		(layer "F.Cu")
		(net "VDD_CORE")
	)
	(segment
		(start 50.237009 28.042006)
		(end 49.73701 28.542005)
		(width 0.254)
		(layer "F.Cu")
		(net "VDD_CORE")
	)
	(segment
		(start 49.237011 21.041995)
		(end 48.737012 21.541994)
		(width 0.254)
		(layer "F.Cu")
		(net "VDD_CORE")
	)
	(segment
		(start 56.736996 30.542001)
		(end 56.236997 30.042002)
		(width 0.254)
		(layer "F.Cu")
		(net "VDD_CORE")
	)
	(segment
		(start 49.237011 13.042011)
		(end 48.737012 12.542012)
		(width 0.254)
		(layer "F.Cu")
		(net "VDD_CORE")
	)
	(segment
		(start 60.736988 32.541997)
		(end 60.236989 32.041998)
		(width 0.254)
		(layer "F.Cu")
		(net "VDD_CORE")
	)
	(segment
		(start 48.236988 20.041997)
		(end 47.736989 20.541996)
		(width 0.254)
		(layer "F.Cu")
		(net "VDD_CORE")
	)
	(segment
		(start 49.237011 19.041999)
		(end 48.737012 19.541998)
		(width 0.254)
		(layer "F.Cu")
		(net "VDD_CORE")
	)
	(segment
		(start 45.236994 27.042008)
		(end 44.736995 27.542007)
		(width 0.254)
		(layer "F.Cu")
		(net "VDD_CORE")
	)
	(segment
		(start 46.236992 14.042009)
		(end 45.736993 13.54201)
		(width 0.254)
		(layer "F.Cu")
		(net "VDD_CORE")
	)
	(segment
		(start 55.736998 16.542004)
		(end 55.236999 17.042003)
		(width 0.254)
		(layer "F.Cu")
		(net "VDD_CORE")
	)
	(segment
		(start 48.236988 16.042005)
		(end 47.736989 15.542006)
		(width 0.254)
		(layer "F.Cu")
		(net "VDD_CORE")
	)
	(segment
		(start 44.236996 30.042002)
		(end 43.736997 30.542001)
		(width 0.254)
		(layer "F.Cu")
		(net "VDD_CORE")
	)
	(segment
		(start 53.213 41.529)
		(end 56.2356 41.529)
		(width 0.2032)
		(layer "F.Cu")
		(net "VDD_CORE")
	)
	(segment
		(start 52.237005 10.041992)
		(end 51.737006 9.541993)
		(width 0.254)
		(layer "F.Cu")
		(net "VDD_CORE")
	)
	(segment
		(start 46.236992 26.04201)
		(end 45.736993 26.542009)
		(width 0.254)
		(layer "F.Cu")
		(net "VDD_CORE")
	)
	(segment
		(start 58.736992 17.542002)
		(end 58.236993 18.042001)
		(width 0.254)
		(layer "F.Cu")
		(net "VDD_CORE")
	)
	(segment
		(start 45.236994 11.04199)
		(end 44.736995 10.541991)
		(width 0.254)
		(layer "F.Cu")
		(net "VDD_CORE")
	)
	(segment
		(start 50.237009 20.041997)
		(end 49.73701 20.541996)
		(width 0.254)
		(layer "F.Cu")
		(net "VDD_CORE")
	)
	(segment
		(start 47.23699 31.042)
		(end 46.736991 31.541999)
		(width 0.254)
		(layer "F.Cu")
		(net "VDD_CORE")
	)
	(segment
		(start 56.736996 24.541988)
		(end 56.236997 24.041989)
		(width 0.254)
		(layer "F.Cu")
		(net "VDD_CORE")
	)
	(segment
		(start 51.237007 15.042007)
		(end 50.737008 14.542008)
		(width 0.254)
		(layer "F.Cu")
		(net "VDD_CORE")
	)
	(segment
		(start 51.237007 27.042008)
		(end 50.737008 27.542007)
		(width 0.254)
		(layer "F.Cu")
		(net "VDD_CORE")
	)
	(segment
		(start 52.237005 30.042002)
		(end 51.737006 30.542001)
		(width 0.254)
		(layer "F.Cu")
		(net "VDD_CORE")
	)
	(segment
		(start 60.736988 26.542009)
		(end 60.236989 26.04201)
		(width 0.254)
		(layer "F.Cu")
		(net "VDD_CORE")
	)
	(segment
		(start 49.237011 31.042)
		(end 48.737012 31.541999)
		(width 0.254)
		(layer "F.Cu")
		(net "VDD_CORE")
	)
	(segment
		(start 52.237005 14.042009)
		(end 51.737006 13.54201)
		(width 0.254)
		(layer "F.Cu")
		(net "VDD_CORE")
	)
	(segment
		(start 53.237003 19.041999)
		(end 52.737004 19.541998)
		(width 0.254)
		(layer "F.Cu")
		(net "VDD_CORE")
	)
	(segment
		(start 49.237011 15.042007)
		(end 48.737012 14.542008)
		(width 0.254)
		(layer "F.Cu")
		(net "VDD_CORE")
	)
	(segment
		(start 40.237004 24.041989)
		(end 39.737005 24.541988)
		(width 0.254)
		(layer "F.Cu")
		(net "VDD_CORE")
	)
	(segment
		(start 59.73699 10.541991)
		(end 59.236991 11.04199)
		(width 0.254)
		(layer "F.Cu")
		(net "VDD_CORE")
	)
	(segment
		(start 46.236992 18.042001)
		(end 45.736993 17.542002)
		(width 0.254)
		(layer "F.Cu")
		(net "VDD_CORE")
	)
	(segment
		(start 53.237003 23.041991)
		(end 52.737004 23.54199)
		(width 0.254)
		(layer "F.Cu")
		(net "VDD_CORE")
	)
	(segment
		(start 60.736988 28.542005)
		(end 60.236989 28.042006)
		(width 0.254)
		(layer "F.Cu")
		(net "VDD_CORE")
	)
	(segment
		(start 59.73699 16.542004)
		(end 59.236991 17.042003)
		(width 0.254)
		(layer "F.Cu")
		(net "VDD_CORE")
	)
	(segment
		(start 53.237003 15.042007)
		(end 52.737004 14.542008)
		(width 0.254)
		(layer "F.Cu")
		(net "VDD_CORE")
	)
	(segment
		(start 48.236988 24.041989)
		(end 47.736989 24.541988)
		(width 0.254)
		(layer "F.Cu")
		(net "VDD_CORE")
	)
	(segment
		(start 49.237011 29.042004)
		(end 48.737012 29.542003)
		(width 0.254)
		(layer "F.Cu")
		(net "VDD_CORE")
	)
	(segment
		(start 45.236994 33.041996)
		(end 44.736995 33.541995)
		(width 0.254)
		(layer "F.Cu")
		(net "VDD_CORE")
	)
	(segment
		(start 45.236994 29.042004)
		(end 44.736995 29.542003)
		(width 0.254)
		(layer "F.Cu")
		(net "VDD_CORE")
	)
	(segment
		(start 52.237005 16.042005)
		(end 51.737006 15.542006)
		(width 0.254)
		(layer "F.Cu")
		(net "VDD_CORE")
	)
	(segment
		(start 60.736988 11.541989)
		(end 60.236989 12.041988)
		(width 0.254)
		(layer "F.Cu")
		(net "VDD_CORE")
	)
	(segment
		(start 56.736996 34.541993)
		(end 56.236997 34.041994)
		(width 0.254)
		(layer "F.Cu")
		(net "VDD_CORE")
	)
	(segment
		(start 45.236994 21.041995)
		(end 44.736995 21.541994)
		(width 0.254)
		(layer "F.Cu")
		(net "VDD_CORE")
	)
	(segment
		(start 59.73699 31.541999)
		(end 59.236991 31.042)
		(width 0.254)
		(layer "F.Cu")
		(net "VDD_CORE")
	)
	(segment
		(start 47.23699 29.042004)
		(end 46.736991 29.542003)
		(width 0.254)
		(layer "F.Cu")
		(net "VDD_CORE")
	)
	(segment
		(start 52.237005 12.041988)
		(end 51.737006 11.541989)
		(width 0.254)
		(layer "F.Cu")
		(net "VDD_CORE")
	)
	(segment
		(start 55.736998 27.542007)
		(end 55.236999 27.042008)
		(width 0.254)
		(layer "F.Cu")
		(net "VDD_CORE")
	)
	(segment
		(start 56.2356 41.529)
		(end 56.2483 41.5417)
		(width 0.2032)
		(layer "F.Cu")
		(net "VDD_CORE")
	)
	(segment
		(start 51.237007 17.042003)
		(end 50.737008 16.542004)
		(width 0.254)
		(layer "F.Cu")
		(net "VDD_CORE")
	)
	(segment
		(start 47.23699 17.042003)
		(end 46.736991 16.542004)
		(width 0.254)
		(layer "F.Cu")
		(net "VDD_CORE")
	)
	(segment
		(start 57.736994 16.542004)
		(end 57.236995 17.042003)
		(width 0.254)
		(layer "F.Cu")
		(net "VDD_CORE")
	)
	(segment
		(start 55.736998 33.541995)
		(end 55.236999 33.041996)
		(width 0.254)
		(layer "F.Cu")
		(net "VDD_CORE")
	)
	(segment
		(start 55.736998 12.542012)
		(end 55.236999 13.042011)
		(width 0.254)
		(layer "F.Cu")
		(net "VDD_CORE")
	)
	(segment
		(start 53.237003 25.042012)
		(end 52.737004 25.542011)
		(width 0.254)
		(layer "F.Cu")
		(net "VDD_CORE")
	)
	(segment
		(start 50.237009 14.042009)
		(end 49.73701 13.54201)
		(width 0.254)
		(layer "F.Cu")
		(net "VDD_CORE")
	)
	(segment
		(start 60.736988 17.542002)
		(end 60.236989 18.042001)
		(width 0.254)
		(layer "F.Cu")
		(net "VDD_CORE")
	)
	(segment
		(start 51.237007 33.041996)
		(end 50.737008 33.541995)
		(width 0.254)
		(layer "F.Cu")
		(net "VDD_CORE")
	)
	(segment
		(start 55.736998 19.541998)
		(end 55.236999 19.041999)
		(width 0.254)
		(layer "F.Cu")
		(net "VDD_CORE")
	)
	(segment
		(start 58.736992 11.541989)
		(end 58.236993 12.041988)
		(width 0.254)
		(layer "F.Cu")
		(net "VDD_CORE")
	)
	(segment
		(start 49.237011 33.041996)
		(end 48.737012 33.541995)
		(width 0.254)
		(layer "F.Cu")
		(net "VDD_CORE")
	)
	(segment
		(start 47.23699 13.042011)
		(end 46.736991 12.542012)
		(width 0.254)
		(layer "F.Cu")
		(net "VDD_CORE")
	)
	(segment
		(start 55.736998 14.542008)
		(end 55.236999 15.042007)
		(width 0.254)
		(layer "F.Cu")
		(net "VDD_CORE")
	)
	(segment
		(start 53.237003 13.042011)
		(end 52.737004 12.542012)
		(width 0.254)
		(layer "F.Cu")
		(net "VDD_CORE")
	)
	(segment
		(start 60.736988 13.54201)
		(end 60.236989 14.042009)
		(width 0.254)
		(layer "F.Cu")
		(net "VDD_CORE")
	)
	(segment
		(start 56.736996 17.542002)
		(end 56.236997 18.042001)
		(width 0.254)
		(layer "F.Cu")
		(net "VDD_CORE")
	)
	(segment
		(start 51.237007 25.042012)
		(end 50.737008 25.542011)
		(width 0.254)
		(layer "F.Cu")
		(net "VDD_CORE")
	)
	(segment
		(start 57.736994 12.542012)
		(end 57.236995 13.042011)
		(width 0.254)
		(layer "F.Cu")
		(net "VDD_CORE")
	)
	(segment
		(start 65.4431 37.6809)
		(end 65.4431 36.957)
		(width 0.2032)
		(layer "F.Cu")
		(net "VDD_CORE")
	)
	(segment
		(start 53.237003 17.042003)
		(end 52.737004 16.542004)
		(width 0.254)
		(layer "F.Cu")
		(net "VDD_CORE")
	)
	(segment
		(start 48.236988 18.042001)
		(end 47.736989 17.542002)
		(width 0.254)
		(layer "F.Cu")
		(net "VDD_CORE")
	)
	(segment
		(start 57.736994 19.541998)
		(end 57.236995 19.041999)
		(width 0.254)
		(layer "F.Cu")
		(net "VDD_CORE")
	)
	(segment
		(start 47.23699 23.041991)
		(end 46.736991 23.54199)
		(width 0.254)
		(layer "F.Cu")
		(net "VDD_CORE")
	)
	(segment
		(start 54.237001 30.042002)
		(end 53.737002 30.542001)
		(width 0.254)
		(layer "F.Cu")
		(net "VDD_CORE")
	)
	(segment
		(start 55.736998 10.541991)
		(end 55.236999 11.04199)
		(width 0.254)
		(layer "F.Cu")
		(net "VDD_CORE")
	)
	(segment
		(start 50.237009 10.041992)
		(end 49.73701 9.541993)
		(width 0.254)
		(layer "F.Cu")
		(net "VDD_CORE")
	)
	(segment
		(start 52.237005 24.041989)
		(end 51.737006 24.541988)
		(width 0.254)
		(layer "F.Cu")
		(net "VDD_CORE")
	)
	(segment
		(start 57.736994 14.542008)
		(end 57.236995 15.042007)
		(width 0.254)
		(layer "F.Cu")
		(net "VDD_CORE")
	)
	(segment
		(start 52.237005 32.041998)
		(end 51.737006 32.541997)
		(width 0.254)
		(layer "F.Cu")
		(net "VDD_CORE")
	)
	(segment
		(start 51.237007 19.041999)
		(end 50.737008 19.541998)
		(width 0.254)
		(layer "F.Cu")
		(net "VDD_CORE")
	)
	(segment
		(start 53.237003 27.042008)
		(end 52.737004 27.542007)
		(width 0.254)
		(layer "F.Cu")
		(net "VDD_CORE")
	)
	(segment
		(start 55.736998 25.542011)
		(end 55.236999 25.042012)
		(width 0.254)
		(layer "F.Cu")
		(net "VDD_CORE")
	)
	(segment
		(start 49.237011 11.04199)
		(end 48.737012 10.541991)
		(width 0.254)
		(layer "F.Cu")
		(net "VDD_CORE")
	)
	(segment
		(start 59.73699 21.541994)
		(end 59.236991 21.041995)
		(width 0.254)
		(layer "F.Cu")
		(net "VDD_CORE")
	)
	(segment
		(start 54.237001 22.041993)
		(end 54.737 22.541992)
		(width 0.254)
		(layer "F.Cu")
		(net "VDD_CORE")
	)
	(segment
		(start 64.643 41.529)
		(end 64.897 41.275)
		(width 0.2032)
		(layer "F.Cu")
		(net "VDD_CORE")
	)
	(segment
		(start 59.73699 25.542011)
		(end 59.236991 25.042012)
		(width 0.254)
		(layer "F.Cu")
		(net "VDD_CORE")
	)
	(segment
		(start 58.736992 30.542001)
		(end 58.236993 30.042002)
		(width 0.254)
		(layer "F.Cu")
		(net "VDD_CORE")
	)
	(segment
		(start 54.237001 34.041994)
		(end 53.737002 34.541993)
		(width 0.254)
		(layer "F.Cu")
		(net "VDD_CORE")
	)
	(segment
		(start 54.237001 32.041998)
		(end 53.737002 32.541997)
		(width 0.254)
		(layer "F.Cu")
		(net "VDD_CORE")
	)
	(segment
		(start 51.237007 13.042011)
		(end 50.737008 12.542012)
		(width 0.254)
		(layer "F.Cu")
		(net "VDD_CORE")
	)
	(segment
		(start 49.237011 23.041991)
		(end 48.737012 23.54199)
		(width 0.254)
		(layer "F.Cu")
		(net "VDD_CORE")
	)
	(segment
		(start 58.736992 34.541993)
		(end 58.236993 34.041994)
		(width 0.254)
		(layer "F.Cu")
		(net "VDD_CORE")
	)
	(segment
		(start 53.1749 36.957)
		(end 53.1749 36.9951)
		(width 0.2032)
		(layer "F.Cu")
		(net "VDD_CORE")
	)
	(segment
		(start 56.736996 13.54201)
		(end 56.236997 14.042009)
		(width 0.254)
		(layer "F.Cu")
		(net "VDD_CORE")
	)
	(segment
		(start 60.736988 24.541988)
		(end 60.236989 24.041989)
		(width 0.254)
		(layer "F.Cu")
		(net "VDD_CORE")
	)
	(segment
		(start 61.2267 41.5417)
		(end 61.2394 41.529)
		(width 0.2032)
		(layer "F.Cu")
		(net "VDD_CORE")
	)
	(segment
		(start 47.23699 21.041995)
		(end 46.736991 21.541994)
		(width 0.254)
		(layer "F.Cu")
		(net "VDD_CORE")
	)
	(segment
		(start 57.736994 31.541999)
		(end 57.236995 31.042)
		(width 0.254)
		(layer "F.Cu")
		(net "VDD_CORE")
	)
	(segment
		(start 46.236992 22.041993)
		(end 45.736993 22.541992)
		(width 0.254)
		(layer "F.Cu")
		(net "VDD_CORE")
	)
	(segment
		(start 47.23699 33.041996)
		(end 46.736991 33.541995)
		(width 0.254)
		(layer "F.Cu")
		(net "VDD_CORE")
	)
	(segment
		(start 46.236992 20.041997)
		(end 45.736993 20.541996)
		(width 0.254)
		(layer "F.Cu")
		(net "VDD_CORE")
	)
	(segment
		(start 46.236992 28.042006)
		(end 45.736993 28.542005)
		(width 0.254)
		(layer "F.Cu")
		(net "VDD_CORE")
	)
	(segment
		(start 54.237001 24.041989)
		(end 53.737002 24.541988)
		(width 0.254)
		(layer "F.Cu")
		(net "VDD_CORE")
	)
	(segment
		(start 60.736988 22.541992)
		(end 60.236989 22.041993)
		(width 0.254)
		(layer "F.Cu")
		(net "VDD_CORE")
	)
	(segment
		(start 58.736992 24.541988)
		(end 58.236993 24.041989)
		(width 0.254)
		(layer "F.Cu")
		(net "VDD_CORE")
	)
	(segment
		(start 58.736992 20.541996)
		(end 58.236993 20.041997)
		(width 0.254)
		(layer "F.Cu")
		(net "VDD_CORE")
	)
	(segment
		(start 57.736994 10.541991)
		(end 57.236995 11.04199)
		(width 0.254)
		(layer "F.Cu")
		(net "VDD_CORE")
	)
	(segment
		(start 58.736992 22.541992)
		(end 58.236993 22.041993)
		(width 0.254)
		(layer "F.Cu")
		(net "VDD_CORE")
	)
	(segment
		(start 48.236988 28.042006)
		(end 47.736989 28.542005)
		(width 0.254)
		(layer "F.Cu")
		(net "VDD_CORE")
	)
	(segment
		(start 48.236988 34.041994)
		(end 47.736989 34.541993)
		(width 0.254)
		(layer "F.Cu")
		(net "VDD_CORE")
	)
	(segment
		(start 49.237011 17.042003)
		(end 48.737012 16.542004)
		(width 0.254)
		(layer "F.Cu")
		(net "VDD_CORE")
	)
	(segment
		(start 56.736996 9.541993)
		(end 56.236997 10.041992)
		(width 0.254)
		(layer "F.Cu")
		(net "VDD_CORE")
	)
	(segment
		(start 52.237005 20.041997)
		(end 51.737006 20.541996)
		(width 0.254)
		(layer "F.Cu")
		(net "VDD_CORE")
	)
	(segment
		(start 41.237002 24.041989)
		(end 40.737003 24.541988)
		(width 0.254)
		(layer "F.Cu")
		(net "VDD_CORE")
	)
	(segment
		(start 52.705 41.021)
		(end 53.213 41.529)
		(width 0.2032)
		(layer "F.Cu")
		(net "VDD_CORE")
	)
	(segment
		(start 53.1749 36.9951)
		(end 52.705 37.465)
		(width 0.2032)
		(layer "F.Cu")
		(net "VDD_CORE")
	)
	(segment
		(start 59.73699 33.541995)
		(end 59.236991 33.041996)
		(width 0.254)
		(layer "F.Cu")
		(net "VDD_CORE")
	)
	(segment
		(start 51.237007 23.041991)
		(end 50.737008 23.54199)
		(width 0.254)
		(layer "F.Cu")
		(net "VDD_CORE")
	)
	(segment
		(start 57.736994 21.541994)
		(end 57.236995 21.041995)
		(width 0.254)
		(layer "F.Cu")
		(net "VDD_CORE")
	)
	(segment
		(start 47.23699 25.042012)
		(end 46.736991 25.542011)
		(width 0.254)
		(layer "F.Cu")
		(net "VDD_CORE")
	)
	(segment
		(start 55.736998 29.542003)
		(end 55.236999 29.042004)
		(width 0.254)
		(layer "F.Cu")
		(net "VDD_CORE")
	)
	(segment
		(start 48.236988 30.042002)
		(end 47.736989 30.542001)
		(width 0.254)
		(layer "F.Cu")
		(net "VDD_CORE")
	)
	(segment
		(start 54.237001 28.042006)
		(end 53.737002 28.542005)
		(width 0.254)
		(layer "F.Cu")
		(net "VDD_CORE")
	)
	(segment
		(start 60.736988 20.541996)
		(end 60.236989 20.041997)
		(width 0.254)
		(layer "F.Cu")
		(net "VDD_CORE")
	)
	(segment
		(start 57.736994 23.54199)
		(end 57.236995 23.041991)
		(width 0.254)
		(layer "F.Cu")
		(net "VDD_CORE")
	)
	(segment
		(start 56.736996 11.541989)
		(end 56.236997 12.041988)
		(width 0.254)
		(layer "F.Cu")
		(net "VDD_CORE")
	)
	(segment
		(start 58.736992 32.541997)
		(end 58.236993 32.041998)
		(width 0.254)
		(layer "F.Cu")
		(net "VDD_CORE")
	)
	(segment
		(start 55.736998 21.541994)
		(end 55.236999 21.041995)
		(width 0.254)
		(layer "F.Cu")
		(net "VDD_CORE")
	)
	(segment
		(start 58.736992 28.542005)
		(end 58.236993 28.042006)
		(width 0.254)
		(layer "F.Cu")
		(net "VDD_CORE")
	)
	(segment
		(start 64.897 38.227)
		(end 65.4431 37.6809)
		(width 0.2032)
		(layer "F.Cu")
		(net "VDD_CORE")
	)
	(segment
		(start 58.736992 15.542006)
		(end 58.236993 16.042005)
		(width 0.254)
		(layer "F.Cu")
		(net "VDD_CORE")
	)
	(segment
		(start 53.237003 29.042004)
		(end 52.737004 29.542003)
		(width 0.254)
		(layer "F.Cu")
		(net "VDD_CORE")
	)
	(segment
		(start 64.897 41.275)
		(end 64.897 38.227)
		(width 0.2032)
		(layer "F.Cu")
		(net "VDD_CORE")
	)
	(segment
		(start 54.237001 14.042009)
		(end 53.737002 13.54201)
		(width 0.254)
		(layer "F.Cu")
		(net "VDD_CORE")
	)
	(segment
		(start 51.237007 11.04199)
		(end 50.737008 10.541991)
		(width 0.254)
		(layer "F.Cu")
		(net "VDD_CORE")
	)
	(segment
		(start 54.237001 18.042001)
		(end 53.737002 17.542002)
		(width 0.254)
		(layer "F.Cu")
		(net "VDD_CORE")
	)
	(segment
		(start 50.237009 32.041998)
		(end 49.73701 32.541997)
		(width 0.254)
		(layer "F.Cu")
		(net "VDD_CORE")
	)
	(segment
		(start 46.236992 32.041998)
		(end 45.736993 32.541997)
		(width 0.254)
		(layer "F.Cu")
		(net "VDD_CORE")
	)
	(segment
		(start 50.237009 26.04201)
		(end 49.73701 26.542009)
		(width 0.254)
		(layer "F.Cu")
		(net "VDD_CORE")
	)
	(segment
		(start 50.237009 18.042001)
		(end 49.73701 17.542002)
		(width 0.254)
		(layer "F.Cu")
		(net "VDD_CORE")
	)
	(segment
		(start 46.236992 34.041994)
		(end 45.736993 34.541993)
		(width 0.254)
		(layer "F.Cu")
		(net "VDD_CORE")
	)
	(segment
		(start 52.237005 26.04201)
		(end 51.737006 26.542009)
		(width 0.254)
		(layer "F.Cu")
		(net "VDD_CORE")
	)
	(segment
		(start 52.237005 22.041993)
		(end 51.737006 22.541992)
		(width 0.254)
		(layer "F.Cu")
		(net "VDD_CORE")
	)
	(segment
		(start 48.236988 26.04201)
		(end 47.736989 26.542009)
		(width 0.254)
		(layer "F.Cu")
		(net "VDD_CORE")
	)
	(segment
		(start 42.291 41.6306)
		(end 42.291 40.386)
		(width 0.508)
		(layer "F.Cu")
		(net "VDD_CORE")
	)
	(segment
		(start 59.73699 12.542012)
		(end 59.236991 13.042011)
		(width 0.254)
		(layer "F.Cu")
		(net "VDD_CORE")
	)
	(segment
		(start 54.237001 16.042005)
		(end 53.737002 15.542006)
		(width 0.254)
		(layer "F.Cu")
		(net "VDD_CORE")
	)
	(segment
		(start 52.237005 18.042001)
		(end 51.737006 17.542002)
		(width 0.254)
		(layer "F.Cu")
		(net "VDD_CORE")
	)
	(segment
		(start 50.237009 34.041994)
		(end 49.73701 34.541993)
		(width 0.254)
		(layer "F.Cu")
		(net "VDD_CORE")
	)
	(segment
		(start 59.73699 27.542007)
		(end 59.236991 27.042008)
		(width 0.254)
		(layer "F.Cu")
		(net "VDD_CORE")
	)
	(segment
		(start 57.736994 25.542011)
		(end 57.236995 25.042012)
		(width 0.254)
		(layer "F.Cu")
		(net "VDD_CORE")
	)
	(segment
		(start 42.237 24.041989)
		(end 41.737001 24.541988)
		(width 0.254)
		(layer "F.Cu")
		(net "VDD_CORE")
	)
	(segment
		(start 50.237009 12.041988)
		(end 49.73701 11.541989)
		(width 0.254)
		(layer "F.Cu")
		(net "VDD_CORE")
	)
	(segment
		(start 59.73699 14.542008)
		(end 59.236991 15.042007)
		(width 0.254)
		(layer "F.Cu")
		(net "VDD_CORE")
	)
	(segment
		(start 61.2394 41.529)
		(end 64.643 41.529)
		(width 0.2032)
		(layer "F.Cu")
		(net "VDD_CORE")
	)
	(segment
		(start 56.736996 28.542005)
		(end 56.236997 28.042006)
		(width 0.254)
		(layer "F.Cu")
		(net "VDD_CORE")
	)
	(segment
		(start 51.237007 31.042)
		(end 50.737008 31.541999)
		(width 0.254)
		(layer "F.Cu")
		(net "VDD_CORE")
	)
	(segment
		(start 45.236994 23.041991)
		(end 44.736995 23.54199)
		(width 0.254)
		(layer "F.Cu")
		(net "VDD_CORE")
	)
	(segment
		(start 56.736996 26.542009)
		(end 56.236997 26.04201)
		(width 0.254)
		(layer "F.Cu")
		(net "VDD_CORE")
	)
	(segment
		(start 47.23699 19.041999)
		(end 46.736991 19.541998)
		(width 0.254)
		(layer "F.Cu")
		(net "VDD_CORE")
	)
	(segment
		(start 51.237007 29.042004)
		(end 50.737008 29.542003)
		(width 0.254)
		(layer "F.Cu")
		(net "VDD_CORE")
	)
	(segment
		(start 48.236988 32.041998)
		(end 47.736989 32.541997)
		(width 0.254)
		(layer "F.Cu")
		(net "VDD_CORE")
	)
	(segment
		(start 57.736994 29.542003)
		(end 57.236995 29.042004)
		(width 0.254)
		(layer "F.Cu")
		(net "VDD_CORE")
	)
	(segment
		(start 49.237011 25.042012)
		(end 48.737012 25.542011)
		(width 0.254)
		(layer "F.Cu")
		(net "VDD_CORE")
	)
	(segment
		(start 52.237005 34.041994)
		(end 51.737006 34.541993)
		(width 0.254)
		(layer "F.Cu")
		(net "VDD_CORE")
	)
	(segment
		(start 46.236992 30.042002)
		(end 45.736993 30.542001)
		(width 0.254)
		(layer "F.Cu")
		(net "VDD_CORE")
	)
	(segment
		(start 50.237009 22.041993)
		(end 49.73701 22.541992)
		(width 0.254)
		(layer "F.Cu")
		(net "VDD_CORE")
	)
	(segment
		(start 52.705 37.465)
		(end 52.705 41.021)
		(width 0.2032)
		(layer "F.Cu")
		(net "VDD_CORE")
	)
	(segment
		(start 45.236994 19.041999)
		(end 44.736995 19.541998)
		(width 0.254)
		(layer "F.Cu")
		(net "VDD_CORE")
	)
	(segment
		(start 60.736988 15.542006)
		(end 60.236989 16.042005)
		(width 0.254)
		(layer "F.Cu")
		(net "VDD_CORE")
	)
	(segment
		(start 48.236988 12.041988)
		(end 47.736989 11.541989)
		(width 0.254)
		(layer "F.Cu")
		(net "VDD_CORE")
	)
	(segment
		(start 54.237001 10.041992)
		(end 53.737002 9.541993)
		(width 0.254)
		(layer "F.Cu")
		(net "VDD_CORE")
	)
	(segment
		(start 54.237001 26.04201)
		(end 53.737002 26.542009)
		(width 0.254)
		(layer "F.Cu")
		(net "VDD_CORE")
	)
	(segment
		(start 57.736994 33.541995)
		(end 57.236995 33.041996)
		(width 0.254)
		(layer "F.Cu")
		(net "VDD_CORE")
	)
	(segment
		(start 44.236996 28.042006)
		(end 43.736997 28.542005)
		(width 0.254)
		(layer "F.Cu")
		(net "VDD_CORE")
	)
	(segment
		(start 60.736988 30.542001)
		(end 60.236989 30.042002)
		(width 0.254)
		(layer "F.Cu")
		(net "VDD_CORE")
	)
	(segment
		(start 53.237003 11.04199)
		(end 52.737004 10.541991)
		(width 0.254)
		(layer "F.Cu")
		(net "VDD_CORE")
	)
	(segment
		(start 45.236994 31.042)
		(end 44.736995 31.541999)
		(width 0.254)
		(layer "F.Cu")
		(net "VDD_CORE")
	)
	(segment
		(start 46.236992 24.041989)
		(end 45.736993 24.541988)
		(width 0.254)
		(layer "F.Cu")
		(net "VDD_CORE")
	)
	(segment
		(start 47.23699 27.042008)
		(end 46.736991 27.542007)
		(width 0.254)
		(layer "F.Cu")
		(net "VDD_CORE")
	)
	(segment
		(start 55.736998 31.541999)
		(end 55.236999 31.042)
		(width 0.254)
		(layer "F.Cu")
		(net "VDD_CORE")
	)
	(segment
		(start 56.736996 15.542006)
		(end 56.236997 16.042005)
		(width 0.254)
		(layer "F.Cu")
		(net "VDD_CORE")
	)
	(segment
		(start 58.736992 13.54201)
		(end 58.236993 14.042009)
		(width 0.254)
		(layer "F.Cu")
		(net "VDD_CORE")
	)
	(segment
		(start 53.237003 21.041995)
		(end 52.737004 21.541994)
		(width 0.254)
		(layer "F.Cu")
		(net "VDD_CORE")
	)
	(segment
		(start 52.237005 28.042006)
		(end 51.737006 28.542005)
		(width 0.254)
		(layer "F.Cu")
		(net "VDD_CORE")
	)
	(segment
		(start 45.236994 25.042012)
		(end 45.236968 25.042012)
		(width 0.254)
		(layer "F.Cu")
		(net "VDD_CORE")
	)
	(segment
		(start 59.73699 23.54199)
		(end 59.236991 23.041991)
		(width 0.254)
		(layer "F.Cu")
		(net "VDD_CORE")
	)
	(segment
		(start 46.236992 16.042005)
		(end 45.736993 15.542006)
		(width 0.254)
		(layer "F.Cu")
		(net "VDD_CORE")
	)
	(segment
		(start 48.236988 14.042009)
		(end 47.736989 13.54201)
		(width 0.254)
		(layer "F.Cu")
		(net "VDD_CORE")
	)
	(segment
		(start 59.73699 19.541998)
		(end 59.236991 19.041999)
		(width 0.254)
		(layer "F.Cu")
		(net "VDD_CORE")
	)
	(segment
		(start 51.237007 21.041995)
		(end 50.737008 21.541994)
		(width 0.254)
		(layer "F.Cu")
		(net "VDD_CORE")
	)
	(segment
		(start 57.736994 27.542007)
		(end 57.236995 27.042008)
		(width 0.254)
		(layer "F.Cu")
		(net "VDD_CORE")
	)
	(segment
		(start 53.237003 31.042)
		(end 52.737004 31.541999)
		(width 0.254)
		(layer "F.Cu")
		(net "VDD_CORE")
	)
	(segment
		(start 59.73699 29.542003)
		(end 59.236991 29.042004)
		(width 0.254)
		(layer "F.Cu")
		(net "VDD_CORE")
	)
	(via
		(at 46.736991 29.542003)
		(size 0.4826)
		(drill 0.20574)
		(layers "F.Cu" "B.Cu")
		(net "VDD_CORE")
	)
	(via
		(at 46.736991 27.542007)
		(size 0.4826)
		(drill 0.20574)
		(layers "F.Cu" "B.Cu")
		(net "VDD_CORE")
	)
	(via
		(at 44.736995 21.541994)
		(size 0.4826)
		(drill 0.20574)
		(layers "F.Cu" "B.Cu")
		(net "VDD_CORE")
	)
	(via
		(at 40.737003 23.54199)
		(size 0.4826)
		(drill 0.20574)
		(layers "F.Cu" "B.Cu")
		(net "VDD_CORE")
	)
	(via
		(at 60.736988 34.541993)
		(size 0.4826)
		(drill 0.20574)
		(layers "F.Cu" "B.Cu")
		(net "VDD_CORE")
	)
	(via
		(at 55.736998 29.542003)
		(size 0.4826)
		(drill 0.20574)
		(layers "F.Cu" "B.Cu")
		(net "VDD_CORE")
	)
	(via
		(at 51.737006 20.541996)
		(size 0.4826)
		(drill 0.20574)
		(layers "F.Cu" "B.Cu")
		(net "VDD_CORE")
	)
	(via
		(at 53.737002 11.541989)
		(size 0.4826)
		(drill 0.20574)
		(layers "F.Cu" "B.Cu")
		(net "VDD_CORE")
	)
	(via
		(at 57.736994 27.542007)
		(size 0.4826)
		(drill 0.20574)
		(layers "F.Cu" "B.Cu")
		(net "VDD_CORE")
	)
	(via
		(at 57.736994 10.541991)
		(size 0.4826)
		(drill 0.20574)
		(layers "F.Cu" "B.Cu")
		(net "VDD_CORE")
	)
	(via
		(at 48.737012 25.542011)
		(size 0.4826)
		(drill 0.20574)
		(layers "F.Cu" "B.Cu")
		(net "VDD_CORE")
	)
	(via
		(at 55.736998 25.542011)
		(size 0.4826)
		(drill 0.20574)
		(layers "F.Cu" "B.Cu")
		(net "VDD_CORE")
	)
	(via
		(at 55.736998 31.541999)
		(size 0.4826)
		(drill 0.20574)
		(layers "F.Cu" "B.Cu")
		(net "VDD_CORE")
	)
	(via
		(at 47.736989 13.54201)
		(size 0.4826)
		(drill 0.20574)
		(layers "F.Cu" "B.Cu")
		(net "VDD_CORE")
	)
	(via
		(at 51.737006 13.54201)
		(size 0.4826)
		(drill 0.20574)
		(layers "F.Cu" "B.Cu")
		(net "VDD_CORE")
	)
	(via
		(at 51.737006 24.541988)
		(size 0.4826)
		(drill 0.25654)
		(layers "F.Cu" "B.Cu")
		(net "VDD_CORE")
	)
	(via
		(at 60.579 41.1099)
		(size 0.508)
		(drill 0.25654)
		(layers "F.Cu" "B.Cu")
		(net "VDD_CORE")
	)
	(via
		(at 47.736989 15.542006)
		(size 0.4826)
		(drill 0.20574)
		(layers "F.Cu" "B.Cu")
		(net "VDD_CORE")
	)
	(via
		(at 61.849 41.1099)
		(size 0.508)
		(drill 0.25654)
		(layers "F.Cu" "B.Cu")
		(net "VDD_CORE")
	)
	(via
		(at 39.737005 24.541988)
		(size 0.4826)
		(drill 0.20574)
		(layers "F.Cu" "B.Cu")
		(net "VDD_CORE")
	)
	(via
		(at 58.736992 24.541988)
		(size 0.4826)
		(drill 0.20574)
		(layers "F.Cu" "B.Cu")
		(net "VDD_CORE")
	)
	(via
		(at 47.736989 30.542001)
		(size 0.4826)
		(drill 0.20574)
		(layers "F.Cu" "B.Cu")
		(net "VDD_CORE")
	)
	(via
		(at 45.736993 22.541992)
		(size 0.4826)
		(drill 0.20574)
		(layers "F.Cu" "B.Cu")
		(net "VDD_CORE")
	)
	(via
		(at 54.737 19.541998)
		(size 0.4826)
		(drill 0.20574)
		(layers "F.Cu" "B.Cu")
		(net "VDD_CORE")
	)
	(via
		(at 49.73701 9.541993)
		(size 0.4826)
		(drill 0.20574)
		(layers "F.Cu" "B.Cu")
		(net "VDD_CORE")
	)
	(via
		(at 60.736988 20.541996)
		(size 0.4826)
		(drill 0.20574)
		(layers "F.Cu" "B.Cu")
		(net "VDD_CORE")
	)
	(via
		(at 59.73699 27.542007)
		(size 0.4826)
		(drill 0.20574)
		(layers "F.Cu" "B.Cu")
		(net "VDD_CORE")
	)
	(via
		(at 60.325 44.0055)
		(size 1.016)
		(drill 0.508)
		(layers "F.Cu" "B.Cu")
		(net "VDD_CORE")
	)
	(via
		(at 57.736994 14.542008)
		(size 0.4826)
		(drill 0.20574)
		(layers "F.Cu" "B.Cu")
		(net "VDD_CORE")
	)
	(via
		(at 61.976 44.0055)
		(size 1.016)
		(drill 0.508)
		(layers "F.Cu" "B.Cu")
		(net "VDD_CORE")
	)
	(via
		(at 57.277 41.1099)
		(size 0.508)
		(drill 0.25654)
		(layers "F.Cu" "B.Cu")
		(net "VDD_CORE")
	)
	(via
		(at 51.737006 26.542009)
		(size 0.4826)
		(drill 0.20574)
		(layers "F.Cu" "B.Cu")
		(net "VDD_CORE")
	)
	(via
		(at 58.736992 32.541997)
		(size 0.4826)
		(drill 0.20574)
		(layers "F.Cu" "B.Cu")
		(net "VDD_CORE")
	)
	(via
		(at 60.736988 30.542001)
		(size 0.4826)
		(drill 0.20574)
		(layers "F.Cu" "B.Cu")
		(net "VDD_CORE")
	)
	(via
		(at 53.737002 28.542005)
		(size 0.4826)
		(drill 0.20574)
		(layers "F.Cu" "B.Cu")
		(net "VDD_CORE")
	)
	(via
		(at 47.736989 20.541996)
		(size 0.4826)
		(drill 0.20574)
		(layers "F.Cu" "B.Cu")
		(net "VDD_CORE")
	)
	(via
		(at 60.736988 28.542005)
		(size 0.4826)
		(drill 0.20574)
		(layers "F.Cu" "B.Cu")
		(net "VDD_CORE")
	)
	(via
		(at 46.736991 16.542004)
		(size 0.4826)
		(drill 0.20574)
		(layers "F.Cu" "B.Cu")
		(net "VDD_CORE")
	)
	(via
		(at 43.736997 28.542005)
		(size 0.4826)
		(drill 0.20574)
		(layers "F.Cu" "B.Cu")
		(net "VDD_CORE")
	)
	(via
		(at 50.737008 12.542012)
		(size 0.4826)
		(drill 0.20574)
		(layers "F.Cu" "B.Cu")
		(net "VDD_CORE")
	)
	(via
		(at 50.737008 31.541999)
		(size 0.4826)
		(drill 0.20574)
		(layers "F.Cu" "B.Cu")
		(net "VDD_CORE")
	)
	(via
		(at 58.674 39.0525)
		(size 1.016)
		(drill 0.508)
		(layers "F.Cu" "B.Cu")
		(net "VDD_CORE")
	)
	(via
		(at 57.736994 12.542012)
		(size 0.4826)
		(drill 0.20574)
		(layers "F.Cu" "B.Cu")
		(net "VDD_CORE")
	)
	(via
		(at 49.73701 15.542006)
		(size 0.4826)
		(drill 0.20574)
		(layers "F.Cu" "B.Cu")
		(net "VDD_CORE")
	)
	(via
		(at 55.736998 23.54199)
		(size 0.4826)
		(drill 0.20574)
		(layers "F.Cu" "B.Cu")
		(net "VDD_CORE")
	)
	(via
		(at 53.737002 24.541988)
		(size 0.4826)
		(drill 0.20574)
		(layers "F.Cu" "B.Cu")
		(net "VDD_CORE")
	)
	(via
		(at 52.737004 10.541991)
		(size 0.4826)
		(drill 0.20574)
		(layers "F.Cu" "B.Cu")
		(net "VDD_CORE")
	)
	(via
		(at 48.737012 19.541998)
		(size 0.4826)
		(drill 0.20574)
		(layers "F.Cu" "B.Cu")
		(net "VDD_CORE")
	)
	(via
		(at 52.737004 27.542007)
		(size 0.4826)
		(drill 0.20574)
		(layers "F.Cu" "B.Cu")
		(net "VDD_CORE")
	)
	(via
		(at 56.736996 15.542006)
		(size 0.4826)
		(drill 0.20574)
		(layers "F.Cu" "B.Cu")
		(net "VDD_CORE")
	)
	(via
		(at 55.736998 10.541991)
		(size 0.4826)
		(drill 0.20574)
		(layers "F.Cu" "B.Cu")
		(net "VDD_CORE")
	)
	(via
		(at 53.737002 13.54201)
		(size 0.4826)
		(drill 0.20574)
		(layers "F.Cu" "B.Cu")
		(net "VDD_CORE")
	)
	(via
		(at 52.737004 25.542011)
		(size 0.4826)
		(drill 0.20574)
		(layers "F.Cu" "B.Cu")
		(net "VDD_CORE")
	)
	(via
		(at 55.736998 33.541995)
		(size 0.4826)
		(drill 0.20574)
		(layers "F.Cu" "B.Cu")
		(net "VDD_CORE")
	)
	(via
		(at 57.736994 16.542004)
		(size 0.4826)
		(drill 0.20574)
		(layers "F.Cu" "B.Cu")
		(net "VDD_CORE")
	)
	(via
		(at 58.674 40.7035)
		(size 1.016)
		(drill 0.508)
		(layers "F.Cu" "B.Cu")
		(net "VDD_CORE")
	)
	(via
		(at 55.736998 14.542008)
		(size 0.4826)
		(drill 0.20574)
		(layers "F.Cu" "B.Cu")
		(net "VDD_CORE")
	)
	(via
		(at 49.73701 34.541993)
		(size 0.4826)
		(drill 0.20574)
		(layers "F.Cu" "B.Cu")
		(net "VDD_CORE")
	)
	(via
		(at 47.736989 26.542009)
		(size 0.4826)
		(drill 0.20574)
		(layers "F.Cu" "B.Cu")
		(net "VDD_CORE")
	)
	(via
		(at 50.737008 21.541994)
		(size 0.4826)
		(drill 0.25654)
		(layers "F.Cu" "B.Cu")
		(net "VDD_CORE")
	)
	(via
		(at 48.737012 23.54199)
		(size 0.4826)
		(drill 0.20574)
		(layers "F.Cu" "B.Cu")
		(net "VDD_CORE")
	)
	(via
		(at 50.737008 10.541991)
		(size 0.4826)
		(drill 0.20574)
		(layers "F.Cu" "B.Cu")
		(net "VDD_CORE")
	)
	(via
		(at 56.736996 13.54201)
		(size 0.4826)
		(drill 0.20574)
		(layers "F.Cu" "B.Cu")
		(net "VDD_CORE")
	)
	(via
		(at 49.73701 11.541989)
		(size 0.4826)
		(drill 0.20574)
		(layers "F.Cu" "B.Cu")
		(net "VDD_CORE")
	)
	(via
		(at 58.736992 20.541996)
		(size 0.4826)
		(drill 0.20574)
		(layers "F.Cu" "B.Cu")
		(net "VDD_CORE")
	)
	(via
		(at 53.737002 34.541993)
		(size 0.4826)
		(drill 0.20574)
		(layers "F.Cu" "B.Cu")
		(net "VDD_CORE")
	)
	(via
		(at 58.736992 26.542009)
		(size 0.4826)
		(drill 0.20574)
		(layers "F.Cu" "B.Cu")
		(net "VDD_CORE")
	)
	(via
		(at 49.73701 28.542005)
		(size 0.4826)
		(drill 0.20574)
		(layers "F.Cu" "B.Cu")
		(net "VDD_CORE")
	)
	(via
		(at 51.737006 30.542001)
		(size 0.4826)
		(drill 0.20574)
		(layers "F.Cu" "B.Cu")
		(net "VDD_CORE")
	)
	(via
		(at 59.73699 33.541995)
		(size 0.4826)
		(drill 0.20574)
		(layers "F.Cu" "B.Cu")
		(net "VDD_CORE")
	)
	(via
		(at 60.736988 32.541997)
		(size 0.4826)
		(drill 0.20574)
		(layers "F.Cu" "B.Cu")
		(net "VDD_CORE")
	)
	(via
		(at 45.736993 34.541993)
		(size 0.4826)
		(drill 0.20574)
		(layers "F.Cu" "B.Cu")
		(net "VDD_CORE")
	)
	(via
		(at 57.736994 25.542011)
		(size 0.4826)
		(drill 0.20574)
		(layers "F.Cu" "B.Cu")
		(net "VDD_CORE")
	)
	(via
		(at 44.736995 23.54199)
		(size 0.4826)
		(drill 0.20574)
		(layers "F.Cu" "B.Cu")
		(net "VDD_CORE")
	)
	(via
		(at 50.737008 27.542007)
		(size 0.4826)
		(drill 0.20574)
		(layers "F.Cu" "B.Cu")
		(net "VDD_CORE")
	)
	(via
		(at 56.736996 11.541989)
		(size 0.4826)
		(drill 0.20574)
		(layers "F.Cu" "B.Cu")
		(net "VDD_CORE")
	)
	(via
		(at 45.736993 32.541997)
		(size 0.4826)
		(drill 0.20574)
		(layers "F.Cu" "B.Cu")
		(net "VDD_CORE")
	)
	(via
		(at 57.736994 19.541998)
		(size 0.4826)
		(drill 0.20574)
		(layers "F.Cu" "B.Cu")
		(net "VDD_CORE")
	)
	(via
		(at 45.736993 20.541996)
		(size 0.4826)
		(drill 0.20574)
		(layers "F.Cu" "B.Cu")
		(net "VDD_CORE")
	)
	(via
		(at 55.499 39.0525)
		(size 1.016)
		(drill 0.508)
		(layers "F.Cu" "B.Cu")
		(net "VDD_CORE")
	)
	(via
		(at 51.737006 9.541993)
		(size 0.4826)
		(drill 0.20574)
		(layers "F.Cu" "B.Cu")
		(net "VDD_CORE")
	)
	(via
		(at 48.737012 33.541995)
		(size 0.4826)
		(drill 0.20574)
		(layers "F.Cu" "B.Cu")
		(net "VDD_CORE")
	)
	(via
		(at 51.737006 34.541993)
		(size 0.4826)
		(drill 0.20574)
		(layers "F.Cu" "B.Cu")
		(net "VDD_CORE")
	)
	(via
		(at 51.737006 22.541992)
		(size 0.4826)
		(drill 0.20574)
		(layers "F.Cu" "B.Cu")
		(net "VDD_CORE")
	)
	(via
		(at 59.73699 29.542003)
		(size 0.4826)
		(drill 0.20574)
		(layers "F.Cu" "B.Cu")
		(net "VDD_CORE")
	)
	(via
		(at 51.737006 17.542002)
		(size 0.4826)
		(drill 0.20574)
		(layers "F.Cu" "B.Cu")
		(net "VDD_CORE")
	)
	(via
		(at 51.737006 32.541997)
		(size 0.4826)
		(drill 0.20574)
		(layers "F.Cu" "B.Cu")
		(net "VDD_CORE")
	)
	(via
		(at 58.736992 17.542002)
		(size 0.4826)
		(drill 0.20574)
		(layers "F.Cu" "B.Cu")
		(net "VDD_CORE")
	)
	(via
		(at 50.737008 14.542008)
		(size 0.4826)
		(drill 0.20574)
		(layers "F.Cu" "B.Cu")
		(net "VDD_CORE")
	)
	(via
		(at 49.73701 17.542002)
		(size 0.4826)
		(drill 0.20574)
		(layers "F.Cu" "B.Cu")
		(net "VDD_CORE")
	)
	(via
		(at 46.736991 10.541991)
		(size 0.4826)
		(drill 0.20574)
		(layers "F.Cu" "B.Cu")
		(net "VDD_CORE")
	)
	(via
		(at 48.737012 16.542004)
		(size 0.4826)
		(drill 0.20574)
		(layers "F.Cu" "B.Cu")
		(net "VDD_CORE")
	)
	(via
		(at 50.737008 29.542003)
		(size 0.4826)
		(drill 0.20574)
		(layers "F.Cu" "B.Cu")
		(net "VDD_CORE")
	)
	(via
		(at 56.736996 30.542001)
		(size 0.4826)
		(drill 0.20574)
		(layers "F.Cu" "B.Cu")
		(net "VDD_CORE")
	)
	(via
		(at 44.736995 33.541995)
		(size 0.4826)
		(drill 0.20574)
		(layers "F.Cu" "B.Cu")
		(net "VDD_CORE")
	)
	(via
		(at 56.736996 17.542002)
		(size 0.4826)
		(drill 0.20574)
		(layers "F.Cu" "B.Cu")
		(net "VDD_CORE")
	)
	(via
		(at 50.737008 25.542011)
		(size 0.4826)
		(drill 0.20574)
		(layers "F.Cu" "B.Cu")
		(net "VDD_CORE")
	)
	(via
		(at 57.736994 31.541999)
		(size 0.4826)
		(drill 0.20574)
		(layers "F.Cu" "B.Cu")
		(net "VDD_CORE")
	)
	(via
		(at 48.737012 27.542007)
		(size 0.4826)
		(drill 0.20574)
		(layers "F.Cu" "B.Cu")
		(net "VDD_CORE")
	)
	(via
		(at 49.73701 24.541988)
		(size 0.4826)
		(drill 0.20574)
		(layers "F.Cu" "B.Cu")
		(net "VDD_CORE")
	)
	(via
		(at 58.736992 13.54201)
		(size 0.4826)
		(drill 0.20574)
		(layers "F.Cu" "B.Cu")
		(net "VDD_CORE")
	)
	(via
		(at 48.737012 31.541999)
		(size 0.4826)
		(drill 0.20574)
		(layers "F.Cu" "B.Cu")
		(net "VDD_CORE")
	)
	(via
		(at 52.737004 23.54199)
		(size 0.4826)
		(drill 0.25654)
		(layers "F.Cu" "B.Cu")
		(net "VDD_CORE")
	)
	(via
		(at 45.736993 15.542006)
		(size 0.4826)
		(drill 0.20574)
		(layers "F.Cu" "B.Cu")
		(net "VDD_CORE")
	)
	(via
		(at 45.736993 28.542005)
		(size 0.4826)
		(drill 0.20574)
		(layers "F.Cu" "B.Cu")
		(net "VDD_CORE")
	)
	(via
		(at 57.15 39.0525)
		(size 1.016)
		(drill 0.508)
		(layers "F.Cu" "B.Cu")
		(net "VDD_CORE")
	)
	(via
		(at 44.736995 31.541999)
		(size 0.4826)
		(drill 0.20574)
		(layers "F.Cu" "B.Cu")
		(net "VDD_CORE")
	)
	(via
		(at 50.737008 23.54199)
		(size 0.4826)
		(drill 0.20574)
		(layers "F.Cu" "B.Cu")
		(net "VDD_CORE")
	)
	(via
		(at 46.736991 23.54199)
		(size 0.4826)
		(drill 0.20574)
		(layers "F.Cu" "B.Cu")
		(net "VDD_CORE")
	)
	(via
		(at 55.736998 19.541998)
		(size 0.4826)
		(drill 0.20574)
		(layers "F.Cu" "B.Cu")
		(net "VDD_CORE")
	)
	(via
		(at 47.736989 34.541993)
		(size 0.4826)
		(drill 0.20574)
		(layers "F.Cu" "B.Cu")
		(net "VDD_CORE")
	)
	(via
		(at 56.736996 32.541997)
		(size 0.4826)
		(drill 0.20574)
		(layers "F.Cu" "B.Cu")
		(net "VDD_CORE")
	)
	(via
		(at 58.736992 22.541992)
		(size 0.4826)
		(drill 0.20574)
		(layers "F.Cu" "B.Cu")
		(net "VDD_CORE")
	)
	(via
		(at 59.73699 10.541991)
		(size 0.4826)
		(drill 0.20574)
		(layers "F.Cu" "B.Cu")
		(net "VDD_CORE")
	)
	(via
		(at 53.737002 15.542006)
		(size 0.4826)
		(drill 0.20574)
		(layers "F.Cu" "B.Cu")
		(net "VDD_CORE")
	)
	(via
		(at 53.737002 9.541993)
		(size 0.4826)
		(drill 0.20574)
		(layers "F.Cu" "B.Cu")
		(net "VDD_CORE")
	)
	(via
		(at 48.737012 29.542003)
		(size 0.4826)
		(drill 0.20574)
		(layers "F.Cu" "B.Cu")
		(net "VDD_CORE")
	)
	(via
		(at 59.73699 31.541999)
		(size 0.4826)
		(drill 0.20574)
		(layers "F.Cu" "B.Cu")
		(net "VDD_CORE")
	)
	(via
		(at 59.73699 12.542012)
		(size 0.4826)
		(drill 0.20574)
		(layers "F.Cu" "B.Cu")
		(net "VDD_CORE")
	)
	(via
		(at 47.736989 32.541997)
		(size 0.4826)
		(drill 0.20574)
		(layers "F.Cu" "B.Cu")
		(net "VDD_CORE")
	)
	(via
		(at 52.737004 19.541998)
		(size 0.4826)
		(drill 0.20574)
		(layers "F.Cu" "B.Cu")
		(net "VDD_CORE")
	)
	(via
		(at 50.737008 19.541998)
		(size 0.4826)
		(drill 0.20574)
		(layers "F.Cu" "B.Cu")
		(net "VDD_CORE")
	)
	(via
		(at 47.736989 22.541992)
		(size 0.4826)
		(drill 0.20574)
		(layers "F.Cu" "B.Cu")
		(net "VDD_CORE")
	)
	(via
		(at 50.737008 33.541995)
		(size 0.4826)
		(drill 0.20574)
		(layers "F.Cu" "B.Cu")
		(net "VDD_CORE")
	)
	(via
		(at 59.73699 14.542008)
		(size 0.4826)
		(drill 0.20574)
		(layers "F.Cu" "B.Cu")
		(net "VDD_CORE")
	)
	(via
		(at 44.736995 19.541998)
		(size 0.4826)
		(drill 0.20574)
		(layers "F.Cu" "B.Cu")
		(net "VDD_CORE")
	)
	(via
		(at 48.737012 14.542008)
		(size 0.4826)
		(drill 0.20574)
		(layers "F.Cu" "B.Cu")
		(net "VDD_CORE")
	)
	(via
		(at 51.737006 28.542005)
		(size 0.4826)
		(drill 0.20574)
		(layers "F.Cu" "B.Cu")
		(net "VDD_CORE")
	)
	(via
		(at 46.736991 19.541998)
		(size 0.4826)
		(drill 0.20574)
		(layers "F.Cu" "B.Cu")
		(net "VDD_CORE")
	)
	(via
		(at 54.737 22.541992)
		(size 0.4826)
		(drill 0.20574)
		(layers "F.Cu" "B.Cu")
		(net "VDD_CORE")
	)
	(via
		(at 52.737004 33.541995)
		(size 0.4826)
		(drill 0.20574)
		(layers "F.Cu" "B.Cu")
		(net "VDD_CORE")
	)
	(via
		(at 49.73701 26.542009)
		(size 0.4826)
		(drill 0.20574)
		(layers "F.Cu" "B.Cu")
		(net "VDD_CORE")
	)
	(via
		(at 58.736992 30.542001)
		(size 0.4826)
		(drill 0.20574)
		(layers "F.Cu" "B.Cu")
		(net "VDD_CORE")
	)
	(via
		(at 42.291 40.386)
		(size 0.508)
		(drill 0.254)
		(layers "F.Cu" "B.Cu")
		(net "VDD_CORE")
	)
	(via
		(at 52.737004 21.541994)
		(size 0.4826)
		(drill 0.20574)
		(layers "F.Cu" "B.Cu")
		(net "VDD_CORE")
	)
	(via
		(at 43.736997 30.542001)
		(size 0.4826)
		(drill 0.20574)
		(layers "F.Cu" "B.Cu")
		(net "VDD_CORE")
	)
	(via
		(at 46.736991 31.541999)
		(size 0.4826)
		(drill 0.20574)
		(layers "F.Cu" "B.Cu")
		(net "VDD_CORE")
	)
	(via
		(at 49.73701 22.541992)
		(size 0.4826)
		(drill 0.25654)
		(layers "F.Cu" "B.Cu")
		(net "VDD_CORE")
	)
	(via
		(at 58.674 42.3545)
		(size 1.016)
		(drill 0.508)
		(layers "F.Cu" "B.Cu")
		(net "VDD_CORE")
	)
	(via
		(at 58.736992 11.541989)
		(size 0.4826)
		(drill 0.20574)
		(layers "F.Cu" "B.Cu")
		(net "VDD_CORE")
	)
	(via
		(at 51.737006 11.541989)
		(size 0.4826)
		(drill 0.20574)
		(layers "F.Cu" "B.Cu")
		(net "VDD_CORE")
	)
	(via
		(at 59.73699 21.541994)
		(size 0.4826)
		(drill 0.20574)
		(layers "F.Cu" "B.Cu")
		(net "VDD_CORE")
	)
	(via
		(at 45.736993 17.542002)
		(size 0.4826)
		(drill 0.20574)
		(layers "F.Cu" "B.Cu")
		(net "VDD_CORE")
	)
	(via
		(at 57.736994 29.542003)
		(size 0.4826)
		(drill 0.20574)
		(layers "F.Cu" "B.Cu")
		(net "VDD_CORE")
	)
	(via
		(at 48.737012 21.541994)
		(size 0.4826)
		(drill 0.20574)
		(layers "F.Cu" "B.Cu")
		(net "VDD_CORE")
	)
	(via
		(at 46.736991 12.542012)
		(size 0.4826)
		(drill 0.20574)
		(layers "F.Cu" "B.Cu")
		(net "VDD_CORE")
	)
	(via
		(at 46.736991 21.541994)
		(size 0.4826)
		(drill 0.20574)
		(layers "F.Cu" "B.Cu")
		(net "VDD_CORE")
	)
	(via
		(at 60.736988 22.541992)
		(size 0.4826)
		(drill 0.20574)
		(layers "F.Cu" "B.Cu")
		(net "VDD_CORE")
	)
	(via
		(at 52.737004 16.542004)
		(size 0.4826)
		(drill 0.20574)
		(layers "F.Cu" "B.Cu")
		(net "VDD_CORE")
	)
	(via
		(at 58.736992 34.541993)
		(size 0.4826)
		(drill 0.20574)
		(layers "F.Cu" "B.Cu")
		(net "VDD_CORE")
	)
	(via
		(at 56.736996 22.541992)
		(size 0.4826)
		(drill 0.20574)
		(layers "F.Cu" "B.Cu")
		(net "VDD_CORE")
	)
	(via
		(at 53.737002 26.542009)
		(size 0.4826)
		(drill 0.20574)
		(layers "F.Cu" "B.Cu")
		(net "VDD_CORE")
	)
	(via
		(at 59.73699 19.541998)
		(size 0.4826)
		(drill 0.20574)
		(layers "F.Cu" "B.Cu")
		(net "VDD_CORE")
	)
	(via
		(at 48.737012 12.542012)
		(size 0.4826)
		(drill 0.20574)
		(layers "F.Cu" "B.Cu")
		(net "VDD_CORE")
	)
	(via
		(at 57.736994 23.54199)
		(size 0.4826)
		(drill 0.20574)
		(layers "F.Cu" "B.Cu")
		(net "VDD_CORE")
	)
	(via
		(at 57.736994 21.541994)
		(size 0.4826)
		(drill 0.20574)
		(layers "F.Cu" "B.Cu")
		(net "VDD_CORE")
	)
	(via
		(at 60.736988 13.54201)
		(size 0.4826)
		(drill 0.20574)
		(layers "F.Cu" "B.Cu")
		(net "VDD_CORE")
	)
	(via
		(at 60.736988 17.542002)
		(size 0.4826)
		(drill 0.20574)
		(layers "F.Cu" "B.Cu")
		(net "VDD_CORE")
	)
	(via
		(at 46.736991 25.542011)
		(size 0.4826)
		(drill 0.20574)
		(layers "F.Cu" "B.Cu")
		(net "VDD_CORE")
	)
	(via
		(at 58.674 44.0055)
		(size 1.016)
		(drill 0.508)
		(layers "F.Cu" "B.Cu")
		(net "VDD_CORE")
	)
	(via
		(at 60.325 39.0525)
		(size 1.016)
		(drill 0.508)
		(layers "F.Cu" "B.Cu")
		(net "VDD_CORE")
	)
	(via
		(at 40.737003 24.541988)
		(size 0.4826)
		(drill 0.20574)
		(layers "F.Cu" "B.Cu")
		(net "VDD_CORE")
	)
	(via
		(at 44.736995 10.541991)
		(size 0.4826)
		(drill 0.20574)
		(layers "F.Cu" "B.Cu")
		(net "VDD_CORE")
	)
	(via
		(at 53.737002 30.542001)
		(size 0.4826)
		(drill 0.20574)
		(layers "F.Cu" "B.Cu")
		(net "VDD_CORE")
	)
	(via
		(at 47.736989 11.541989)
		(size 0.4826)
		(drill 0.20574)
		(layers "F.Cu" "B.Cu")
		(net "VDD_CORE")
	)
	(via
		(at 57.15 44.0055)
		(size 1.016)
		(drill 0.508)
		(layers "F.Cu" "B.Cu")
		(net "VDD_CORE")
	)
	(via
		(at 53.737002 17.542002)
		(size 0.4826)
		(drill 0.20574)
		(layers "F.Cu" "B.Cu")
		(net "VDD_CORE")
	)
	(via
		(at 55.736998 12.542012)
		(size 0.4826)
		(drill 0.20574)
		(layers "F.Cu" "B.Cu")
		(net "VDD_CORE")
	)
	(via
		(at 56.736996 28.542005)
		(size 0.4826)
		(drill 0.20574)
		(layers "F.Cu" "B.Cu")
		(net "VDD_CORE")
	)
	(via
		(at 47.736989 24.541988)
		(size 0.4826)
		(drill 0.25654)
		(layers "F.Cu" "B.Cu")
		(net "VDD_CORE")
	)
	(via
		(at 56.736996 34.541993)
		(size 0.4826)
		(drill 0.20574)
		(layers "F.Cu" "B.Cu")
		(net "VDD_CORE")
	)
	(via
		(at 59.73699 16.542004)
		(size 0.4826)
		(drill 0.20574)
		(layers "F.Cu" "B.Cu")
		(net "VDD_CORE")
	)
	(via
		(at 52.737004 12.542012)
		(size 0.4826)
		(drill 0.20574)
		(layers "F.Cu" "B.Cu")
		(net "VDD_CORE")
	)
	(via
		(at 52.737004 14.542008)
		(size 0.4826)
		(drill 0.20574)
		(layers "F.Cu" "B.Cu")
		(net "VDD_CORE")
	)
	(via
		(at 49.73701 20.541996)
		(size 0.4826)
		(drill 0.20574)
		(layers "F.Cu" "B.Cu")
		(net "VDD_CORE")
	)
	(via
		(at 58.736992 15.542006)
		(size 0.4826)
		(drill 0.20574)
		(layers "F.Cu" "B.Cu")
		(net "VDD_CORE")
	)
	(via
		(at 52.737004 31.541999)
		(size 0.4826)
		(drill 0.20574)
		(layers "F.Cu" "B.Cu")
		(net "VDD_CORE")
	)
	(via
		(at 56.736996 9.541993)
		(size 0.4826)
		(drill 0.20574)
		(layers "F.Cu" "B.Cu")
		(net "VDD_CORE")
	)
	(via
		(at 57.736994 33.541995)
		(size 0.4826)
		(drill 0.20574)
		(layers "F.Cu" "B.Cu")
		(net "VDD_CORE")
	)
	(via
		(at 56.007 41.1099)
		(size 0.508)
		(drill 0.25654)
		(layers "F.Cu" "B.Cu")
		(net "VDD_CORE")
	)
	(via
		(at 44.736995 29.542003)
		(size 0.4826)
		(drill 0.20574)
		(layers "F.Cu" "B.Cu")
		(net "VDD_CORE")
	)
	(via
		(at 52.737004 29.542003)
		(size 0.4826)
		(drill 0.20574)
		(layers "F.Cu" "B.Cu")
		(net "VDD_CORE")
	)
	(via
		(at 60.736988 26.542009)
		(size 0.4826)
		(drill 0.20574)
		(layers "F.Cu" "B.Cu")
		(net "VDD_CORE")
	)
	(via
		(at 49.73701 13.54201)
		(size 0.4826)
		(drill 0.20574)
		(layers "F.Cu" "B.Cu")
		(net "VDD_CORE")
	)
	(via
		(at 59.73699 23.54199)
		(size 0.4826)
		(drill 0.20574)
		(layers "F.Cu" "B.Cu")
		(net "VDD_CORE")
	)
	(via
		(at 44.736995 25.541986)
		(size 0.4826)
		(drill 0.20574)
		(layers "F.Cu" "B.Cu")
		(net "VDD_CORE")
	)
	(via
		(at 42.291 39.116)
		(size 0.508)
		(drill 0.254)
		(layers "F.Cu" "B.Cu")
		(net "VDD_CORE")
	)
	(via
		(at 50.737008 16.542004)
		(size 0.4826)
		(drill 0.20574)
		(layers "F.Cu" "B.Cu")
		(net "VDD_CORE")
	)
	(via
		(at 47.736989 28.542005)
		(size 0.4826)
		(drill 0.20574)
		(layers "F.Cu" "B.Cu")
		(net "VDD_CORE")
	)
	(via
		(at 44.736995 27.542007)
		(size 0.4826)
		(drill 0.20574)
		(layers "F.Cu" "B.Cu")
		(net "VDD_CORE")
	)
	(via
		(at 58.736992 28.542005)
		(size 0.4826)
		(drill 0.20574)
		(layers "F.Cu" "B.Cu")
		(net "VDD_CORE")
	)
	(via
		(at 45.736993 30.542001)
		(size 0.4826)
		(drill 0.20574)
		(layers "F.Cu" "B.Cu")
		(net "VDD_CORE")
	)
	(via
		(at 53.737002 32.541997)
		(size 0.4826)
		(drill 0.20574)
		(layers "F.Cu" "B.Cu")
		(net "VDD_CORE")
	)
	(via
		(at 60.736988 11.541989)
		(size 0.4826)
		(drill 0.20574)
		(layers "F.Cu" "B.Cu")
		(net "VDD_CORE")
	)
	(via
		(at 59.73699 25.542011)
		(size 0.4826)
		(drill 0.20574)
		(layers "F.Cu" "B.Cu")
		(net "VDD_CORE")
	)
	(via
		(at 45.736993 13.54201)
		(size 0.4826)
		(drill 0.20574)
		(layers "F.Cu" "B.Cu")
		(net "VDD_CORE")
	)
	(via
		(at 45.736993 24.541988)
		(size 0.4826)
		(drill 0.20574)
		(layers "F.Cu" "B.Cu")
		(net "VDD_CORE")
	)
	(via
		(at 56.736996 20.541996)
		(size 0.4826)
		(drill 0.20574)
		(layers "F.Cu" "B.Cu")
		(net "VDD_CORE")
	)
	(via
		(at 61.976 39.0525)
		(size 1.016)
		(drill 0.508)
		(layers "F.Cu" "B.Cu")
		(net "VDD_CORE")
	)
	(via
		(at 55.499 44.0055)
		(size 1.016)
		(drill 0.508)
		(layers "F.Cu" "B.Cu")
		(net "VDD_CORE")
	)
	(via
		(at 55.736998 16.542004)
		(size 0.4826)
		(drill 0.20574)
		(layers "F.Cu" "B.Cu")
		(net "VDD_CORE")
	)
	(via
		(at 55.736998 21.541994)
		(size 0.4826)
		(drill 0.20574)
		(layers "F.Cu" "B.Cu")
		(net "VDD_CORE")
	)
	(via
		(at 55.736998 27.542007)
		(size 0.4826)
		(drill 0.20574)
		(layers "F.Cu" "B.Cu")
		(net "VDD_CORE")
	)
	(via
		(at 56.736996 26.542009)
		(size 0.4826)
		(drill 0.20574)
		(layers "F.Cu" "B.Cu")
		(net "VDD_CORE")
	)
	(via
		(at 60.736988 15.542006)
		(size 0.4826)
		(drill 0.20574)
		(layers "F.Cu" "B.Cu")
		(net "VDD_CORE")
	)
	(via
		(at 46.736991 33.541995)
		(size 0.4826)
		(drill 0.20574)
		(layers "F.Cu" "B.Cu")
		(net "VDD_CORE")
	)
	(via
		(at 45.736993 26.542009)
		(size 0.4826)
		(drill 0.20574)
		(layers "F.Cu" "B.Cu")
		(net "VDD_CORE")
	)
	(via
		(at 47.736989 17.542002)
		(size 0.4826)
		(drill 0.20574)
		(layers "F.Cu" "B.Cu")
		(net "VDD_CORE")
	)
	(via
		(at 49.73701 32.541997)
		(size 0.4826)
		(drill 0.20574)
		(layers "F.Cu" "B.Cu")
		(net "VDD_CORE")
	)
	(via
		(at 49.73701 30.542001)
		(size 0.4826)
		(drill 0.20574)
		(layers "F.Cu" "B.Cu")
		(net "VDD_CORE")
	)
	(via
		(at 56.736996 24.541988)
		(size 0.4826)
		(drill 0.20574)
		(layers "F.Cu" "B.Cu")
		(net "VDD_CORE")
	)
	(via
		(at 48.737012 10.541991)
		(size 0.4826)
		(drill 0.20574)
		(layers "F.Cu" "B.Cu")
		(net "VDD_CORE")
	)
	(via
		(at 51.737006 15.542006)
		(size 0.4826)
		(drill 0.20574)
		(layers "F.Cu" "B.Cu")
		(net "VDD_CORE")
	)
	(via
		(at 41.737001 24.541988)
		(size 0.4826)
		(drill 0.20574)
		(layers "F.Cu" "B.Cu")
		(net "VDD_CORE")
	)
	(via
		(at 60.736988 24.541988)
		(size 0.4826)
		(drill 0.20574)
		(layers "F.Cu" "B.Cu")
		(net "VDD_CORE")
	)
	(segment
		(start 49.73701 30.542001)
		(end 50.236857 31.041848)
		(width 0.254)
		(layer "B.Cu")
		(net "VDD_CORE")
	)
	(segment
		(start 44.736995 33.541995)
		(end 45.237019 33.041971)
		(width 0.254)
		(layer "B.Cu")
		(net "VDD_CORE")
	)
	(segment
		(start 58.736992 28.542005)
		(end 58.237145 29.041852)
		(width 0.254)
		(layer "B.Cu")
		(net "VDD_CORE")
	)
	(segment
		(start 54.737 25.7429)
		(end 54.297656 26.233044)
		(width 0.254)
		(layer "B.Cu")
		(net "VDD_CORE")
	)
	(segment
		(start 53.737002 32.541997)
		(end 54.297097 32.541997)
		(width 0.254)
		(layer "B.Cu")
		(net "VDD_CORE")
	)
	(segment
		(start 50.236857 31.041848)
		(end 50.237009 31.041848)
		(width 0.254)
		(layer "B.Cu")
		(net "VDD_CORE")
	)
	(segment
		(start 59.236991 31.042)
		(end 59.236991 31.041848)
		(width 0.254)
		(layer "B.Cu")
		(net "VDD_CORE")
	)
	(segment
		(start 59.73699 31.541999)
		(end 59.236991 31.042)
		(width 0.254)
		(layer "B.Cu")
		(net "VDD_CORE")
	)
	(segment
		(start 60.736988 26.542009)
		(end 60.237141 27.041856)
		(width 0.254)
		(layer "B.Cu")
		(net "VDD_CORE")
	)
	(segment
		(start 54.238398 9.040597)
		(end 54.737 9.040597)
		(width 0.508)
		(layer "B.Cu")
		(net "VDD_CORE")
	)
	(segment
		(start 54.987698 9.040597)
		(end 54.737 9.040597)
		(width 0.508)
		(layer "B.Cu")
		(net "VDD_CORE")
	)
	(segment
		(start 61.849 39.1795)
		(end 61.976 39.0525)
		(width 0.508)
		(layer "B.Cu")
		(net "VDD_CORE")
	)
	(segment
		(start 55.88 45.593)
		(end 55.88 44.3865)
		(width 0.508)
		(layer "B.Cu")
		(net "VDD_CORE")
	)
	(segment
		(start 55.118 9.922993)
		(end 55.118 9.803105)
		(width 0.508)
		(layer "B.Cu")
		(net "VDD_CORE")
	)
	(segment
		(start 53.737002 13.54201)
		(end 54.236976 13.042036)
		(width 0.508)
		(layer "B.Cu")
		(net "VDD_CORE")
	)
	(segment
		(start 46.355 18.542)
		(end 45.736993 17.962093)
		(width 0.254)
		(layer "B.Cu")
		(net "VDD_CORE")
	)
	(segment
		(start 56.736996 13.54201)
		(end 57.236995 13.042011)
		(width 0.254)
		(layer "B.Cu")
		(net "VDD_CORE")
	)
	(segment
		(start 45.236892 11.041888)
		(end 45.236892 11.042015)
		(width 0.254)
		(layer "B.Cu")
		(net "VDD_CORE")
	)
	(segment
		(start 52.236853 33.041844)
		(end 52.237005 33.041844)
		(width 0.254)
		(layer "B.Cu")
		(net "VDD_CORE")
	)
	(segment
		(start 56.007 39.5605)
		(end 55.499 39.0525)
		(width 0.508)
		(layer "B.Cu")
		(net "VDD_CORE")
	)
	(segment
		(start 53.737002 9.541993)
		(end 54.238398 9.040597)
		(width 0.508)
		(layer "B.Cu")
		(net "VDD_CORE")
	)
	(segment
		(start 51.737006 32.541997)
		(end 52.236853 33.041844)
		(width 0.254)
		(layer "B.Cu")
		(net "VDD_CORE")
	)
	(segment
		(start 45.736993 17.962093)
		(end 45.736993 17.542002)
		(width 0.254)
		(layer "B.Cu")
		(net "VDD_CORE")
	)
	(segment
		(start 59.0804 41.1099)
		(end 58.674 40.7035)
		(width 0.508)
		(layer "B.Cu")
		(net "VDD_CORE")
	)
	(segment
		(start 55.452874 12.826136)
		(end 55.736998 12.542012)
		(width 0.508)
		(layer "B.Cu")
		(net "VDD_CORE")
	)
	(segment
		(start 60.236964 12.042013)
		(end 60.236862 12.042013)
		(width 0.254)
		(layer "B.Cu")
		(net "VDD_CORE")
	)
	(segment
		(start 50.737008 12.542012)
		(end 51.237007 12.042013)
		(width 0.254)
		(layer "B.Cu")
		(net "VDD_CORE")
	)
	(segment
		(start 49.237011 12.041886)
		(end 49.237113 12.041886)
		(width 0.254)
		(layer "B.Cu")
		(net "VDD_CORE")
	)
	(segment
		(start 48.737012 19.042888)
		(end 48.737012 19.541998)
		(width 0.254)
		(layer "B.Cu")
		(net "VDD_CORE")
	)
	(segment
		(start 55.114698 9.799803)
		(end 55.114698 9.167597)
		(width 0.508)
		(layer "B.Cu")
		(net "VDD_CORE")
	)
	(segment
		(start 49.237113 12.041886)
		(end 49.73701 11.541989)
		(width 0.254)
		(layer "B.Cu")
		(net "VDD_CORE")
	)
	(segment
		(start 54.902964 13.042036)
		(end 55.118864 12.826136)
		(width 0.508)
		(layer "B.Cu")
		(net "VDD_CORE")
	)
	(segment
		(start 54.230499 30.542001)
		(end 54.737 30.0355)
		(width 0.254)
		(layer "B.Cu")
		(net "VDD_CORE")
	)
	(segment
		(start 58.237145 29.041852)
		(end 58.236993 29.041852)
		(width 0.254)
		(layer "B.Cu")
		(net "VDD_CORE")
	)
	(segment
		(start 54.236976 13.042036)
		(end 54.737 13.042036)
		(width 0.508)
		(layer "B.Cu")
		(net "VDD_CORE")
	)
	(segment
		(start 51.737006 26.542009)
		(end 51.237007 26.04201)
		(width 0.254)
		(layer "B.Cu")
		(net "VDD_CORE")
	)
	(segment
		(start 56.237149 27.041856)
		(end 56.236997 27.041856)
		(width 0.254)
		(layer "B.Cu")
		(net "VDD_CORE")
	)
	(segment
		(start 54.737 28.6893)
		(end 53.884297 28.6893)
		(width 0.254)
		(layer "B.Cu")
		(net "VDD_CORE")
	)
	(segment
		(start 44.736995 29.542003)
		(end 45.237019 29.041979)
		(width 0.254)
		(layer "B.Cu")
		(net "VDD_CORE")
	)
	(segment
		(start 55.88 44.3865)
		(end 55.499 44.0055)
		(width 0.508)
		(layer "B.Cu")
		(net "VDD_CORE")
	)
	(segment
		(start 45.237019 29.041979)
		(end 45.237019 29.041852)
		(width 0.254)
		(layer "B.Cu")
		(net "VDD_CORE")
	)
	(segment
		(start 58.736992 11.541989)
		(end 59.236991 11.04199)
		(width 0.254)
		(layer "B.Cu")
		(net "VDD_CORE")
	)
	(segment
		(start 57.277 41.1099)
		(end 57.277 39.1795)
		(width 0.508)
		(layer "B.Cu")
		(net "VDD_CORE")
	)
	(segment
		(start 60.736988 32.541997)
		(end 61.236835 33.041844)
		(width 0.254)
		(layer "B.Cu")
		(net "VDD_CORE")
	)
	(segment
		(start 47.736989 28.542005)
		(end 48.236835 29.041852)
		(width 0.254)
		(layer "B.Cu")
		(net "VDD_CORE")
	)
	(segment
		(start 49.73701 26.542009)
		(end 49.237113 26.042112)
		(width 0.254)
		(layer "B.Cu")
		(net "VDD_CORE")
	)
	(segment
		(start 54.737 13.042036)
		(end 54.902964 13.042036)
		(width 0.508)
		(layer "B.Cu")
		(net "VDD_CORE")
	)
	(segment
		(start 48.237013 31.042)
		(end 48.737012 31.541999)
		(width 0.254)
		(layer "B.Cu")
		(net "VDD_CORE")
	)
	(segment
		(start 51.237007 26.04201)
		(end 51.237007 26.041858)
		(width 0.254)
		(layer "B.Cu")
		(net "VDD_CORE")
	)
	(segment
		(start 44.736995 10.541991)
		(end 45.236892 11.041888)
		(width 0.254)
		(layer "B.Cu")
		(net "VDD_CORE")
	)
	(segment
		(start 56.736996 34.541993)
		(end 57.080023 34.88502)
		(width 0.254)
		(layer "B.Cu")
		(net "VDD_CORE")
	)
	(segment
		(start 58.736992 34.541993)
		(end 58.736992 35.305492)
		(width 0.254)
		(layer "B.Cu")
		(net "VDD_CORE")
	)
	(segment
		(start 51.237007 12.042013)
		(end 51.237007 12.041886)
		(width 0.254)
		(layer "B.Cu")
		(net "VDD_CORE")
	)
	(segment
		(start 60.579 41.1099)
		(end 59.0804 41.1099)
		(width 0.508)
		(layer "B.Cu")
		(net "VDD_CORE")
	)
	(segment
		(start 53.737002 13.54201)
		(end 54.237001 14.042009)
		(width 0.254)
		(layer "B.Cu")
		(net "VDD_CORE")
	)
	(segment
		(start 60.236989 14.042009)
		(end 60.236862 14.042009)
		(width 0.254)
		(layer "B.Cu")
		(net "VDD_CORE")
	)
	(segment
		(start 48.237013 31.041975)
		(end 48.237013 31.042)
		(width 0.254)
		(layer "B.Cu")
		(net "VDD_CORE")
	)
	(segment
		(start 60.736988 11.541989)
		(end 60.236964 12.042013)
		(width 0.254)
		(layer "B.Cu")
		(net "VDD_CORE")
	)
	(segment
		(start 51.237007 29.042004)
		(end 51.237007 29.041852)
		(width 0.254)
		(layer "B.Cu")
		(net "VDD_CORE")
	)
	(segment
		(start 57.237122 11.041863)
		(end 57.736994 10.541991)
		(width 0.254)
		(layer "B.Cu")
		(net "VDD_CORE")
	)
	(segment
		(start 49.3014 18.542)
		(end 48.737012 19.042888)
		(width 0.254)
		(layer "B.Cu")
		(net "VDD_CORE")
	)
	(segment
		(start 57.080023 34.994723)
		(end 57.6453 35.56)
		(width 0.254)
		(layer "B.Cu")
		(net "VDD_CORE")
	)
	(segment
		(start 53.884297 28.6893)
		(end 53.737002 28.542005)
		(width 0.254)
		(layer "B.Cu")
		(net "VDD_CORE")
	)
	(segment
		(start 57.2516 37.465)
		(end 57.2516 38.9509)
		(width 0.508)
		(layer "B.Cu")
		(net "VDD_CORE")
	)
	(segment
		(start 54.237001 14.447901)
		(end 54.737 14.9479)
		(width 0.254)
		(layer "B.Cu")
		(net "VDD_CORE")
	)
	(segment
		(start 55.114698 9.167597)
		(end 54.987698 9.040597)
		(width 0.508)
		(layer "B.Cu")
		(net "VDD_CORE")
	)
	(segment
		(start 57.236995 31.042)
		(end 57.236995 31.041848)
		(width 0.254)
		(layer "B.Cu")
		(net "VDD_CORE")
	)
	(segment
		(start 58.736992 35.305492)
		(end 58.9915 35.56)
		(width 0.254)
		(layer "B.Cu")
		(net "VDD_CORE")
	)
	(segment
		(start 60.736988 13.54201)
		(end 60.236989 14.042009)
		(width 0.254)
		(layer "B.Cu")
		(net "VDD_CORE")
	)
	(segment
		(start 57.736994 31.541999)
		(end 57.236995 31.042)
		(width 0.254)
		(layer "B.Cu")
		(net "VDD_CORE")
	)
	(segment
		(start 55.736998 10.541991)
		(end 55.118 9.922993)
		(width 0.508)
		(layer "B.Cu")
		(net "VDD_CORE")
	)
	(segment
		(start 52.237005 13.042011)
		(end 52.237005 13.041884)
		(width 0.254)
		(layer "B.Cu")
		(net "VDD_CORE")
	)
	(segment
		(start 55.118 9.803105)
		(end 55.114698 9.799803)
		(width 0.508)
		(layer "B.Cu")
		(net "VDD_CORE")
	)
	(segment
		(start 55.118864 12.826136)
		(end 55.452874 12.826136)
		(width 0.508)
		(layer "B.Cu")
		(net "VDD_CORE")
	)
	(segment
		(start 53.737002 30.542001)
		(end 54.230499 30.542001)
		(width 0.254)
		(layer "B.Cu")
		(net "VDD_CORE")
	)
	(segment
		(start 57.277 39.1795)
		(end 57.15 39.0525)
		(width 0.508)
		(layer "B.Cu")
		(net "VDD_CORE")
	)
	(segment
		(start 61.849 41.1099)
		(end 61.849 39.1795)
		(width 0.508)
		(layer "B.Cu")
		(net "VDD_CORE")
	)
	(segment
		(start 56.736996 26.542009)
		(end 56.237149 27.041856)
		(width 0.254)
		(layer "B.Cu")
		(net "VDD_CORE")
	)
	(segment
		(start 57.237122 11.042015)
		(end 57.237122 11.041863)
		(width 0.254)
		(layer "B.Cu")
		(net "VDD_CORE")
	)
	(segment
		(start 58.736992 26.542009)
		(end 58.236993 26.04201)
		(width 0.254)
		(layer "B.Cu")
		(net "VDD_CORE")
	)
	(segment
		(start 54.045968 26.233044)
		(end 53.737002 26.542009)
		(width 0.254)
		(layer "B.Cu")
		(net "VDD_CORE")
	)
	(segment
		(start 48.236835 29.041852)
		(end 48.237013 29.041852)
		(width 0.254)
		(layer "B.Cu")
		(net "VDD_CORE")
	)
	(segment
		(start 49.237113 26.042112)
		(end 49.237011 26.042112)
		(width 0.254)
		(layer "B.Cu")
		(net "VDD_CORE")
	)
	(segment
		(start 57.236995 13.042011)
		(end 57.236995 13.041884)
		(width 0.254)
		(layer "B.Cu")
		(net "VDD_CORE")
	)
	(segment
		(start 57.080023 34.88502)
		(end 57.080023 34.994723)
		(width 0.254)
		(layer "B.Cu")
		(net "VDD_CORE")
	)
	(segment
		(start 54.297097 32.541997)
		(end 54.737 32.9819)
		(width 0.254)
		(layer "B.Cu")
		(net "VDD_CORE")
	)
	(segment
		(start 60.237141 27.041856)
		(end 60.236989 27.041856)
		(width 0.254)
		(layer "B.Cu")
		(net "VDD_CORE")
	)
	(segment
		(start 59.236991 11.04199)
		(end 59.236991 11.041888)
		(width 0.254)
		(layer "B.Cu")
		(net "VDD_CORE")
	)
	(segment
		(start 58.236993 26.04201)
		(end 58.236993 26.041858)
		(width 0.254)
		(layer "B.Cu")
		(net "VDD_CORE")
	)
	(segment
		(start 54.237001 14.042009)
		(end 54.237001 14.447901)
		(width 0.254)
		(layer "B.Cu")
		(net "VDD_CORE")
	)
	(segment
		(start 50.737008 29.542003)
		(end 51.237007 29.042004)
		(width 0.254)
		(layer "B.Cu")
		(net "VDD_CORE")
	)
	(segment
		(start 54.297656 26.233044)
		(end 54.045968 26.233044)
		(width 0.254)
		(layer "B.Cu")
		(net "VDD_CORE")
	)
	(segment
		(start 51.737006 13.54201)
		(end 52.237005 13.042011)
		(width 0.254)
		(layer "B.Cu")
		(net "VDD_CORE")
	)
	(segment
		(start 57.2516 38.9509)
		(end 57.15 39.0525)
		(width 0.508)
		(layer "B.Cu")
		(net "VDD_CORE")
	)
	(segment
		(start 56.007 41.1099)
		(end 56.007 39.5605)
		(width 0.508)
		(layer "B.Cu")
		(net "VDD_CORE")
	)
	(segment
		(start 45.237019 33.041971)
		(end 45.237019 33.041844)
		(width 0.254)
		(layer "B.Cu")
		(net "VDD_CORE")
	)
	(segment
		(start 61.236835 33.041844)
		(end 61.236987 33.041844)
		(width 0.254)
		(layer "B.Cu")
		(net "VDD_CORE")
	)
	(segment
		(start 9.971634 -0.20066)
		(end 9.97966 -0.20066)
		(width 0.14732)
		(layer "F.Cu")
		(net "PCIE0_WAKE_L")
	)
	(segment
		(start 9.97966 -0.20066)
		(end 10.033 -0.254)
		(width 0.14732)
		(layer "F.Cu")
		(net "PCIE0_WAKE_L")
	)
	(segment
		(start 10.16 1.8161)
		(end 11.303 1.8161)
		(width 0.14732)
		(layer "F.Cu")
		(net "PCIE0_WAKE_L")
	)
	(segment
		(start 9.70534 1.36144)
		(end 9.70534 0.065634)
		(width 0.14732)
		(layer "F.Cu")
		(net "PCIE0_WAKE_L")
	)
	(segment
		(start 10.16 1.8161)
		(end 9.70534 1.36144)
		(width 0.14732)
		(layer "F.Cu")
		(net "PCIE0_WAKE_L")
	)
	(segment
		(start 12.033275 2.317775)
		(end 12.8524 3.1369)
		(width 0.14732)
		(layer "F.Cu")
		(net "PCIE0_WAKE_L")
	)
	(segment
		(start 11.303 1.8161)
		(end 11.804675 2.317775)
		(width 0.14732)
		(layer "F.Cu")
		(net "PCIE0_WAKE_L")
	)
	(segment
		(start 9.70534 0.065634)
		(end 9.971634 -0.20066)
		(width 0.14732)
		(layer "F.Cu")
		(net "PCIE0_WAKE_L")
	)
	(segment
		(start 11.804675 2.317775)
		(end 12.033275 2.317775)
		(width 0.14732)
		(layer "F.Cu")
		(net "PCIE0_WAKE_L")
	)
	(segment
		(start 10.033 -0.254)
		(end 12.065 -0.254)
		(width 0.14732)
		(layer "F.Cu")
		(net "PCIE0_WAKE_L")
	)
	(via
		(at 12.065 -0.254)
		(size 0.762)
		(drill 0.381)
		(layers "F.Cu" "B.Cu")
		(net "PCIE0_WAKE_L")
	)
	(via
		(at 12.8524 3.1369)
		(size 0.508)
		(drill 0.254)
		(layers "F.Cu" "B.Cu")
		(net "PCIE0_WAKE_L")
	)
	(segment
		(start 13.4874 3.7719)
		(end 12.8524 3.1369)
		(width 0.254)
		(layer "B.Cu")
		(net "PCIE0_WAKE_L")
	)
	(segment
		(start 19.177 26.035)
		(end 18.9611 26.2509)
		(width 0.14732)
		(layer "F.Cu")
		(net "NFP_FAIL_SAFE_BOOT_L")
	)
	(segment
		(start 18.9611 26.2509)
		(end 17.907 26.2509)
		(width 0.14732)
		(layer "F.Cu")
		(net "NFP_FAIL_SAFE_BOOT_L")
	)
	(segment
		(start 30.2895 23.473766)
		(end 30.24599 23.430255)
		(width 0.127)
		(layer "F.Cu")
		(net "NFP_FAIL_SAFE_BOOT_L")
	)
	(segment
		(start 30.24599 23.430255)
		(end 30.24599 23.048392)
		(width 0.127)
		(layer "F.Cu")
		(net "NFP_FAIL_SAFE_BOOT_L")
	)
	(segment
		(start 41.237002 13.042011)
		(end 40.737003 12.542012)
		(width 0.13208)
		(layer "F.Cu")
		(net "NFP_FAIL_SAFE_BOOT_L")
	)
	(segment
		(start 30.2895 24.0411)
		(end 30.2895 23.473766)
		(width 0.127)
		(layer "F.Cu")
		(net "NFP_FAIL_SAFE_BOOT_L")
	)
	(segment
		(start 30.7086 24.4602)
		(end 30.2895 24.0411)
		(width 0.127)
		(layer "F.Cu")
		(net "NFP_FAIL_SAFE_BOOT_L")
	)
	(via
		(at 19.177 26.035)
		(size 0.508)
		(drill 0.254)
		(layers "F.Cu" "B.Cu")
		(net "NFP_FAIL_SAFE_BOOT_L")
	)
	(via
		(at 30.7086 24.4602)
		(size 0.4572)
		(drill 0.20574)
		(layers "F.Cu" "B.Cu")
		(net "NFP_FAIL_SAFE_BOOT_L")
	)
	(via
		(at 40.737003 12.542012)
		(size 0.4826)
		(drill 0.20574)
		(layers "F.Cu" "B.Cu")
		(net "NFP_FAIL_SAFE_BOOT_L")
	)
	(via
		(at 17.78 48.7045)
		(size 0.508)
		(drill 0.25654)
		(layers "F.Cu" "B.Cu")
		(net "NFP_FAIL_SAFE_BOOT_L")
	)
	(segment
		(start 40.737003 12.542012)
		(end 41.2369 12.042115)
		(width 0.14732)
		(layer "B.Cu")
		(net "NFP_FAIL_SAFE_BOOT_L")
	)
	(segment
		(start 29.3624 24.8666)
		(end 28.448 25.781)
		(width 0.1016)
		(layer "B.Cu")
		(net "NFP_FAIL_SAFE_BOOT_L")
	)
	(segment
		(start 41.2369 12.042115)
		(end 41.2369 12.042013)
		(width 0.14732)
		(layer "B.Cu")
		(net "NFP_FAIL_SAFE_BOOT_L")
	)
	(segment
		(start 30.7086 24.4602)
		(end 30.3022 24.8666)
		(width 0.1016)
		(layer "B.Cu")
		(net "NFP_FAIL_SAFE_BOOT_L")
	)
	(segment
		(start 30.3022 24.8666)
		(end 29.3624 24.8666)
		(width 0.1016)
		(layer "B.Cu")
		(net "NFP_FAIL_SAFE_BOOT_L")
	)
	(segment
		(start 31.912941 23.784941)
		(end 31.912941 23.485196)
		(width 0.12065)
		(layer "In6.Cu")
		(net "NFP_FAIL_SAFE_BOOT_L")
	)
	(segment
		(start 30.058004 24.851741)
		(end 30.449545 24.4602)
		(width 0.12065)
		(layer "In6.Cu")
		(net "NFP_FAIL_SAFE_BOOT_L")
	)
	(segment
		(start 32.725741 24.622404)
		(end 32.725741 24.297996)
		(width 0.12065)
		(layer "In6.Cu")
		(net "NFP_FAIL_SAFE_BOOT_L")
	)
	(segment
		(start 32.196659 24.068659)
		(end 31.912941 23.784941)
		(width 0.12065)
		(layer "In6.Cu")
		(net "NFP_FAIL_SAFE_BOOT_L")
	)
	(segment
		(start 29.661714 24.779859)
		(end 29.733596 24.851741)
		(width 0.12065)
		(layer "In6.Cu")
		(net "NFP_FAIL_SAFE_BOOT_L")
	)
	(segment
		(start 32.496404 24.068659)
		(end 32.196659 24.068659)
		(width 0.12065)
		(layer "In6.Cu")
		(net "NFP_FAIL_SAFE_BOOT_L")
	)
	(segment
		(start 21.650325 21.844)
		(end 21.529675 21.72335)
		(width 0.12065)
		(layer "In6.Cu")
		(net "NFP_FAIL_SAFE_BOOT_L")
	)
	(segment
		(start 28.067 16.002)
		(end 28.067 15.113)
		(width 0.12065)
		(layer "In6.Cu")
		(net "NFP_FAIL_SAFE_BOOT_L")
	)
	(segment
		(start 30.7086 24.4602)
		(end 31.313145 24.4602)
		(width 0.12065)
		(layer "In6.Cu")
		(net "NFP_FAIL_SAFE_BOOT_L")
	)
	(segment
		(start 31.912941 23.485196)
		(end 31.668745 23.241)
		(width 0.12065)
		(layer "In6.Cu")
		(net "NFP_FAIL_SAFE_BOOT_L")
	)
	(segment
		(start 19.177 26.035)
		(end 19.304 26.162)
		(width 0.12065)
		(layer "In6.Cu")
		(net "NFP_FAIL_SAFE_BOOT_L")
	)
	(segment
		(start 23.494975 22.987)
		(end 22.351975 21.844)
		(width 0.12065)
		(layer "In6.Cu")
		(net "NFP_FAIL_SAFE_BOOT_L")
	)
	(segment
		(start 21.912961 20.769885)
		(end 23.299115 20.769885)
		(width 0.12065)
		(layer "In6.Cu")
		(net "NFP_FAIL_SAFE_BOOT_L")
	)
	(segment
		(start 19.304 26.162)
		(end 24.257 26.162)
		(width 0.12065)
		(layer "In6.Cu")
		(net "NFP_FAIL_SAFE_BOOT_L")
	)
	(segment
		(start 25.639141 24.779859)
		(end 29.661714 24.779859)
		(width 0.12065)
		(layer "In6.Cu")
		(net "NFP_FAIL_SAFE_BOOT_L")
	)
	(segment
		(start 31.668745 23.241)
		(end 27.223745 23.241)
		(width 0.12065)
		(layer "In6.Cu")
		(net "NFP_FAIL_SAFE_BOOT_L")
	)
	(segment
		(start 21.529675 21.153171)
		(end 21.912961 20.769885)
		(width 0.12065)
		(layer "In6.Cu")
		(net "NFP_FAIL_SAFE_BOOT_L")
	)
	(segment
		(start 28.067 15.113)
		(end 31.496 11.684)
		(width 0.12065)
		(layer "In6.Cu")
		(net "NFP_FAIL_SAFE_BOOT_L")
	)
	(segment
		(start 27.086204 23.103459)
		(end 24.108613 23.103459)
		(width 0.12065)
		(layer "In6.Cu")
		(net "NFP_FAIL_SAFE_BOOT_L")
	)
	(segment
		(start 31.496 11.684)
		(end 34.417 11.684)
		(width 0.12065)
		(layer "In6.Cu")
		(net "NFP_FAIL_SAFE_BOOT_L")
	)
	(segment
		(start 23.992154 22.987)
		(end 23.494975 22.987)
		(width 0.12065)
		(layer "In6.Cu")
		(net "NFP_FAIL_SAFE_BOOT_L")
	)
	(segment
		(start 34.798 12.065)
		(end 40.259991 12.065)
		(width 0.12065)
		(layer "In6.Cu")
		(net "NFP_FAIL_SAFE_BOOT_L")
	)
	(segment
		(start 31.734404 24.881459)
		(end 32.466686 24.881459)
		(width 0.12065)
		(layer "In6.Cu")
		(net "NFP_FAIL_SAFE_BOOT_L")
	)
	(segment
		(start 34.417 11.684)
		(end 34.798 12.065)
		(width 0.12065)
		(layer "In6.Cu")
		(net "NFP_FAIL_SAFE_BOOT_L")
	)
	(segment
		(start 22.351975 21.844)
		(end 21.650325 21.844)
		(width 0.12065)
		(layer "In6.Cu")
		(net "NFP_FAIL_SAFE_BOOT_L")
	)
	(segment
		(start 40.259991 12.065)
		(end 40.737003 12.542012)
		(width 0.12065)
		(layer "In6.Cu")
		(net "NFP_FAIL_SAFE_BOOT_L")
	)
	(segment
		(start 27.223745 23.241)
		(end 27.086204 23.103459)
		(width 0.12065)
		(layer "In6.Cu")
		(net "NFP_FAIL_SAFE_BOOT_L")
	)
	(segment
		(start 23.299115 20.769885)
		(end 28.067 16.002)
		(width 0.12065)
		(layer "In6.Cu")
		(net "NFP_FAIL_SAFE_BOOT_L")
	)
	(segment
		(start 24.108613 23.103459)
		(end 23.992154 22.987)
		(width 0.12065)
		(layer "In6.Cu")
		(net "NFP_FAIL_SAFE_BOOT_L")
	)
	(segment
		(start 32.725741 24.297996)
		(end 32.496404 24.068659)
		(width 0.12065)
		(layer "In6.Cu")
		(net "NFP_FAIL_SAFE_BOOT_L")
	)
	(segment
		(start 21.529675 21.72335)
		(end 21.529675 21.153171)
		(width 0.12065)
		(layer "In6.Cu")
		(net "NFP_FAIL_SAFE_BOOT_L")
	)
	(segment
		(start 32.466686 24.881459)
		(end 32.725741 24.622404)
		(width 0.12065)
		(layer "In6.Cu")
		(net "NFP_FAIL_SAFE_BOOT_L")
	)
	(segment
		(start 31.313145 24.4602)
		(end 31.734404 24.881459)
		(width 0.12065)
		(layer "In6.Cu")
		(net "NFP_FAIL_SAFE_BOOT_L")
	)
	(segment
		(start 30.449545 24.4602)
		(end 30.7086 24.4602)
		(width 0.12065)
		(layer "In6.Cu")
		(net "NFP_FAIL_SAFE_BOOT_L")
	)
	(segment
		(start 24.257 26.162)
		(end 25.639141 24.779859)
		(width 0.12065)
		(layer "In6.Cu")
		(net "NFP_FAIL_SAFE_BOOT_L")
	)
	(segment
		(start 29.733596 24.851741)
		(end 30.058004 24.851741)
		(width 0.12065)
		(layer "In6.Cu")
		(net "NFP_FAIL_SAFE_BOOT_L")
	)
	(segment
		(start 17.78 47.371)
		(end 17.78 48.7045)
		(width 0.12065)
		(layer "In7.Cu")
		(net "NFP_FAIL_SAFE_BOOT_L")
	)
	(segment
		(start 17.145 43.18)
		(end 17.145 46.736)
		(width 0.12065)
		(layer "In7.Cu")
		(net "NFP_FAIL_SAFE_BOOT_L")
	)
	(segment
		(start 20.694777 37.03767)
		(end 20.40067 37.331777)
		(width 0.12065)
		(layer "In7.Cu")
		(net "NFP_FAIL_SAFE_BOOT_L")
	)
	(segment
		(start 20.634325 36.509325)
		(end 20.634325 36.561878)
		(width 0.12065)
		(layer "In7.Cu")
		(net "NFP_FAIL_SAFE_BOOT_L")
	)
	(segment
		(start 19.177 26.035)
		(end 18.923 26.289)
		(width 0.12065)
		(layer "In7.Cu")
		(net "NFP_FAIL_SAFE_BOOT_L")
	)
	(segment
		(start 18.923 26.289)
		(end 18.923 29.083)
		(width 0.12065)
		(layer "In7.Cu")
		(net "NFP_FAIL_SAFE_BOOT_L")
	)
	(segment
		(start 17.145 46.736)
		(end 17.78 47.371)
		(width 0.12065)
		(layer "In7.Cu")
		(net "NFP_FAIL_SAFE_BOOT_L")
	)
	(segment
		(start 20.40067 37.331777)
		(end 19.945223 37.331777)
		(width 0.12065)
		(layer "In7.Cu")
		(net "NFP_FAIL_SAFE_BOOT_L")
	)
	(segment
		(start 19.945223 37.331777)
		(end 17.78 39.497)
		(width 0.12065)
		(layer "In7.Cu")
		(net "NFP_FAIL_SAFE_BOOT_L")
	)
	(segment
		(start 18.923 29.083)
		(end 19.027775 29.187775)
		(width 0.12065)
		(layer "In7.Cu")
		(net "NFP_FAIL_SAFE_BOOT_L")
	)
	(segment
		(start 17.78 39.497)
		(end 17.78 42.545)
		(width 0.12065)
		(layer "In7.Cu")
		(net "NFP_FAIL_SAFE_BOOT_L")
	)
	(segment
		(start 19.027775 34.902775)
		(end 20.634325 36.509325)
		(width 0.12065)
		(layer "In7.Cu")
		(net "NFP_FAIL_SAFE_BOOT_L")
	)
	(segment
		(start 20.634325 36.561878)
		(end 20.694777 36.62233)
		(width 0.12065)
		(layer "In7.Cu")
		(net "NFP_FAIL_SAFE_BOOT_L")
	)
	(segment
		(start 20.694777 36.62233)
		(end 20.694777 37.03767)
		(width 0.12065)
		(layer "In7.Cu")
		(net "NFP_FAIL_SAFE_BOOT_L")
	)
	(segment
		(start 17.78 42.545)
		(end 17.145 43.18)
		(width 0.12065)
		(layer "In7.Cu")
		(net "NFP_FAIL_SAFE_BOOT_L")
	)
	(segment
		(start 19.027775 29.187775)
		(end 19.027775 34.902775)
		(width 0.12065)
		(layer "In7.Cu")
		(net "NFP_FAIL_SAFE_BOOT_L")
	)
	(segment
		(start 22.7838 21.7932)
		(end 23.241 21.336)
		(width 0.14732)
		(layer "F.Cu")
		(net "NFP_ARM_SPI_FLASH_WP_L")
	)
	(segment
		(start 22.7838 26.1239)
		(end 22.7838 21.7932)
		(width 0.14732)
		(layer "F.Cu")
		(net "NFP_ARM_SPI_FLASH_WP_L")
	)
	(segment
		(start 42.237 14.042009)
		(end 41.737001 13.54201)
		(width 0.13208)
		(layer "F.Cu")
		(net "NFP_ARM_SPI_FLASH_WP_L")
	)
	(via
		(at 41.737001 13.54201)
		(size 0.4826)
		(drill 0.25654)
		(layers "F.Cu" "B.Cu")
		(net "NFP_ARM_SPI_FLASH_WP_L")
	)
	(via
		(at 23.241 21.336)
		(size 0.508)
		(drill 0.254)
		(layers "F.Cu" "B.Cu")
		(net "NFP_ARM_SPI_FLASH_WP_L")
	)
	(segment
		(start 23.241 19.685)
		(end 23.241 21.336)
		(width 0.14732)
		(layer "B.Cu")
		(net "NFP_ARM_SPI_FLASH_WP_L")
	)
	(segment
		(start 23.241 17.3101)
		(end 23.241 19.685)
		(width 0.14732)
		(layer "B.Cu")
		(net "NFP_ARM_SPI_FLASH_WP_L")
	)
	(segment
		(start 39.140232 12.802768)
		(end 38.862 13.081)
		(width 0.12065)
		(layer "In2.Cu")
		(net "NFP_ARM_SPI_FLASH_WP_L")
	)
	(segment
		(start 29.337 15.621)
		(end 28.829 15.621)
		(width 0.12065)
		(layer "In2.Cu")
		(net "NFP_ARM_SPI_FLASH_WP_L")
	)
	(segment
		(start 41.051328 13.54201)
		(end 40.14023 12.630912)
		(width 0.12065)
		(layer "In2.Cu")
		(net "NFP_ARM_SPI_FLASH_WP_L")
	)
	(segment
		(start 28.829 15.621)
		(end 23.241 21.209)
		(width 0.12065)
		(layer "In2.Cu")
		(net "NFP_ARM_SPI_FLASH_WP_L")
	)
	(segment
		(start 29.845 15.113)
		(end 29.337 15.621)
		(width 0.12065)
		(layer "In2.Cu")
		(net "NFP_ARM_SPI_FLASH_WP_L")
	)
	(segment
		(start 38.862 13.081)
		(end 35.724795 13.081)
		(width 0.12065)
		(layer "In2.Cu")
		(net "NFP_ARM_SPI_FLASH_WP_L")
	)
	(segment
		(start 31.787795 11.773205)
		(end 29.845 13.716)
		(width 0.12065)
		(layer "In2.Cu")
		(net "NFP_ARM_SPI_FLASH_WP_L")
	)
	(segment
		(start 39.830273 12.065)
		(end 39.497 12.065)
		(width 0.12065)
		(layer "In2.Cu")
		(net "NFP_ARM_SPI_FLASH_WP_L")
	)
	(segment
		(start 35.724795 13.081)
		(end 34.417 11.773205)
		(width 0.12065)
		(layer "In2.Cu")
		(net "NFP_ARM_SPI_FLASH_WP_L")
	)
	(segment
		(start 29.845 13.716)
		(end 29.845 15.113)
		(width 0.12065)
		(layer "In2.Cu")
		(net "NFP_ARM_SPI_FLASH_WP_L")
	)
	(segment
		(start 40.14023 12.630912)
		(end 40.14023 12.374956)
		(width 0.12065)
		(layer "In2.Cu")
		(net "NFP_ARM_SPI_FLASH_WP_L")
	)
	(segment
		(start 41.737001 13.54201)
		(end 41.051328 13.54201)
		(width 0.12065)
		(layer "In2.Cu")
		(net "NFP_ARM_SPI_FLASH_WP_L")
	)
	(segment
		(start 34.417 11.773205)
		(end 31.787795 11.773205)
		(width 0.12065)
		(layer "In2.Cu")
		(net "NFP_ARM_SPI_FLASH_WP_L")
	)
	(segment
		(start 23.241 21.209)
		(end 23.241 21.336)
		(width 0.12065)
		(layer "In2.Cu")
		(net "NFP_ARM_SPI_FLASH_WP_L")
	)
	(segment
		(start 39.497 12.065)
		(end 39.140232 12.421768)
		(width 0.12065)
		(layer "In2.Cu")
		(net "NFP_ARM_SPI_FLASH_WP_L")
	)
	(segment
		(start 39.140232 12.421768)
		(end 39.140232 12.802768)
		(width 0.12065)
		(layer "In2.Cu")
		(net "NFP_ARM_SPI_FLASH_WP_L")
	)
	(segment
		(start 40.14023 12.374956)
		(end 39.830273 12.065)
		(width 0.12065)
		(layer "In2.Cu")
		(net "NFP_ARM_SPI_FLASH_WP_L")
	)
	(via
		(at 35.433 25.6794)
		(size 0.4572)
		(drill 0.20574)
		(layers "F.Cu" "B.Cu")
		(net "CORE_FB_PH2_THERM_L")
	)
	(via
		(at 41.737001 26.543991)
		(size 0.4826)
		(drill 0.20574)
		(layers "F.Cu" "B.Cu")
		(net "CORE_FB_PH2_THERM_L")
	)
	(via
		(at 44.30489 39.38999)
		(size 0.508)
		(drill 0.254)
		(layers "F.Cu" "B.Cu")
		(net "CORE_FB_PH2_THERM_L")
	)
	(segment
		(start 43.5229 37.3761)
		(end 44.13758 37.99078)
		(width 0.14732)
		(layer "B.Cu")
		(net "CORE_FB_PH2_THERM_L")
	)
	(segment
		(start 40.259 37.846)
		(end 43.053 37.846)
		(width 0.14732)
		(layer "B.Cu")
		(net "CORE_FB_PH2_THERM_L")
	)
	(segment
		(start 44.13758 38.862)
		(end 44.30489 39.02931)
		(width 0.14732)
		(layer "B.Cu")
		(net "CORE_FB_PH2_THERM_L")
	)
	(segment
		(start 44.13758 37.99078)
		(end 44.13758 38.862)
		(width 0.14732)
		(layer "B.Cu")
		(net "CORE_FB_PH2_THERM_L")
	)
	(segment
		(start 44.30489 39.02931)
		(end 44.30489 39.38999)
		(width 0.14732)
		(layer "B.Cu")
		(net "CORE_FB_PH2_THERM_L")
	)
	(segment
		(start 43.053 37.846)
		(end 43.5229 37.3761)
		(width 0.14732)
		(layer "B.Cu")
		(net "CORE_FB_PH2_THERM_L")
	)
	(segment
		(start 45.2755 39.38999)
		(end 44.30489 39.38999)
		(width 0.14732)
		(layer "B.Cu")
		(net "CORE_FB_PH2_THERM_L")
	)
	(segment
		(start 34.246007 25.048388)
		(end 34.801988 25.048388)
		(width 0.127)
		(layer "In1.Cu")
		(net "CORE_FB_PH2_THERM_L")
	)
	(segment
		(start 34.801988 25.048388)
		(end 35.433 25.6794)
		(width 0.127)
		(layer "In1.Cu")
		(net "CORE_FB_PH2_THERM_L")
	)
	(segment
		(start 41.737001 26.543991)
		(end 41.167685 25.974675)
		(width 0.12065)
		(layer "In6.Cu")
		(net "CORE_FB_PH2_THERM_L")
	)
	(segment
		(start 36.50427 25.974675)
		(end 36.408004 26.070941)
		(width 0.12065)
		(layer "In6.Cu")
		(net "CORE_FB_PH2_THERM_L")
	)
	(segment
		(start 36.408004 26.070941)
		(end 35.976941 26.070941)
		(width 0.12065)
		(layer "In6.Cu")
		(net "CORE_FB_PH2_THERM_L")
	)
	(segment
		(start 41.167685 25.974675)
		(end 36.50427 25.974675)
		(width 0.12065)
		(layer "In6.Cu")
		(net "CORE_FB_PH2_THERM_L")
	)
	(segment
		(start 35.976941 26.070941)
		(end 35.5854 25.6794)
		(width 0.12065)
		(layer "In6.Cu")
		(net "CORE_FB_PH2_THERM_L")
	)
	(segment
		(start 35.5854 25.6794)
		(end 35.433 25.6794)
		(width 0.12065)
		(layer "In6.Cu")
		(net "CORE_FB_PH2_THERM_L")
	)
	(segment
		(start 41.737001 26.543991)
		(end 43.688991 26.543991)
		(width 0.12065)
		(layer "In7.Cu")
		(net "CORE_FB_PH2_THERM_L")
	)
	(segment
		(start 43.688991 26.543991)
		(end 44.30489 27.15989)
		(width 0.12065)
		(layer "In7.Cu")
		(net "CORE_FB_PH2_THERM_L")
	)
	(segment
		(start 44.30489 27.15989)
		(end 44.30489 39.38999)
		(width 0.12065)
		(layer "In7.Cu")
		(net "CORE_FB_PH2_THERM_L")
	)
	(segment
		(start 33.746008 25.548412)
		(end 33.495996 25.2984)
		(width 0.14732)
		(layer "F.Cu")
		(net "CORE_FB_PH1_THERM_L")
	)
	(segment
		(start 33.495996 25.2984)
		(end 33.147 25.2984)
		(width 0.14732)
		(layer "F.Cu")
		(net "CORE_FB_PH1_THERM_L")
	)
	(via
		(at 61.849 47.498)
		(size 0.508)
		(drill 0.25654)
		(layers "F.Cu" "B.Cu")
		(net "CORE_FB_PH1_THERM_L")
	)
	(via
		(at 33.147 25.2984)
		(size 0.4572)
		(drill 0.20574)
		(layers "F.Cu" "B.Cu")
		(net "CORE_FB_PH1_THERM_L")
	)
	(via
		(at 63.90099 39.38999)
		(size 0.508)
		(drill 0.254)
		(layers "F.Cu" "B.Cu")
		(net "CORE_FB_PH1_THERM_L")
	)
	(via
		(at 62.736984 30.542001)
		(size 0.4826)
		(drill 0.20574)
		(layers "F.Cu" "B.Cu")
		(net "CORE_FB_PH1_THERM_L")
	)
	(segment
		(start 63.73368 38.862)
		(end 63.90099 39.02931)
		(width 0.14732)
		(layer "B.Cu")
		(net "CORE_FB_PH1_THERM_L")
	)
	(segment
		(start 63.119 37.3761)
		(end 63.73368 37.99078)
		(width 0.14732)
		(layer "B.Cu")
		(net "CORE_FB_PH1_THERM_L")
	)
	(segment
		(start 63.90099 39.02931)
		(end 63.90099 39.38999)
		(width 0.14732)
		(layer "B.Cu")
		(net "CORE_FB_PH1_THERM_L")
	)
	(segment
		(start 63.73368 37.99078)
		(end 63.73368 38.862)
		(width 0.14732)
		(layer "B.Cu")
		(net "CORE_FB_PH1_THERM_L")
	)
	(segment
		(start 64.8716 39.38999)
		(end 63.90099 39.38999)
		(width 0.14732)
		(layer "B.Cu")
		(net "CORE_FB_PH1_THERM_L")
	)
	(segment
		(start 32.547941 26.959941)
		(end 32.893 27.305)
		(width 0.12065)
		(layer "In2.Cu")
		(net "CORE_FB_PH1_THERM_L")
	)
	(segment
		(start 32.247459 26.405459)
		(end 32.547941 26.705941)
		(width 0.12065)
		(layer "In2.Cu")
		(net "CORE_FB_PH1_THERM_L")
	)
	(segment
		(start 42.672 29.972)
		(end 62.166983 29.972)
		(width 0.12065)
		(layer "In2.Cu")
		(net "CORE_FB_PH1_THERM_L")
	)
	(segment
		(start 32.725741 25.719659)
		(end 32.476796 25.719659)
		(width 0.12065)
		(layer "In2.Cu")
		(net "CORE_FB_PH1_THERM_L")
	)
	(segment
		(start 62.166983 29.972)
		(end 62.736984 30.542001)
		(width 0.12065)
		(layer "In2.Cu")
		(net "CORE_FB_PH1_THERM_L")
	)
	(segment
		(start 32.247459 25.948996)
		(end 32.247459 26.405459)
		(width 0.12065)
		(layer "In2.Cu")
		(net "CORE_FB_PH1_THERM_L")
	)
	(segment
		(start 33.147 25.2984)
		(end 32.725741 25.719659)
		(width 0.12065)
		(layer "In2.Cu")
		(net "CORE_FB_PH1_THERM_L")
	)
	(segment
		(start 35.052 27.813)
		(end 35.687 27.813)
		(width 0.12065)
		(layer "In2.Cu")
		(net "CORE_FB_PH1_THERM_L")
	)
	(segment
		(start 32.893 27.305)
		(end 34.544 27.305)
		(width 0.12065)
		(layer "In2.Cu")
		(net "CORE_FB_PH1_THERM_L")
	)
	(segment
		(start 32.476796 25.719659)
		(end 32.247459 25.948996)
		(width 0.12065)
		(layer "In2.Cu")
		(net "CORE_FB_PH1_THERM_L")
	)
	(segment
		(start 39.37 29.083)
		(end 41.783 29.083)
		(width 0.12065)
		(layer "In2.Cu")
		(net "CORE_FB_PH1_THERM_L")
	)
	(segment
		(start 41.783 29.083)
		(end 42.672 29.972)
		(width 0.12065)
		(layer "In2.Cu")
		(net "CORE_FB_PH1_THERM_L")
	)
	(segment
		(start 39.243 29.21)
		(end 39.37 29.083)
		(width 0.12065)
		(layer "In2.Cu")
		(net "CORE_FB_PH1_THERM_L")
	)
	(segment
		(start 37.084 29.21)
		(end 39.243 29.21)
		(width 0.12065)
		(layer "In2.Cu")
		(net "CORE_FB_PH1_THERM_L")
	)
	(segment
		(start 35.687 27.813)
		(end 37.084 29.21)
		(width 0.12065)
		(layer "In2.Cu")
		(net "CORE_FB_PH1_THERM_L")
	)
	(segment
		(start 34.544 27.305)
		(end 35.052 27.813)
		(width 0.12065)
		(layer "In2.Cu")
		(net "CORE_FB_PH1_THERM_L")
	)
	(segment
		(start 32.547941 26.705941)
		(end 32.547941 26.959941)
		(width 0.12065)
		(layer "In2.Cu")
		(net "CORE_FB_PH1_THERM_L")
	)
	(segment
		(start 63.90099 35.70699)
		(end 63.90099 39.38999)
		(width 0.12065)
		(layer "In3.Cu")
		(net "CORE_FB_PH1_THERM_L")
	)
	(segment
		(start 62.736984 30.542001)
		(end 63.246 31.051017)
		(width 0.12065)
		(layer "In3.Cu")
		(net "CORE_FB_PH1_THERM_L")
	)
	(segment
		(start 63.246 31.051017)
		(end 63.246 35.052)
		(width 0.12065)
		(layer "In3.Cu")
		(net "CORE_FB_PH1_THERM_L")
	)
	(segment
		(start 63.246 35.052)
		(end 63.90099 35.70699)
		(width 0.12065)
		(layer "In3.Cu")
		(net "CORE_FB_PH1_THERM_L")
	)
	(segment
		(start 62.290325 41.292729)
		(end 62.031829 41.551225)
		(width 0.12065)
		(layer "In6.Cu")
		(net "CORE_FB_PH1_THERM_L")
	)
	(segment
		(start 61.739755 41.551225)
		(end 61.214 42.07698)
		(width 0.12065)
		(layer "In6.Cu")
		(net "CORE_FB_PH1_THERM_L")
	)
	(segment
		(start 62.031829 41.551225)
		(end 61.739755 41.551225)
		(width 0.12065)
		(layer "In6.Cu")
		(net "CORE_FB_PH1_THERM_L")
	)
	(segment
		(start 61.214 42.07698)
		(end 61.214 46.863)
		(width 0.12065)
		(layer "In6.Cu")
		(net "CORE_FB_PH1_THERM_L")
	)
	(segment
		(start 61.214 46.863)
		(end 61.849 47.498)
		(width 0.12065)
		(layer "In6.Cu")
		(net "CORE_FB_PH1_THERM_L")
	)
	(segment
		(start 62.290325 41.000655)
		(end 62.290325 41.292729)
		(width 0.12065)
		(layer "In6.Cu")
		(net "CORE_FB_PH1_THERM_L")
	)
	(segment
		(start 63.90099 39.38999)
		(end 62.290325 41.000655)
		(width 0.12065)
		(layer "In6.Cu")
		(net "CORE_FB_PH1_THERM_L")
	)
	(segment
		(start 26.65476 36.50234)
		(end 27.366366 36.50234)
		(width 0.14732)
		(layer "F.Cu")
		(net "CORE_FB_FAULT_L")
	)
	(segment
		(start 32.94065 25.6921)
		(end 33.682508 26.433958)
		(width 0.127)
		(layer "F.Cu")
		(net "CORE_FB_FAULT_L")
	)
	(segment
		(start 33.682508 26.433958)
		(end 33.682508 26.48491)
		(width 0.127)
		(layer "F.Cu")
		(net "CORE_FB_FAULT_L")
	)
	(segment
		(start 26.3271 36.83)
		(end 26.65476 36.50234)
		(width 0.14732)
		(layer "F.Cu")
		(net "CORE_FB_FAULT_L")
	)
	(segment
		(start 27.366366 36.50234)
		(end 27.714016 36.84999)
		(width 0.14732)
		(layer "F.Cu")
		(net "CORE_FB_FAULT_L")
	)
	(segment
		(start 27.714016 36.84999)
		(end 28.1686 36.84999)
		(width 0.14732)
		(layer "F.Cu")
		(net "CORE_FB_FAULT_L")
	)
	(segment
		(start 33.682508 26.48491)
		(end 33.746008 26.54841)
		(width 0.127)
		(layer "F.Cu")
		(net "CORE_FB_FAULT_L")
	)
	(segment
		(start 31.9405 25.6921)
		(end 32.94065 25.6921)
		(width 0.127)
		(layer "F.Cu")
		(net "CORE_FB_FAULT_L")
	)
	(segment
		(start 31.5214 25.2222)
		(end 31.9405 25.6921)
		(width 0.127)
		(layer "F.Cu")
		(net "CORE_FB_FAULT_L")
	)
	(via
		(at 26.2763 36.83)
		(size 0.508)
		(drill 0.25654)
		(layers "F.Cu" "B.Cu")
		(net "CORE_FB_FAULT_L")
	)
	(via
		(at 31.5214 25.2222)
		(size 0.4572)
		(drill 0.20574)
		(layers "F.Cu" "B.Cu")
		(net "CORE_FB_FAULT_L")
	)
	(segment
		(start 31.180659 24.881459)
		(end 30.546396 24.881459)
		(width 0.12065)
		(layer "In6.Cu")
		(net "CORE_FB_FAULT_L")
	)
	(segment
		(start 27.315541 28.564459)
		(end 27.315541 28.584804)
		(width 0.12065)
		(layer "In6.Cu")
		(net "CORE_FB_FAULT_L")
	)
	(segment
		(start 26.984325 31.678829)
		(end 26.797 31.866154)
		(width 0.12065)
		(layer "In6.Cu")
		(net "CORE_FB_FAULT_L")
	)
	(segment
		(start 30.317059 25.110796)
		(end 30.317059 25.562941)
		(width 0.12065)
		(layer "In6.Cu")
		(net "CORE_FB_FAULT_L")
	)
	(segment
		(start 25.781 36.322)
		(end 26.2763 36.8173)
		(width 0.12065)
		(layer "In6.Cu")
		(net "CORE_FB_FAULT_L")
	)
	(segment
		(start 26.797 31.866154)
		(end 26.797 34.342654)
		(width 0.12065)
		(layer "In6.Cu")
		(net "CORE_FB_FAULT_L")
	)
	(segment
		(start 26.416 29.484345)
		(end 26.416 30.734)
		(width 0.12065)
		(layer "In6.Cu")
		(net "CORE_FB_FAULT_L")
	)
	(segment
		(start 26.797 34.342654)
		(end 25.781 35.358654)
		(width 0.12065)
		(layer "In6.Cu")
		(net "CORE_FB_FAULT_L")
	)
	(segment
		(start 26.2763 36.8173)
		(end 26.2763 36.83)
		(width 0.12065)
		(layer "In6.Cu")
		(net "CORE_FB_FAULT_L")
	)
	(segment
		(start 31.5214 25.2222)
		(end 31.180659 24.881459)
		(width 0.12065)
		(layer "In6.Cu")
		(net "CORE_FB_FAULT_L")
	)
	(segment
		(start 30.546396 24.881459)
		(end 30.317059 25.110796)
		(width 0.12065)
		(layer "In6.Cu")
		(net "CORE_FB_FAULT_L")
	)
	(segment
		(start 26.984325 31.302325)
		(end 26.984325 31.678829)
		(width 0.12065)
		(layer "In6.Cu")
		(net "CORE_FB_FAULT_L")
	)
	(segment
		(start 26.416 30.734)
		(end 26.984325 31.302325)
		(width 0.12065)
		(layer "In6.Cu")
		(net "CORE_FB_FAULT_L")
	)
	(segment
		(start 25.781 35.358654)
		(end 25.781 36.322)
		(width 0.12065)
		(layer "In6.Cu")
		(net "CORE_FB_FAULT_L")
	)
	(segment
		(start 27.315541 28.584804)
		(end 26.416 29.484345)
		(width 0.12065)
		(layer "In6.Cu")
		(net "CORE_FB_FAULT_L")
	)
	(segment
		(start 30.317059 25.562941)
		(end 27.315541 28.564459)
		(width 0.12065)
		(layer "In6.Cu")
		(net "CORE_FB_FAULT_L")
	)
	(segment
		(start 26.61412 36.22802)
		(end 27.480006 36.22802)
		(width 0.14732)
		(layer "F.Cu")
		(net "CORE_FB_ALERT_L")
	)
	(segment
		(start 27.480006 36.22802)
		(end 27.601977 36.349991)
		(width 0.14732)
		(layer "F.Cu")
		(net "CORE_FB_ALERT_L")
	)
	(segment
		(start 27.601977 36.349991)
		(end 28.1686 36.349991)
		(width 0.14732)
		(layer "F.Cu")
		(net "CORE_FB_ALERT_L")
	)
	(segment
		(start 26.3271 35.941)
		(end 26.61412 36.22802)
		(width 0.14732)
		(layer "F.Cu")
		(net "CORE_FB_ALERT_L")
	)
	(via
		(at 26.3271 35.941)
		(size 0.508)
		(drill 0.25654)
		(layers "F.Cu" "B.Cu")
		(net "CORE_FB_ALERT_L")
	)
	(via
		(at 35.433 26.5176)
		(size 0.4572)
		(drill 0.20574)
		(layers "F.Cu" "B.Cu")
		(net "CORE_FB_ALERT_L")
	)
	(segment
		(start 34.430411 26.048411)
		(end 34.246007 26.048411)
		(width 0.127)
		(layer "In1.Cu")
		(net "CORE_FB_ALERT_L")
	)
	(segment
		(start 34.8996 26.5176)
		(end 34.430411 26.048411)
		(width 0.127)
		(layer "In1.Cu")
		(net "CORE_FB_ALERT_L")
	)
	(segment
		(start 35.433 26.5176)
		(end 34.8996 26.5176)
		(width 0.127)
		(layer "In1.Cu")
		(net "CORE_FB_ALERT_L")
	)
	(segment
		(start 31.505804 26.507059)
		(end 31.735141 26.736396)
		(width 0.12065)
		(layer "In6.Cu")
		(net "CORE_FB_ALERT_L")
	)
	(segment
		(start 30.922341 27.060804)
		(end 30.922341 26.725855)
		(width 0.12065)
		(layer "In6.Cu")
		(net "CORE_FB_ALERT_L")
	)
	(segment
		(start 30.240859 27.290141)
		(end 30.693004 27.290141)
		(width 0.12065)
		(layer "In6.Cu")
		(net "CORE_FB_ALERT_L")
	)
	(segment
		(start 26.3271 35.941)
		(end 26.3271 35.267925)
		(width 0.12065)
		(layer "In6.Cu")
		(net "CORE_FB_ALERT_L")
	)
	(segment
		(start 30.693004 27.290141)
		(end 30.922341 27.060804)
		(width 0.12065)
		(layer "In6.Cu")
		(net "CORE_FB_ALERT_L")
	)
	(segment
		(start 26.3271 35.267925)
		(end 26.923949 34.671076)
		(width 0.12065)
		(layer "In6.Cu")
		(net "CORE_FB_ALERT_L")
	)
	(segment
		(start 28.762325 32.324675)
		(end 28.762325 30.546675)
		(width 0.12065)
		(layer "In6.Cu")
		(net "CORE_FB_ALERT_L")
	)
	(segment
		(start 26.923949 34.66465)
		(end 27.044599 34.544)
		(width 0.12065)
		(layer "In6.Cu")
		(net "CORE_FB_ALERT_L")
	)
	(segment
		(start 27.873325 33.213675)
		(end 28.762325 32.324675)
		(width 0.12065)
		(layer "In6.Cu")
		(net "CORE_FB_ALERT_L")
	)
	(segment
		(start 28.991941 30.317059)
		(end 28.991941 28.539059)
		(width 0.12065)
		(layer "In6.Cu")
		(net "CORE_FB_ALERT_L")
	)
	(segment
		(start 30.922341 26.725855)
		(end 31.141137 26.507059)
		(width 0.12065)
		(layer "In6.Cu")
		(net "CORE_FB_ALERT_L")
	)
	(segment
		(start 34.6456 27.305)
		(end 35.433 26.5176)
		(width 0.12065)
		(layer "In6.Cu")
		(net "CORE_FB_ALERT_L")
	)
	(segment
		(start 27.614829 34.223325)
		(end 27.873325 33.964829)
		(width 0.12065)
		(layer "In6.Cu")
		(net "CORE_FB_ALERT_L")
	)
	(segment
		(start 32.009055 27.305)
		(end 34.6456 27.305)
		(width 0.12065)
		(layer "In6.Cu")
		(net "CORE_FB_ALERT_L")
	)
	(segment
		(start 31.141137 26.507059)
		(end 31.505804 26.507059)
		(width 0.12065)
		(layer "In6.Cu")
		(net "CORE_FB_ALERT_L")
	)
	(segment
		(start 31.735141 27.031086)
		(end 32.009055 27.305)
		(width 0.12065)
		(layer "In6.Cu")
		(net "CORE_FB_ALERT_L")
	)
	(segment
		(start 27.050975 34.544)
		(end 27.37165 34.223325)
		(width 0.12065)
		(layer "In6.Cu")
		(net "CORE_FB_ALERT_L")
	)
	(segment
		(start 27.37165 34.223325)
		(end 27.614829 34.223325)
		(width 0.12065)
		(layer "In6.Cu")
		(net "CORE_FB_ALERT_L")
	)
	(segment
		(start 27.873325 33.964829)
		(end 27.873325 33.213675)
		(width 0.12065)
		(layer "In6.Cu")
		(net "CORE_FB_ALERT_L")
	)
	(segment
		(start 28.991941 28.539059)
		(end 30.240859 27.290141)
		(width 0.12065)
		(layer "In6.Cu")
		(net "CORE_FB_ALERT_L")
	)
	(segment
		(start 27.044599 34.544)
		(end 27.050975 34.544)
		(width 0.12065)
		(layer "In6.Cu")
		(net "CORE_FB_ALERT_L")
	)
	(segment
		(start 26.923949 34.671076)
		(end 26.923949 34.66465)
		(width 0.12065)
		(layer "In6.Cu")
		(net "CORE_FB_ALERT_L")
	)
	(segment
		(start 31.735141 26.736396)
		(end 31.735141 27.031086)
		(width 0.12065)
		(layer "In6.Cu")
		(net "CORE_FB_ALERT_L")
	)
	(segment
		(start 28.762325 30.546675)
		(end 28.991941 30.317059)
		(width 0.12065)
		(layer "In6.Cu")
		(net "CORE_FB_ALERT_L")
	)
	(segment
		(start 36.4871 44.4119)
		(end 35.814 44.4119)
		(width 0.14732)
		(layer "F.Cu")
		(net "NFP_VDD_CORE_TCOMPB")
	)
	(segment
		(start 36.957 43.434)
		(end 36.957 43.942)
		(width 0.14732)
		(layer "F.Cu")
		(net "NFP_VDD_CORE_TCOMPB")
	)
	(segment
		(start 35.7251 44.323)
		(end 35.814 44.4119)
		(width 0.14732)
		(layer "F.Cu")
		(net "NFP_VDD_CORE_TCOMPB")
	)
	(segment
		(start 36.957 43.942)
		(end 36.4871 44.4119)
		(width 0.14732)
		(layer "F.Cu")
		(net "NFP_VDD_CORE_TCOMPB")
	)
	(segment
		(start 34.2519 44.323)
		(end 35.7251 44.323)
		(width 0.14732)
		(layer "F.Cu")
		(net "NFP_VDD_CORE_TCOMPB")
	)
	(via
		(at 60.4139 46.355)
		(size 0.508)
		(drill 0.25654)
		(layers "F.Cu" "B.Cu")
		(net "NFP_VDD_CORE_TCOMPB")
	)
	(via
		(at 36.957 43.434)
		(size 0.508)
		(drill 0.25654)
		(layers "F.Cu" "B.Cu")
		(net "NFP_VDD_CORE_TCOMPB")
	)
	(segment
		(start 61.087 46.599475)
		(end 61.087 47.244)
		(width 0.12065)
		(layer "In3.Cu")
		(net "NFP_VDD_CORE_TCOMPB")
	)
	(segment
		(start 55.128871 45.847)
		(end 46.08195 45.847)
		(width 0.12065)
		(layer "In3.Cu")
		(net "NFP_VDD_CORE_TCOMPB")
	)
	(segment
		(start 36.528197 44.017235)
		(end 36.524184 43.896686)
		(width 0.12065)
		(layer "In3.Cu")
		(net "NFP_VDD_CORE_TCOMPB")
	)
	(segment
		(start 56.967171 47.685325)
		(end 55.394581 46.112735)
		(width 0.12065)
		(layer "In3.Cu")
		(net "NFP_VDD_CORE_TCOMPB")
	)
	(segment
		(start 61.090175 46.47565)
		(end 61.090175 46.5963)
		(width 0.12065)
		(layer "In3.Cu")
		(net "NFP_VDD_CORE_TCOMPB")
	)
	(segment
		(start 55.394581 46.112735)
		(end 55.394581 46.112709)
		(width 0.12065)
		(layer "In3.Cu")
		(net "NFP_VDD_CORE_TCOMPB")
	)
	(segment
		(start 42.164 45.847)
		(end 37.475846 45.847)
		(width 0.12065)
		(layer "In3.Cu")
		(net "NFP_VDD_CORE_TCOMPB")
	)
	(segment
		(start 60.969525 46.355)
		(end 61.090175 46.47565)
		(width 0.12065)
		(layer "In3.Cu")
		(net "NFP_VDD_CORE_TCOMPB")
	)
	(segment
		(start 59.044154 47.498)
		(end 58.856829 47.685325)
		(width 0.12065)
		(layer "In3.Cu")
		(net "NFP_VDD_CORE_TCOMPB")
	)
	(segment
		(start 55.394581 46.112709)
		(end 55.128871 45.847)
		(width 0.12065)
		(layer "In3.Cu")
		(net "NFP_VDD_CORE_TCOMPB")
	)
	(segment
		(start 37.475846 45.847)
		(end 36.528197 44.899351)
		(width 0.12065)
		(layer "In3.Cu")
		(net "NFP_VDD_CORE_TCOMPB")
	)
	(segment
		(start 45.646975 45.412025)
		(end 42.598975 45.412025)
		(width 0.12065)
		(layer "In3.Cu")
		(net "NFP_VDD_CORE_TCOMPB")
	)
	(segment
		(start 61.090175 46.5963)
		(end 61.087 46.599475)
		(width 0.12065)
		(layer "In3.Cu")
		(net "NFP_VDD_CORE_TCOMPB")
	)
	(segment
		(start 36.524184 43.896686)
		(end 36.957 43.434)
		(width 0.12065)
		(layer "In3.Cu")
		(net "NFP_VDD_CORE_TCOMPB")
	)
	(segment
		(start 36.528197 44.899351)
		(end 36.528197 44.017235)
		(width 0.12065)
		(layer "In3.Cu")
		(net "NFP_VDD_CORE_TCOMPB")
	)
	(segment
		(start 46.08195 45.847)
		(end 45.646975 45.412025)
		(width 0.12065)
		(layer "In3.Cu")
		(net "NFP_VDD_CORE_TCOMPB")
	)
	(segment
		(start 58.856829 47.685325)
		(end 56.967171 47.685325)
		(width 0.12065)
		(layer "In3.Cu")
		(net "NFP_VDD_CORE_TCOMPB")
	)
	(segment
		(start 61.087 47.244)
		(end 60.833 47.498)
		(width 0.12065)
		(layer "In3.Cu")
		(net "NFP_VDD_CORE_TCOMPB")
	)
	(segment
		(start 60.4139 46.355)
		(end 60.969525 46.355)
		(width 0.12065)
		(layer "In3.Cu")
		(net "NFP_VDD_CORE_TCOMPB")
	)
	(segment
		(start 60.833 47.498)
		(end 59.044154 47.498)
		(width 0.12065)
		(layer "In3.Cu")
		(net "NFP_VDD_CORE_TCOMPB")
	)
	(segment
		(start 42.598975 45.412025)
		(end 42.164 45.847)
		(width 0.12065)
		(layer "In3.Cu")
		(net "NFP_VDD_CORE_TCOMPB")
	)
	(segment
		(start 32.853554 42.037)
		(end 33.5661 42.037)
		(width 0.14732)
		(layer "F.Cu")
		(net "NFP_VDD_CORE_TCOMPA")
	)
	(segment
		(start 33.5661 42.037)
		(end 34.0233 42.545)
		(width 0.14732)
		(layer "F.Cu")
		(net "NFP_VDD_CORE_TCOMPA")
	)
	(segment
		(start 32.36501 41.0464)
		(end 32.36501 41.548456)
		(width 0.14732)
		(layer "F.Cu")
		(net "NFP_VDD_CORE_TCOMPA")
	)
	(segment
		(start 35.814 43.4721)
		(end 34.925 43.4467)
		(width 0.14732)
		(layer "F.Cu")
		(net "NFP_VDD_CORE_TCOMPA")
	)
	(segment
		(start 34.925 43.4467)
		(end 34.8869 43.434)
		(width 0.14732)
		(layer "F.Cu")
		(net "NFP_VDD_CORE_TCOMPA")
	)
	(segment
		(start 34.8869 43.434)
		(end 34.0233 43.434)
		(width 0.14732)
		(layer "F.Cu")
		(net "NFP_VDD_CORE_TCOMPA")
	)
	(segment
		(start 34.0233 42.545)
		(end 34.0233 43.434)
		(width 0.14732)
		(layer "F.Cu")
		(net "NFP_VDD_CORE_TCOMPA")
	)
	(segment
		(start 32.36501 41.548456)
		(end 32.853554 42.037)
		(width 0.14732)
		(layer "F.Cu")
		(net "NFP_VDD_CORE_TCOMPA")
	)
	(via
		(at 35.814 43.4721)
		(size 0.508)
		(drill 0.25654)
		(layers "F.Cu" "B.Cu")
		(net "NFP_VDD_CORE_TCOMPA")
	)
	(via
		(at 62.0141 46.355)
		(size 0.508)
		(drill 0.25654)
		(layers "F.Cu" "B.Cu")
		(net "NFP_VDD_CORE_TCOMPA")
	)
	(segment
		(start 55.146931 46.215325)
		(end 55.146931 46.2153)
		(width 0.12065)
		(layer "In3.Cu")
		(net "NFP_VDD_CORE_TCOMPA")
	)
	(segment
		(start 61.33465 47.346591)
		(end 60.935591 47.74565)
		(width 0.12065)
		(layer "In3.Cu")
		(net "NFP_VDD_CORE_TCOMPA")
	)
	(segment
		(start 62.0141 46.355)
		(end 61.458475 46.355)
		(width 0.12065)
		(layer "In3.Cu")
		(net "NFP_VDD_CORE_TCOMPA")
	)
	(segment
		(start 61.458475 46.355)
		(end 61.337825 46.47565)
		(width 0.12065)
		(layer "In3.Cu")
		(net "NFP_VDD_CORE_TCOMPA")
	)
	(segment
		(start 42.701566 45.659675)
		(end 42.266591 46.09465)
		(width 0.12065)
		(layer "In3.Cu")
		(net "NFP_VDD_CORE_TCOMPA")
	)
	(segment
		(start 59.146745 47.74565)
		(end 58.95942 47.932975)
		(width 0.12065)
		(layer "In3.Cu")
		(net "NFP_VDD_CORE_TCOMPA")
	)
	(segment
		(start 61.337825 46.698891)
		(end 61.33465 46.702066)
		(width 0.12065)
		(layer "In3.Cu")
		(net "NFP_VDD_CORE_TCOMPA")
	)
	(segment
		(start 56.86458 47.932975)
		(end 55.146931 46.215325)
		(width 0.12065)
		(layer "In3.Cu")
		(net "NFP_VDD_CORE_TCOMPA")
	)
	(segment
		(start 45.979359 46.09465)
		(end 45.544384 45.659675)
		(width 0.12065)
		(layer "In3.Cu")
		(net "NFP_VDD_CORE_TCOMPA")
	)
	(segment
		(start 55.146931 46.2153)
		(end 55.026281 46.09465)
		(width 0.12065)
		(layer "In3.Cu")
		(net "NFP_VDD_CORE_TCOMPA")
	)
	(segment
		(start 61.337825 46.47565)
		(end 61.337825 46.698891)
		(width 0.12065)
		(layer "In3.Cu")
		(net "NFP_VDD_CORE_TCOMPA")
	)
	(segment
		(start 55.026281 46.09465)
		(end 45.979359 46.09465)
		(width 0.12065)
		(layer "In3.Cu")
		(net "NFP_VDD_CORE_TCOMPA")
	)
	(segment
		(start 36.276661 43.904916)
		(end 35.814 43.4721)
		(width 0.12065)
		(layer "In3.Cu")
		(net "NFP_VDD_CORE_TCOMPA")
	)
	(segment
		(start 60.935591 47.74565)
		(end 59.146745 47.74565)
		(width 0.12065)
		(layer "In3.Cu")
		(net "NFP_VDD_CORE_TCOMPA")
	)
	(segment
		(start 37.373255 46.09465)
		(end 36.280547 45.001942)
		(width 0.12065)
		(layer "In3.Cu")
		(net "NFP_VDD_CORE_TCOMPA")
	)
	(segment
		(start 42.266591 46.09465)
		(end 37.373255 46.09465)
		(width 0.12065)
		(layer "In3.Cu")
		(net "NFP_VDD_CORE_TCOMPA")
	)
	(segment
		(start 58.95942 47.932975)
		(end 56.86458 47.932975)
		(width 0.12065)
		(layer "In3.Cu")
		(net "NFP_VDD_CORE_TCOMPA")
	)
	(segment
		(start 36.280547 44.0214)
		(end 36.276661 43.904916)
		(width 0.12065)
		(layer "In3.Cu")
		(net "NFP_VDD_CORE_TCOMPA")
	)
	(segment
		(start 45.544384 45.659675)
		(end 42.701566 45.659675)
		(width 0.12065)
		(layer "In3.Cu")
		(net "NFP_VDD_CORE_TCOMPA")
	)
	(segment
		(start 36.280547 45.001942)
		(end 36.280547 44.0214)
		(width 0.12065)
		(layer "In3.Cu")
		(net "NFP_VDD_CORE_TCOMPA")
	)
	(segment
		(start 61.33465 46.702066)
		(end 61.33465 47.346591)
		(width 0.12065)
		(layer "In3.Cu")
		(net "NFP_VDD_CORE_TCOMPA")
	)
	(segment
		(start 34.0614 38.850011)
		(end 34.913011 38.850011)
		(width 0.14732)
		(layer "F.Cu")
		(net "_SW2")
	)
	(segment
		(start 34.913011 38.850011)
		(end 35.179 39.3065)
		(width 0.14732)
		(layer "F.Cu")
		(net "_SW2")
	)
	(segment
		(start 35.179 40.9321)
		(end 35.8521 41.656)
		(width 0.14732)
		(layer "F.Cu")
		(net "_SW2")
	)
	(segment
		(start 35.179 39.3065)
		(end 35.179 40.9321)
		(width 0.14732)
		(layer "F.Cu")
		(net "_SW2")
	)
	(via
		(at 35.179 39.3065)
		(size 0.508)
		(drill 0.2667)
		(layers "F.Cu" "B.Cu")
		(net "_SW2")
	)
	(segment
		(start 34.9123 38.350012)
		(end 34.0614 38.350012)
		(width 0.14732)
		(layer "F.Cu")
		(net "_SW1")
	)
	(segment
		(start 35.9029 38.989)
		(end 35.263912 38.350012)
		(width 0.14732)
		(layer "F.Cu")
		(net "_SW1")
	)
	(segment
		(start 35.263912 38.350012)
		(end 34.9123 38.350012)
		(width 0.14732)
		(layer "F.Cu")
		(net "_SW1")
	)
	(via
		(at 34.9123 38.350012)
		(size 0.508)
		(drill 0.2667)
		(layers "F.Cu" "B.Cu")
		(net "_SW1")
	)
	(segment
		(start 33.365008 41.0464)
		(end 34.036 41.0464)
		(width 0.14732)
		(layer "F.Cu")
		(net "VR_ODN_L")
	)
	(via
		(at 34.036 41.0464)
		(size 0.508)
		(drill 0.254)
		(layers "F.Cu" "B.Cu")
		(net "VR_ODN_L")
	)
	(via
		(at 42.799 34.925)
		(size 0.508)
		(drill 0.2667)
		(layers "F.Cu" "B.Cu")
		(net "VR_ODN_L")
	)
	(segment
		(start 42.7609 34.8869)
		(end 42.799 34.925)
		(width 0.14732)
		(layer "B.Cu")
		(net "VR_ODN_L")
	)
	(segment
		(start 41.783 34.8869)
		(end 42.7609 34.8869)
		(width 0.14732)
		(layer "B.Cu")
		(net "VR_ODN_L")
	)
	(segment
		(start 35.192589 36.308386)
		(end 35.461575 36.0394)
		(width 0.12065)
		(layer "In6.Cu")
		(net "VR_ODN_L")
	)
	(segment
		(start 41.402 35.687)
		(end 42.164 34.925)
		(width 0.12065)
		(layer "In6.Cu")
		(net "VR_ODN_L")
	)
	(segment
		(start 42.164 34.925)
		(end 42.799 34.925)
		(width 0.12065)
		(layer "In6.Cu")
		(net "VR_ODN_L")
	)
	(segment
		(start 40.132 35.687)
		(end 41.402 35.687)
		(width 0.12065)
		(layer "In6.Cu")
		(net "VR_ODN_L")
	)
	(segment
		(start 40.005 35.814)
		(end 40.132 35.687)
		(width 0.12065)
		(layer "In6.Cu")
		(net "VR_ODN_L")
	)
	(segment
		(start 34.684614 36.308386)
		(end 35.192589 36.308386)
		(width 0.12065)
		(layer "In6.Cu")
		(net "VR_ODN_L")
	)
	(segment
		(start 36.085729 35.753675)
		(end 36.146054 35.814)
		(width 0.12065)
		(layer "In6.Cu")
		(net "VR_ODN_L")
	)
	(segment
		(start 35.461575 36.012171)
		(end 35.720071 35.753675)
		(width 0.12065)
		(layer "In6.Cu")
		(net "VR_ODN_L")
	)
	(segment
		(start 35.461575 36.0394)
		(end 35.461575 36.012171)
		(width 0.12065)
		(layer "In6.Cu")
		(net "VR_ODN_L")
	)
	(segment
		(start 35.720071 35.753675)
		(end 36.085729 35.753675)
		(width 0.12065)
		(layer "In6.Cu")
		(net "VR_ODN_L")
	)
	(segment
		(start 36.146054 35.814)
		(end 40.005 35.814)
		(width 0.12065)
		(layer "In6.Cu")
		(net "VR_ODN_L")
	)
	(segment
		(start 34.036 41.0464)
		(end 34.036 36.957)
		(width 0.12065)
		(layer "In6.Cu")
		(net "VR_ODN_L")
	)
	(segment
		(start 34.036 36.957)
		(end 34.684614 36.308386)
		(width 0.12065)
		(layer "In6.Cu")
		(net "VR_ODN_L")
	)
	(segment
		(start 34.841612 41.402)
		(end 34.798 41.358388)
		(width 0.14732)
		(layer "F.Cu")
		(net "VR_OD1_L")
	)
	(segment
		(start 34.841612 41.422345)
		(end 34.841612 41.402)
		(width 0.14732)
		(layer "F.Cu")
		(net "VR_OD1_L")
	)
	(segment
		(start 34.798 41.086608)
		(end 34.0614 40.350008)
		(width 0.14732)
		(layer "F.Cu")
		(net "VR_OD1_L")
	)
	(segment
		(start 34.798 41.358388)
		(end 34.798 41.086608)
		(width 0.14732)
		(layer "F.Cu")
		(net "VR_OD1_L")
	)
	(via
		(at 62.23 37.211)
		(size 0.508)
		(drill 0.254)
		(layers "F.Cu" "B.Cu")
		(net "VR_OD1_L")
	)
	(via
		(at 34.841612 41.422345)
		(size 0.508)
		(drill 0.2667)
		(layers "F.Cu" "B.Cu")
		(net "VR_OD1_L")
	)
	(segment
		(start 62.560556 34.983953)
		(end 62.79896 35.222358)
		(width 0.14732)
		(layer "B.Cu")
		(net "VR_OD1_L")
	)
	(segment
		(start 62.553901 34.983953)
		(end 62.560556 34.983953)
		(width 0.14732)
		(layer "B.Cu")
		(net "VR_OD1_L")
	)
	(segment
		(start 62.237112 34.042096)
		(end 62.23 34.049208)
		(width 0.14732)
		(layer "B.Cu")
		(net "VR_OD1_L")
	)
	(segment
		(start 62.79896 35.80097)
		(end 62.611 35.98893)
		(width 0.14732)
		(layer "B.Cu")
		(net "VR_OD1_L")
	)
	(segment
		(start 62.23 34.049208)
		(end 62.23 34.671025)
		(width 0.14732)
		(layer "B.Cu")
		(net "VR_OD1_L")
	)
	(segment
		(start 62.79896 35.222358)
		(end 62.79896 35.80097)
		(width 0.14732)
		(layer "B.Cu")
		(net "VR_OD1_L")
	)
	(segment
		(start 62.23 34.671025)
		(end 62.440642 34.881668)
		(width 0.14732)
		(layer "B.Cu")
		(net "VR_OD1_L")
	)
	(segment
		(start 62.611 35.98893)
		(end 62.611 36.83)
		(width 0.14732)
		(layer "B.Cu")
		(net "VR_OD1_L")
	)
	(segment
		(start 62.611 36.83)
		(end 62.23 37.211)
		(width 0.14732)
		(layer "B.Cu")
		(net "VR_OD1_L")
	)
	(segment
		(start 62.451615 34.881668)
		(end 62.553901 34.983953)
		(width 0.14732)
		(layer "B.Cu")
		(net "VR_OD1_L")
	)
	(segment
		(start 62.440642 34.881668)
		(end 62.451615 34.881668)
		(width 0.14732)
		(layer "B.Cu")
		(net "VR_OD1_L")
	)
	(segment
		(start 52.832 41.148)
		(end 53.743225 40.236775)
		(width 0.12065)
		(layer "In6.Cu")
		(net "VR_OD1_L")
	)
	(segment
		(start 53.743225 40.236775)
		(end 53.743225 38.712775)
		(width 0.12065)
		(layer "In6.Cu")
		(net "VR_OD1_L")
	)
	(segment
		(start 50.165 43.942)
		(end 52.832 41.275)
		(width 0.12065)
		(layer "In6.Cu")
		(net "VR_OD1_L")
	)
	(segment
		(start 36.322 42.986325)
		(end 36.32835 42.992675)
		(width 0.12065)
		(layer "In6.Cu")
		(net "VR_OD1_L")
	)
	(segment
		(start 52.832 41.275)
		(end 52.832 41.148)
		(width 0.12065)
		(layer "In6.Cu")
		(net "VR_OD1_L")
	)
	(segment
		(start 54.864 38.354)
		(end 56.007 37.211)
		(width 0.12065)
		(layer "In6.Cu")
		(net "VR_OD1_L")
	)
	(segment
		(start 53.743225 38.712775)
		(end 54.102 38.354)
		(width 0.12065)
		(layer "In6.Cu")
		(net "VR_OD1_L")
	)
	(segment
		(start 35.620325 42.986325)
		(end 36.322 42.986325)
		(width 0.12065)
		(layer "In6.Cu")
		(net "VR_OD1_L")
	)
	(segment
		(start 43.373675 42.992675)
		(end 44.323 43.942)
		(width 0.12065)
		(layer "In6.Cu")
		(net "VR_OD1_L")
	)
	(segment
		(start 36.32835 42.992675)
		(end 43.373675 42.992675)
		(width 0.12065)
		(layer "In6.Cu")
		(net "VR_OD1_L")
	)
	(segment
		(start 34.841612 41.900958)
		(end 35.366325 42.425671)
		(width 0.12065)
		(layer "In6.Cu")
		(net "VR_OD1_L")
	)
	(segment
		(start 35.366325 42.732325)
		(end 35.620325 42.986325)
		(width 0.12065)
		(layer "In6.Cu")
		(net "VR_OD1_L")
	)
	(segment
		(start 34.841612 41.422345)
		(end 34.841612 41.900958)
		(width 0.12065)
		(layer "In6.Cu")
		(net "VR_OD1_L")
	)
	(segment
		(start 56.007 37.211)
		(end 62.23 37.211)
		(width 0.12065)
		(layer "In6.Cu")
		(net "VR_OD1_L")
	)
	(segment
		(start 54.102 38.354)
		(end 54.864 38.354)
		(width 0.12065)
		(layer "In6.Cu")
		(net "VR_OD1_L")
	)
	(segment
		(start 44.323 43.942)
		(end 50.165 43.942)
		(width 0.12065)
		(layer "In6.Cu")
		(net "VR_OD1_L")
	)
	(segment
		(start 35.366325 42.425671)
		(end 35.366325 42.732325)
		(width 0.12065)
		(layer "In6.Cu")
		(net "VR_OD1_L")
	)
	(via
		(at 40.132 39.878)
		(size 0.508)
		(drill 0.25654)
		(layers "F.Cu" "B.Cu")
		(net "GL_PHASE2")
	)
	(via
		(at 44.349848 40.389988)
		(size 0.508)
		(drill 0.254)
		(layers "F.Cu" "B.Cu")
		(net "GL_PHASE2")
	)
	(segment
		(start 45.2755 40.389988)
		(end 44.349848 40.389988)
		(width 0.14732)
		(layer "B.Cu")
		(net "GL_PHASE2")
	)
	(segment
		(start 40.132 39.878)
		(end 43.83786 39.878)
		(width 0.12065)
		(layer "In6.Cu")
		(net "GL_PHASE2")
	)
	(segment
		(start 43.83786 39.878)
		(end 44.349848 40.389988)
		(width 0.12065)
		(layer "In6.Cu")
		(net "GL_PHASE2")
	)
	(via
		(at 63.945948 40.389988)
		(size 0.508)
		(drill 0.254)
		(layers "F.Cu" "B.Cu")
		(net "GL_PHASE1")
	)
	(via
		(at 58.674 47.244)
		(size 0.508)
		(drill 0.25654)
		(layers "F.Cu" "B.Cu")
		(net "GL_PHASE1")
	)
	(segment
		(start 64.8716 40.389988)
		(end 63.945948 40.389988)
		(width 0.14732)
		(layer "B.Cu")
		(net "GL_PHASE1")
	)
	(segment
		(start 63.945948 40.389988)
		(end 62.671325 41.664611)
		(width 0.12065)
		(layer "In6.Cu")
		(net "GL_PHASE1")
	)
	(segment
		(start 61.976 48.006)
		(end 59.436 48.006)
		(width 0.12065)
		(layer "In6.Cu")
		(net "GL_PHASE1")
	)
	(segment
		(start 62.671325 47.310675)
		(end 61.976 48.006)
		(width 0.12065)
		(layer "In6.Cu")
		(net "GL_PHASE1")
	)
	(segment
		(start 62.671325 41.664611)
		(end 62.671325 47.310675)
		(width 0.12065)
		(layer "In6.Cu")
		(net "GL_PHASE1")
	)
	(segment
		(start 59.436 48.006)
		(end 58.674 47.244)
		(width 0.12065)
		(layer "In6.Cu")
		(net "GL_PHASE1")
	)
	(via
		(at 48.8569 36.703)
		(size 0.508)
		(drill 0.254)
		(layers "F.Cu" "B.Cu")
		(net "GH_PHASE2")
	)
	(via
		(at 38.608 39.878)
		(size 0.508)
		(drill 0.25654)
		(layers "F.Cu" "B.Cu")
		(net "GH_PHASE2")
	)
	(segment
		(start 48.6029 36.703)
		(end 48.8569 36.703)
		(width 0.14732)
		(layer "B.Cu")
		(net "GH_PHASE2")
	)
	(segment
		(start 48.471912 36.833988)
		(end 48.6029 36.703)
		(width 0.14732)
		(layer "B.Cu")
		(net "GH_PHASE2")
	)
	(segment
		(start 48.471912 37.6936)
		(end 48.471912 36.833988)
		(width 0.14732)
		(layer "B.Cu")
		(net "GH_PHASE2")
	)
	(segment
		(start 39.243 39.878)
		(end 39.751 39.37)
		(width 0.12065)
		(layer "In6.Cu")
		(net "GH_PHASE2")
	)
	(segment
		(start 47.355125 38.204775)
		(end 48.8569 36.703)
		(width 0.12065)
		(layer "In6.Cu")
		(net "GH_PHASE2")
	)
	(segment
		(start 44.853225 38.204775)
		(end 47.355125 38.204775)
		(width 0.12065)
		(layer "In6.Cu")
		(net "GH_PHASE2")
	)
	(segment
		(start 43.434 39.624)
		(end 44.853225 38.204775)
		(width 0.12065)
		(layer "In6.Cu")
		(net "GH_PHASE2")
	)
	(segment
		(start 39.751 39.37)
		(end 41.783 39.37)
		(width 0.12065)
		(layer "In6.Cu")
		(net "GH_PHASE2")
	)
	(segment
		(start 41.783 39.37)
		(end 42.037 39.624)
		(width 0.12065)
		(layer "In6.Cu")
		(net "GH_PHASE2")
	)
	(segment
		(start 38.608 39.878)
		(end 39.243 39.878)
		(width 0.12065)
		(layer "In6.Cu")
		(net "GH_PHASE2")
	)
	(segment
		(start 42.037 39.624)
		(end 43.434 39.624)
		(width 0.12065)
		(layer "In6.Cu")
		(net "GH_PHASE2")
	)
	(via
		(at 68.5546 36.703)
		(size 0.508)
		(drill 0.254)
		(layers "F.Cu" "B.Cu")
		(net "GH_PHASE1")
	)
	(via
		(at 57.15 47.244)
		(size 0.508)
		(drill 0.25654)
		(layers "F.Cu" "B.Cu")
		(net "GH_PHASE1")
	)
	(segment
		(start 68.068012 37.189588)
		(end 68.068012 37.6936)
		(width 0.14732)
		(layer "B.Cu")
		(net "GH_PHASE1")
	)
	(segment
		(start 68.5546 36.703)
		(end 68.068012 37.189588)
		(width 0.14732)
		(layer "B.Cu")
		(net "GH_PHASE1")
	)
	(segment
		(start 67.106114 38.204775)
		(end 66.817875 38.493014)
		(width 0.12065)
		(layer "In6.Cu")
		(net "GH_PHASE1")
	)
	(segment
		(start 57.912 45.212)
		(end 57.15 45.974)
		(width 0.12065)
		(layer "In6.Cu")
		(net "GH_PHASE1")
	)
	(segment
		(start 65.494154 38.948665)
		(end 63.413335 38.948665)
		(width 0.12065)
		(layer "In6.Cu")
		(net "GH_PHASE1")
	)
	(segment
		(start 68.5546 37.6174)
		(end 67.967225 38.204775)
		(width 0.12065)
		(layer "In6.Cu")
		(net "GH_PHASE1")
	)
	(segment
		(start 63.413335 38.948665)
		(end 62.484 39.878)
		(width 0.12065)
		(layer "In6.Cu")
		(net "GH_PHASE1")
	)
	(segment
		(start 67.967225 38.204775)
		(end 67.106114 38.204775)
		(width 0.12065)
		(layer "In6.Cu")
		(net "GH_PHASE1")
	)
	(segment
		(start 62.484 39.878)
		(end 58.42 39.878)
		(width 0.12065)
		(layer "In6.Cu")
		(net "GH_PHASE1")
	)
	(segment
		(start 65.734514 39.189025)
		(end 65.494154 38.948665)
		(width 0.12065)
		(layer "In6.Cu")
		(net "GH_PHASE1")
	)
	(segment
		(start 66.817875 38.513436)
		(end 66.142286 39.189025)
		(width 0.12065)
		(layer "In6.Cu")
		(net "GH_PHASE1")
	)
	(segment
		(start 58.42 39.878)
		(end 57.912 40.386)
		(width 0.12065)
		(layer "In6.Cu")
		(net "GH_PHASE1")
	)
	(segment
		(start 57.912 40.386)
		(end 57.912 45.212)
		(width 0.12065)
		(layer "In6.Cu")
		(net "GH_PHASE1")
	)
	(segment
		(start 57.15 45.974)
		(end 57.15 47.244)
		(width 0.12065)
		(layer "In6.Cu")
		(net "GH_PHASE1")
	)
	(segment
		(start 66.817875 38.493014)
		(end 66.817875 38.513436)
		(width 0.12065)
		(layer "In6.Cu")
		(net "GH_PHASE1")
	)
	(segment
		(start 66.142286 39.189025)
		(end 65.734514 39.189025)
		(width 0.12065)
		(layer "In6.Cu")
		(net "GH_PHASE1")
	)
	(segment
		(start 68.5546 36.703)
		(end 68.5546 37.6174)
		(width 0.12065)
		(layer "In6.Cu")
		(net "GH_PHASE1")
	)
	(via
		(at 29.337 14.732)
		(size 0.508)
		(drill 0.254)
		(layers "F.Cu" "B.Cu")
		(net "MH_2")
	)
	(via
		(at 33.147 10.922)
		(size 0.508)
		(drill 0.2667)
		(layers "F.Cu" "B.Cu")
		(net "MH_2")
	)
	(via
		(at 36.957 14.732)
		(size 0.508)
		(drill 0.254)
		(layers "F.Cu" "B.Cu")
		(net "MH_2")
	)
	(via
		(at 33.147 18.669)
		(size 0.508)
		(drill 0.254)
		(layers "F.Cu" "B.Cu")
		(net "MH_2")
	)
	(segment
		(start 27.686 16.3449)
		(end 28.956 15.748)
		(width 0.508)
		(layer "B.Cu")
		(net "MH_2")
	)
	(segment
		(start 73.8759 46.1391)
		(end 73.914 46.1391)
		(width 0.508)
		(layer "F.Cu")
		(net "MH_1")
	)
	(segment
		(start 73.025 46.99)
		(end 73.8759 46.1391)
		(width 0.508)
		(layer "F.Cu")
		(net "MH_1")
	)
	(via
		(at 66.929 50.8)
		(size 0.508)
		(drill 0.254)
		(layers "F.Cu" "B.Cu")
		(net "MH_1")
	)
	(via
		(at 74.422 50.673)
		(size 0.508)
		(drill 0.254)
		(layers "F.Cu" "B.Cu")
		(net "MH_1")
	)
	(via
		(at 70.612 54.737)
		(size 0.508)
		(drill 0.254)
		(layers "F.Cu" "B.Cu")
		(net "MH_1")
	)
	(via
		(at 70.612 47.3202)
		(size 0.508)
		(drill 0.2667)
		(layers "F.Cu" "B.Cu")
		(net "MH_1")
	)
	(segment
		(start 39.237006 22.041993)
		(end 38.737007 22.541992)
		(width 0.13208)
		(layer "F.Cu")
		(net "_NFP_UART_SR_TX")
	)
	(via
		(at 38.737007 22.541992)
		(size 0.4826)
		(drill 0.20574)
		(layers "F.Cu" "B.Cu")
		(net "_NFP_UART_SR_TX")
	)
	(via
		(at 24.1681 27.94)
		(size 0.762)
		(drill 0.25654)
		(layers "F.Cu" "B.Cu")
		(net "_NFP_UART_SR_TX")
	)
	(segment
		(start 34.9504 24.038941)
		(end 35.052 24.140541)
		(width 0.12065)
		(layer "In2.Cu")
		(net "_NFP_UART_SR_TX")
	)
	(segment
		(start 36.642396 24.140541)
		(end 36.896396 24.394541)
		(width 0.12065)
		(layer "In2.Cu")
		(net "_NFP_UART_SR_TX")
	)
	(segment
		(start 37.450141 24.165204)
		(end 37.450141 24.098098)
		(width 0.12065)
		(layer "In2.Cu")
		(net "_NFP_UART_SR_TX")
	)
	(segment
		(start 25.918541 25.643459)
		(end 27.188541 25.643459)
		(width 0.12065)
		(layer "In2.Cu")
		(net "_NFP_UART_SR_TX")
	)
	(segment
		(start 28.793059 24.038941)
		(end 34.9504 24.038941)
		(width 0.12065)
		(layer "In2.Cu")
		(net "_NFP_UART_SR_TX")
	)
	(segment
		(start 25.527 27.208759)
		(end 25.527 26.035)
		(width 0.12065)
		(layer "In2.Cu")
		(net "_NFP_UART_SR_TX")
	)
	(segment
		(start 37.220804 24.394541)
		(end 37.450141 24.165204)
		(width 0.12065)
		(layer "In2.Cu")
		(net "_NFP_UART_SR_TX")
	)
	(segment
		(start 25.527 26.035)
		(end 25.918541 25.643459)
		(width 0.12065)
		(layer "In2.Cu")
		(net "_NFP_UART_SR_TX")
	)
	(segment
		(start 36.896396 24.394541)
		(end 37.220804 24.394541)
		(width 0.12065)
		(layer "In2.Cu")
		(net "_NFP_UART_SR_TX")
	)
	(segment
		(start 24.1681 27.94)
		(end 24.795759 27.94)
		(width 0.12065)
		(layer "In2.Cu")
		(net "_NFP_UART_SR_TX")
	)
	(segment
		(start 27.188541 25.643459)
		(end 28.793059 24.038941)
		(width 0.12065)
		(layer "In2.Cu")
		(net "_NFP_UART_SR_TX")
	)
	(segment
		(start 24.795759 27.94)
		(end 25.527 27.208759)
		(width 0.12065)
		(layer "In2.Cu")
		(net "_NFP_UART_SR_TX")
	)
	(segment
		(start 35.052 24.140541)
		(end 36.642396 24.140541)
		(width 0.12065)
		(layer "In2.Cu")
		(net "_NFP_UART_SR_TX")
	)
	(segment
		(start 38.672008 22.541992)
		(end 38.737007 22.541992)
		(width 0.12065)
		(layer "In2.Cu")
		(net "_NFP_UART_SR_TX")
	)
	(segment
		(start 37.499925 24.048314)
		(end 37.499925 23.714075)
		(width 0.12065)
		(layer "In2.Cu")
		(net "_NFP_UART_SR_TX")
	)
	(segment
		(start 37.499925 23.714075)
		(end 38.672008 22.541992)
		(width 0.12065)
		(layer "In2.Cu")
		(net "_NFP_UART_SR_TX")
	)
	(segment
		(start 37.450141 24.098098)
		(end 37.499925 24.048314)
		(width 0.12065)
		(layer "In2.Cu")
		(net "_NFP_UART_SR_TX")
	)
	(segment
		(start 79.502 41.529)
		(end 80.137 41.529)
		(width 0.2032)
		(layer "F.Cu")
		(net "DDR_VTT")
	)
	(segment
		(start 79.121 41.91)
		(end 79.502 41.529)
		(width 0.2032)
		(layer "F.Cu")
		(net "DDR_VTT")
	)
	(via
		(at 86.487 40.386)
		(size 0.508)
		(drill 0.2667)
		(layers "F.Cu" "B.Cu")
		(net "DDR_VTT")
	)
	(via
		(at 86.487 42.672)
		(size 0.508)
		(drill 0.2667)
		(layers "F.Cu" "B.Cu")
		(net "DDR_VTT")
	)
	(via
		(at 76.962 41.656)
		(size 0.508)
		(drill 0.254)
		(layers "F.Cu" "B.Cu")
		(net "DDR_VTT")
	)
	(via
		(at 75.819 41.529)
		(size 0.762)
		(drill 0.381)
		(layers "F.Cu" "B.Cu")
		(net "DDR_VTT")
	)
	(via
		(at 86.487 41.529)
		(size 0.508)
		(drill 0.254)
		(layers "F.Cu" "B.Cu")
		(net "DDR_VTT")
	)
	(via
		(at 78.232 41.656)
		(size 0.508)
		(drill 0.254)
		(layers "F.Cu" "B.Cu")
		(net "DDR_VTT")
	)
	(via
		(at 79.121 41.91)
		(size 0.508)
		(drill 0.254)
		(layers "F.Cu" "B.Cu")
		(net "DDR_VTT")
	)
	(via
		(at 86.487 39.243)
		(size 0.508)
		(drill 0.254)
		(layers "F.Cu" "B.Cu")
		(net "DDR_VTT")
	)
	(segment
		(start 78.74 42.8879)
		(end 78.74 42.100449)
		(width 0.254)
		(layer "B.Cu")
		(net "DDR_VTT")
	)
	(segment
		(start 76.073 42.8879)
		(end 76.073 42.100449)
		(width 0.254)
		(layer "B.Cu")
		(net "DDR_VTT")
	)
	(segment
		(start 77.343 42.8879)
		(end 77.343 42.100449)
		(width 0.254)
		(layer "B.Cu")
		(net "DDR_VTT")
	)
	(segment
		(start 42.237 19.041999)
		(end 41.737001 19.541998)
		(width 0.13208)
		(layer "F.Cu")
		(net "_NFP_SPI2_SCK")
	)
	(via
		(at 41.737001 19.541998)
		(size 0.4826)
		(drill 0.20574)
		(layers "F.Cu" "B.Cu")
		(net "_NFP_SPI2_SCK")
	)
	(via
		(at 42.737024 24.541988)
		(size 0.4826)
		(drill 0.20574)
		(layers "F.Cu" "B.Cu")
		(net "_NFP_SPI2_SCK")
	)
	(segment
		(start 42.237025 25.04186)
		(end 42.237152 25.04186)
		(width 0.14732)
		(layer "B.Cu")
		(net "_NFP_SPI2_SCK")
	)
	(segment
		(start 42.237152 25.04186)
		(end 42.737024 24.541988)
		(width 0.14732)
		(layer "B.Cu")
		(net "_NFP_SPI2_SCK")
	)
	(segment
		(start 42.164 23.968964)
		(end 42.737024 24.541988)
		(width 0.12065)
		(layer "In7.Cu")
		(net "_NFP_SPI2_SCK")
	)
	(segment
		(start 41.737001 19.541998)
		(end 42.164 19.968997)
		(width 0.12065)
		(layer "In7.Cu")
		(net "_NFP_SPI2_SCK")
	)
	(segment
		(start 42.164 19.968997)
		(end 42.164 23.968964)
		(width 0.12065)
		(layer "In7.Cu")
		(net "_NFP_SPI2_SCK")
	)
	(segment
		(start 52.237005 3.042006)
		(end 52.093368 3.042006)
		(width 0.138633)
		(layer "F.Cu")
		(net "_NFP_PCIE0_PER7_P")
	)
	(segment
		(start 48.880852 0.918464)
		(end 49.089564 0.918464)
		(width 0.138633)
		(layer "F.Cu")
		(net "_NFP_PCIE0_PER7_P")
	)
	(segment
		(start 49.46777 2.245487)
		(end 48.733253 1.51097)
		(width 0.138633)
		(layer "F.Cu")
		(net "_NFP_PCIE0_PER7_P")
	)
	(segment
		(start 50.448616 1.84592)
		(end 50.040921 2.253615)
		(width 0.138633)
		(layer "F.Cu")
		(net "_NFP_PCIE0_PER7_P")
	)
	(segment
		(start 48.733253 1.066063)
		(end 48.880852 0.918464)
		(width 0.138633)
		(layer "F.Cu")
		(net "_NFP_PCIE0_PER7_P")
	)
	(segment
		(start 48.733253 1.51097)
		(end 48.733253 1.066063)
		(width 0.138633)
		(layer "F.Cu")
		(net "_NFP_PCIE0_PER7_P")
	)
	(segment
		(start 49.595583 2.32857)
		(end 49.512499 2.245487)
		(width 0.138633)
		(layer "F.Cu")
		(net "_NFP_PCIE0_PER7_P")
	)
	(segment
		(start 52.093368 3.042006)
		(end 51.945794 2.894432)
		(width 0.138633)
		(layer "F.Cu")
		(net "_NFP_PCIE0_PER7_P")
	)
	(segment
		(start 50.040921 2.260067)
		(end 49.972417 2.32857)
		(width 0.138633)
		(layer "F.Cu")
		(net "_NFP_PCIE0_PER7_P")
	)
	(segment
		(start 49.089564 0.918464)
		(end 49.403 1.2319)
		(width 0.138633)
		(layer "F.Cu")
		(net "_NFP_PCIE0_PER7_P")
	)
	(segment
		(start 49.972417 2.32857)
		(end 49.595583 2.32857)
		(width 0.138633)
		(layer "F.Cu")
		(net "_NFP_PCIE0_PER7_P")
	)
	(segment
		(start 49.512499 2.245487)
		(end 49.46777 2.245487)
		(width 0.138633)
		(layer "F.Cu")
		(net "_NFP_PCIE0_PER7_P")
	)
	(segment
		(start 51.100152 1.84592)
		(end 50.448616 1.84592)
		(width 0.138633)
		(layer "F.Cu")
		(net "_NFP_PCIE0_PER7_P")
	)
	(segment
		(start 51.945794 2.894432)
		(end 51.945794 2.691562)
		(width 0.138633)
		(layer "F.Cu")
		(net "_NFP_PCIE0_PER7_P")
	)
	(segment
		(start 50.040921 2.253615)
		(end 50.040921 2.260067)
		(width 0.138633)
		(layer "F.Cu")
		(net "_NFP_PCIE0_PER7_P")
	)
	(segment
		(start 51.945794 2.691562)
		(end 51.100152 1.84592)
		(width 0.138633)
		(layer "F.Cu")
		(net "_NFP_PCIE0_PER7_P")
	)
	(via
		(at 49.403 1.2319)
		(size 0.508)
		(drill 0.25654)
		(layers "F.Cu" "B.Cu")
		(net "_NFP_PCIE0_PER7_P")
	)
	(segment
		(start 50.99492 2.09992)
		(end 50.553849 2.09992)
		(width 0.138633)
		(layer "F.Cu")
		(net "_NFP_PCIE0_PER7_N")
	)
	(segment
		(start 49.362512 2.499487)
		(end 48.26 1.396975)
		(width 0.138633)
		(layer "F.Cu")
		(net "_NFP_PCIE0_PER7_N")
	)
	(segment
		(start 52.237005 4.042004)
		(end 52.175004 4.042004)
		(width 0.138633)
		(layer "F.Cu")
		(net "_NFP_PCIE0_PER7_N")
	)
	(segment
		(start 52.175004 4.042004)
		(end 51.691794 3.558794)
		(width 0.138633)
		(layer "F.Cu")
		(net "_NFP_PCIE0_PER7_N")
	)
	(segment
		(start 50.077649 2.58257)
		(end 49.490351 2.58257)
		(width 0.138633)
		(layer "F.Cu")
		(net "_NFP_PCIE0_PER7_N")
	)
	(segment
		(start 51.691794 2.796794)
		(end 50.99492 2.09992)
		(width 0.138633)
		(layer "F.Cu")
		(net "_NFP_PCIE0_PER7_N")
	)
	(segment
		(start 49.407267 2.499487)
		(end 49.362512 2.499487)
		(width 0.138633)
		(layer "F.Cu")
		(net "_NFP_PCIE0_PER7_N")
	)
	(segment
		(start 50.294921 2.358847)
		(end 50.294921 2.365299)
		(width 0.138633)
		(layer "F.Cu")
		(net "_NFP_PCIE0_PER7_N")
	)
	(segment
		(start 50.553849 2.09992)
		(end 50.294921 2.358847)
		(width 0.138633)
		(layer "F.Cu")
		(net "_NFP_PCIE0_PER7_N")
	)
	(segment
		(start 49.490351 2.58257)
		(end 49.407267 2.499487)
		(width 0.138633)
		(layer "F.Cu")
		(net "_NFP_PCIE0_PER7_N")
	)
	(segment
		(start 48.26 1.396975)
		(end 48.26 1.2319)
		(width 0.138633)
		(layer "F.Cu")
		(net "_NFP_PCIE0_PER7_N")
	)
	(segment
		(start 51.691794 3.558794)
		(end 51.691794 2.796794)
		(width 0.138633)
		(layer "F.Cu")
		(net "_NFP_PCIE0_PER7_N")
	)
	(segment
		(start 50.294921 2.365299)
		(end 50.077649 2.58257)
		(width 0.138633)
		(layer "F.Cu")
		(net "_NFP_PCIE0_PER7_N")
	)
	(via
		(at 48.26 1.2319)
		(size 0.508)
		(drill 0.25654)
		(layers "F.Cu" "B.Cu")
		(net "_NFP_PCIE0_PER7_N")
	)
	(segment
		(start 53.237003 4.042004)
		(end 52.737004 3.542005)
		(width 0.138633)
		(layer "F.Cu")
		(net "_NFP_PCIE0_PER6_P")
	)
	(via
		(at 51.469036 1.2319)
		(size 0.508)
		(drill 0.25654)
		(layers "F.Cu" "B.Cu")
		(net "_NFP_PCIE0_PER6_P")
	)
	(via
		(at 52.737004 3.542005)
		(size 0.4826)
		(drill 0.20574)
		(layers "F.Cu" "B.Cu")
		(net "_NFP_PCIE0_PER6_P")
	)
	(segment
		(start 52.737004 3.542005)
		(end 52.737004 3.904996)
		(width 0.106248)
		(layer "In6.Cu")
		(net "_NFP_PCIE0_PER6_P")
	)
	(segment
		(start 51.054 1.646936)
		(end 51.469036 1.2319)
		(width 0.106248)
		(layer "In6.Cu")
		(net "_NFP_PCIE0_PER6_P")
	)
	(segment
		(start 52.340891 2.707894)
		(end 51.952119 2.319122)
		(width 0.106248)
		(layer "In6.Cu")
		(net "_NFP_PCIE0_PER6_P")
	)
	(segment
		(start 51.054 1.778)
		(end 51.054 1.646936)
		(width 0.106248)
		(layer "In6.Cu")
		(net "_NFP_PCIE0_PER6_P")
	)
	(segment
		(start 52.640611 4.001389)
		(end 52.490345 4.001389)
		(width 0.106248)
		(layer "In6.Cu")
		(net "_NFP_PCIE0_PER6_P")
	)
	(segment
		(start 52.737004 3.904996)
		(end 52.640611 4.001389)
		(width 0.106248)
		(layer "In6.Cu")
		(net "_NFP_PCIE0_PER6_P")
	)
	(segment
		(start 52.490345 4.001389)
		(end 52.340891 3.851935)
		(width 0.106248)
		(layer "In6.Cu")
		(net "_NFP_PCIE0_PER6_P")
	)
	(segment
		(start 52.340891 3.851935)
		(end 52.340891 2.707894)
		(width 0.106248)
		(layer "In6.Cu")
		(net "_NFP_PCIE0_PER6_P")
	)
	(segment
		(start 51.952119 2.319122)
		(end 51.595122 2.319122)
		(width 0.106248)
		(layer "In6.Cu")
		(net "_NFP_PCIE0_PER6_P")
	)
	(segment
		(start 51.595122 2.319122)
		(end 51.054 1.778)
		(width 0.106248)
		(layer "In6.Cu")
		(net "_NFP_PCIE0_PER6_P")
	)
	(segment
		(start 53.237003 5.042002)
		(end 52.737004 4.542003)
		(width 0.138633)
		(layer "F.Cu")
		(net "_NFP_PCIE0_PER6_N")
	)
	(via
		(at 52.737004 4.542003)
		(size 0.4826)
		(drill 0.20574)
		(layers "F.Cu" "B.Cu")
		(net "_NFP_PCIE0_PER6_N")
	)
	(via
		(at 50.477039 1.2319)
		(size 0.508)
		(drill 0.25654)
		(layers "F.Cu" "B.Cu")
		(net "_NFP_PCIE0_PER6_N")
	)
	(segment
		(start 50.846152 1.601013)
		(end 50.477039 1.2319)
		(width 0.106248)
		(layer "In6.Cu")
		(net "_NFP_PCIE0_PER6_N")
	)
	(segment
		(start 51.866013 2.52697)
		(end 51.509016 2.52697)
		(width 0.106248)
		(layer "In6.Cu")
		(net "_NFP_PCIE0_PER6_N")
	)
	(segment
		(start 52.737004 4.542003)
		(end 52.133043 3.938041)
		(width 0.106248)
		(layer "In6.Cu")
		(net "_NFP_PCIE0_PER6_N")
	)
	(segment
		(start 50.846152 1.864106)
		(end 50.846152 1.601013)
		(width 0.106248)
		(layer "In6.Cu")
		(net "_NFP_PCIE0_PER6_N")
	)
	(segment
		(start 51.509016 2.52697)
		(end 50.846152 1.864106)
		(width 0.106248)
		(layer "In6.Cu")
		(net "_NFP_PCIE0_PER6_N")
	)
	(segment
		(start 52.133043 3.938041)
		(end 52.133043 2.794)
		(width 0.106248)
		(layer "In6.Cu")
		(net "_NFP_PCIE0_PER6_N")
	)
	(segment
		(start 52.133043 2.794)
		(end 51.866013 2.52697)
		(width 0.106248)
		(layer "In6.Cu")
		(net "_NFP_PCIE0_PER6_N")
	)
	(segment
		(start 53.485212 1.213688)
		(end 53.467 1.2319)
		(width 0.138633)
		(layer "F.Cu")
		(net "_NFP_PCIE0_PER5_P")
	)
	(segment
		(start 52.959 1.762785)
		(end 52.959 0.909574)
		(width 0.138633)
		(layer "F.Cu")
		(net "_NFP_PCIE0_PER5_P")
	)
	(segment
		(start 53.375687 0.797687)
		(end 53.485212 0.907212)
		(width 0.138633)
		(layer "F.Cu")
		(net "_NFP_PCIE0_PER5_P")
	)
	(segment
		(start 53.94579 2.750795)
		(end 53.94579 2.749575)
		(width 0.138633)
		(layer "F.Cu")
		(net "_NFP_PCIE0_PER5_P")
	)
	(segment
		(start 53.485212 0.907212)
		(end 53.485212 1.213688)
		(width 0.138633)
		(layer "F.Cu")
		(net "_NFP_PCIE0_PER5_P")
	)
	(segment
		(start 53.94579 2.749575)
		(end 52.959 1.762785)
		(width 0.138633)
		(layer "F.Cu")
		(net "_NFP_PCIE0_PER5_P")
	)
	(segment
		(start 52.959 0.909574)
		(end 53.070887 0.797687)
		(width 0.138633)
		(layer "F.Cu")
		(net "_NFP_PCIE0_PER5_P")
	)
	(segment
		(start 54.237001 3.042006)
		(end 53.94579 2.750795)
		(width 0.138633)
		(layer "F.Cu")
		(net "_NFP_PCIE0_PER5_P")
	)
	(segment
		(start 53.070887 0.797687)
		(end 53.375687 0.797687)
		(width 0.138633)
		(layer "F.Cu")
		(net "_NFP_PCIE0_PER5_P")
	)
	(via
		(at 53.467 1.2319)
		(size 0.508)
		(drill 0.25654)
		(layers "F.Cu" "B.Cu")
		(net "_NFP_PCIE0_PER5_P")
	)
	(segment
		(start 53.782214 2.945232)
		(end 52.705 1.868018)
		(width 0.138633)
		(layer "F.Cu")
		(net "_NFP_PCIE0_PER5_N")
	)
	(segment
		(start 52.705 1.868018)
		(end 52.705 1.45034)
		(width 0.138633)
		(layer "F.Cu")
		(net "_NFP_PCIE0_PER5_N")
	)
	(segment
		(start 52.705 1.45034)
		(end 52.48656 1.2319)
		(width 0.138633)
		(layer "F.Cu")
		(net "_NFP_PCIE0_PER5_N")
	)
	(segment
		(start 54.231896 3.680104)
		(end 53.782214 3.230423)
		(width 0.138633)
		(layer "F.Cu")
		(net "_NFP_PCIE0_PER5_N")
	)
	(segment
		(start 54.237001 4.042004)
		(end 54.232429 4.037305)
		(width 0.138633)
		(layer "F.Cu")
		(net "_NFP_PCIE0_PER5_N")
	)
	(segment
		(start 53.782214 3.230423)
		(end 53.782214 2.945232)
		(width 0.138633)
		(layer "F.Cu")
		(net "_NFP_PCIE0_PER5_N")
	)
	(segment
		(start 54.232429 4.037305)
		(end 54.231896 3.680104)
		(width 0.138633)
		(layer "F.Cu")
		(net "_NFP_PCIE0_PER5_N")
	)
	(via
		(at 52.48656 1.2319)
		(size 0.508)
		(drill 0.25654)
		(layers "F.Cu" "B.Cu")
		(net "_NFP_PCIE0_PER5_N")
	)
	(segment
		(start 54.737 3.542005)
		(end 55.236999 4.042004)
		(width 0.138633)
		(layer "F.Cu")
		(net "_NFP_PCIE0_PER4_P")
	)
	(via
		(at 54.483 1.2319)
		(size 0.508)
		(drill 0.25654)
		(layers "F.Cu" "B.Cu")
		(net "_NFP_PCIE0_PER4_P")
	)
	(via
		(at 54.737 3.542005)
		(size 0.4826)
		(drill 0.20574)
		(layers "F.Cu" "B.Cu")
		(net "_NFP_PCIE0_PER4_P")
	)
	(segment
		(start 54.864 1.905)
		(end 54.864 1.6129)
		(width 0.106248)
		(layer "In6.Cu")
		(net "_NFP_PCIE0_PER4_P")
	)
	(segment
		(start 54.939133 3.988867)
		(end 55.133113 3.794887)
		(width 0.106248)
		(layer "In6.Cu")
		(net "_NFP_PCIE0_PER4_P")
	)
	(segment
		(start 54.864 1.6129)
		(end 54.483 1.2319)
		(width 0.106248)
		(layer "In6.Cu")
		(net "_NFP_PCIE0_PER4_P")
	)
	(segment
		(start 54.713708 3.565296)
		(end 54.713708 3.913708)
		(width 0.106248)
		(layer "In6.Cu")
		(net "_NFP_PCIE0_PER4_P")
	)
	(segment
		(start 55.133113 2.174113)
		(end 54.864 1.905)
		(width 0.106248)
		(layer "In6.Cu")
		(net "_NFP_PCIE0_PER4_P")
	)
	(segment
		(start 54.737 3.542005)
		(end 54.713708 3.565296)
		(width 0.106248)
		(layer "In6.Cu")
		(net "_NFP_PCIE0_PER4_P")
	)
	(segment
		(start 55.133113 3.794887)
		(end 55.133113 2.174113)
		(width 0.106248)
		(layer "In6.Cu")
		(net "_NFP_PCIE0_PER4_P")
	)
	(segment
		(start 54.713708 3.913708)
		(end 54.788867 3.988867)
		(width 0.106248)
		(layer "In6.Cu")
		(net "_NFP_PCIE0_PER4_P")
	)
	(segment
		(start 54.788867 3.988867)
		(end 54.939133 3.988867)
		(width 0.106248)
		(layer "In6.Cu")
		(net "_NFP_PCIE0_PER4_P")
	)
	(segment
		(start 54.737 4.542003)
		(end 55.236999 5.042002)
		(width 0.138633)
		(layer "F.Cu")
		(net "_NFP_PCIE0_PER4_N")
	)
	(via
		(at 55.437024 1.2319)
		(size 0.508)
		(drill 0.25654)
		(layers "F.Cu" "B.Cu")
		(net "_NFP_PCIE0_PER4_N")
	)
	(via
		(at 54.737 4.542003)
		(size 0.4826)
		(drill 0.25654)
		(layers "F.Cu" "B.Cu")
		(net "_NFP_PCIE0_PER4_N")
	)
	(segment
		(start 55.340961 2.088007)
		(end 55.071848 1.818894)
		(width 0.106248)
		(layer "In6.Cu")
		(net "_NFP_PCIE0_PER4_N")
	)
	(segment
		(start 55.340961 3.938041)
		(end 55.340961 2.088007)
		(width 0.106248)
		(layer "In6.Cu")
		(net "_NFP_PCIE0_PER4_N")
	)
	(segment
		(start 55.071848 1.597076)
		(end 55.437024 1.2319)
		(width 0.106248)
		(layer "In6.Cu")
		(net "_NFP_PCIE0_PER4_N")
	)
	(segment
		(start 54.737 4.542003)
		(end 55.340961 3.938041)
		(width 0.106248)
		(layer "In6.Cu")
		(net "_NFP_PCIE0_PER4_N")
	)
	(segment
		(start 55.071848 1.818894)
		(end 55.071848 1.597076)
		(width 0.106248)
		(layer "In6.Cu")
		(net "_NFP_PCIE0_PER4_N")
	)
	(segment
		(start 57.277 1.1049)
		(end 57.404 1.2319)
		(width 0.138633)
		(layer "F.Cu")
		(net "_NFP_PCIE0_PER3_P")
	)
	(segment
		(start 56.576417 1.686687)
		(end 56.842787 1.420317)
		(width 0.138633)
		(layer "F.Cu")
		(net "_NFP_PCIE0_PER3_P")
	)
	(segment
		(start 56.236997 2.994787)
		(end 56.03621 2.794)
		(width 0.138633)
		(layer "F.Cu")
		(net "_NFP_PCIE0_PER3_P")
	)
	(segment
		(start 56.292445 1.686687)
		(end 56.576417 1.686687)
		(width 0.138633)
		(layer "F.Cu")
		(net "_NFP_PCIE0_PER3_P")
	)
	(segment
		(start 56.982157 0.929843)
		(end 57.190843 0.929843)
		(width 0.138633)
		(layer "F.Cu")
		(net "_NFP_PCIE0_PER3_P")
	)
	(segment
		(start 56.842787 1.420317)
		(end 56.842787 1.069213)
		(width 0.138633)
		(layer "F.Cu")
		(net "_NFP_PCIE0_PER3_P")
	)
	(segment
		(start 56.236997 3.042006)
		(end 56.236997 2.994787)
		(width 0.138633)
		(layer "F.Cu")
		(net "_NFP_PCIE0_PER3_P")
	)
	(segment
		(start 56.03621 1.942922)
		(end 56.292445 1.686687)
		(width 0.138633)
		(layer "F.Cu")
		(net "_NFP_PCIE0_PER3_P")
	)
	(segment
		(start 57.190843 0.929843)
		(end 57.277 1.016)
		(width 0.138633)
		(layer "F.Cu")
		(net "_NFP_PCIE0_PER3_P")
	)
	(segment
		(start 56.03621 2.794)
		(end 56.03621 1.942922)
		(width 0.138633)
		(layer "F.Cu")
		(net "_NFP_PCIE0_PER3_P")
	)
	(segment
		(start 56.842787 1.069213)
		(end 56.982157 0.929843)
		(width 0.138633)
		(layer "F.Cu")
		(net "_NFP_PCIE0_PER3_P")
	)
	(segment
		(start 57.277 1.016)
		(end 57.277 1.1049)
		(width 0.138633)
		(layer "F.Cu")
		(net "_NFP_PCIE0_PER3_P")
	)
	(via
		(at 57.404 1.2319)
		(size 0.508)
		(drill 0.25654)
		(layers "F.Cu" "B.Cu")
		(net "_NFP_PCIE0_PER3_P")
	)
	(segment
		(start 56.112816 1.507058)
		(end 56.388 1.2319)
		(width 0.138633)
		(layer "F.Cu")
		(net "_NFP_PCIE0_PER3_N")
	)
	(segment
		(start 56.236997 4.042004)
		(end 56.236997 3.68521)
		(width 0.138633)
		(layer "F.Cu")
		(net "_NFP_PCIE0_PER3_N")
	)
	(segment
		(start 55.78221 1.83769)
		(end 56.112816 1.507058)
		(width 0.138633)
		(layer "F.Cu")
		(net "_NFP_PCIE0_PER3_N")
	)
	(segment
		(start 56.236997 3.68521)
		(end 55.78221 3.230423)
		(width 0.138633)
		(layer "F.Cu")
		(net "_NFP_PCIE0_PER3_N")
	)
	(segment
		(start 55.78221 3.230423)
		(end 55.78221 1.83769)
		(width 0.138633)
		(layer "F.Cu")
		(net "_NFP_PCIE0_PER3_N")
	)
	(via
		(at 56.388 1.2319)
		(size 0.508)
		(drill 0.25654)
		(layers "F.Cu" "B.Cu")
		(net "_NFP_PCIE0_PER3_N")
	)
	(segment
		(start 56.736996 3.542005)
		(end 57.236995 4.042004)
		(width 0.138633)
		(layer "F.Cu")
		(net "_NFP_PCIE0_PER2_P")
	)
	(via
		(at 59.373008 1.2319)
		(size 0.508)
		(drill 0.25654)
		(layers "F.Cu" "B.Cu")
		(net "_NFP_PCIE0_PER2_P")
	)
	(via
		(at 56.736996 3.542005)
		(size 0.4826)
		(drill 0.20574)
		(layers "F.Cu" "B.Cu")
		(net "_NFP_PCIE0_PER2_P")
	)
	(segment
		(start 58.498511 2.032025)
		(end 58.494397 2.027911)
		(width 0.110185)
		(layer "In6.Cu")
		(net "_NFP_PCIE0_PER2_P")
	)
	(segment
		(start 56.877712 2.022958)
		(end 56.870625 2.015871)
		(width 0.106248)
		(layer "In6.Cu")
		(net "_NFP_PCIE0_PER2_P")
	)
	(segment
		(start 59.373008 1.2319)
		(end 59.110474 1.2319)
		(width 0.110185)
		(layer "In6.Cu")
		(net "_NFP_PCIE0_PER2_P")
	)
	(segment
		(start 56.504281 4.015334)
		(end 56.640603 4.015334)
		(width 0.106248)
		(layer "In6.Cu")
		(net "_NFP_PCIE0_PER2_P")
	)
	(segment
		(start 56.340883 2.206117)
		(end 56.340883 3.851935)
		(width 0.106248)
		(layer "In6.Cu")
		(net "_NFP_PCIE0_PER2_P")
	)
	(segment
		(start 57.010325 2.027911)
		(end 56.985764 2.027911)
		(width 0.106248)
		(layer "In6.Cu")
		(net "_NFP_PCIE0_PER2_P")
	)
	(segment
		(start 56.983757 2.025904)
		(end 56.923407 2.025904)
		(width 0.106248)
		(layer "In6.Cu")
		(net "_NFP_PCIE0_PER2_P")
	)
	(segment
		(start 56.340883 3.851935)
		(end 56.504281 4.015334)
		(width 0.106248)
		(layer "In6.Cu")
		(net "_NFP_PCIE0_PER2_P")
	)
	(segment
		(start 58.673975 2.032025)
		(end 58.498511 2.032025)
		(width 0.110185)
		(layer "In6.Cu")
		(net "_NFP_PCIE0_PER2_P")
	)
	(segment
		(start 56.736996 3.918941)
		(end 56.736996 3.542005)
		(width 0.106248)
		(layer "In6.Cu")
		(net "_NFP_PCIE0_PER2_P")
	)
	(segment
		(start 56.531129 2.015871)
		(end 56.340883 2.206117)
		(width 0.106248)
		(layer "In6.Cu")
		(net "_NFP_PCIE0_PER2_P")
	)
	(segment
		(start 58.494397 2.027911)
		(end 57.010325 2.027911)
		(width 0.110185)
		(layer "In6.Cu")
		(net "_NFP_PCIE0_PER2_P")
	)
	(segment
		(start 58.990052 1.352321)
		(end 58.990052 1.715948)
		(width 0.110185)
		(layer "In6.Cu")
		(net "_NFP_PCIE0_PER2_P")
	)
	(segment
		(start 56.923407 2.025904)
		(end 56.92046 2.022958)
		(width 0.106248)
		(layer "In6.Cu")
		(net "_NFP_PCIE0_PER2_P")
	)
	(segment
		(start 56.640603 4.015334)
		(end 56.736996 3.918941)
		(width 0.106248)
		(layer "In6.Cu")
		(net "_NFP_PCIE0_PER2_P")
	)
	(segment
		(start 56.92046 2.022958)
		(end 56.877712 2.022958)
		(width 0.106248)
		(layer "In6.Cu")
		(net "_NFP_PCIE0_PER2_P")
	)
	(segment
		(start 56.985764 2.027911)
		(end 56.983757 2.025904)
		(width 0.106248)
		(layer "In6.Cu")
		(net "_NFP_PCIE0_PER2_P")
	)
	(segment
		(start 59.110474 1.2319)
		(end 58.990052 1.352321)
		(width 0.110185)
		(layer "In6.Cu")
		(net "_NFP_PCIE0_PER2_P")
	)
	(segment
		(start 58.990052 1.715948)
		(end 58.673975 2.032025)
		(width 0.110185)
		(layer "In6.Cu")
		(net "_NFP_PCIE0_PER2_P")
	)
	(segment
		(start 56.870625 2.015871)
		(end 56.531129 2.015871)
		(width 0.106248)
		(layer "In6.Cu")
		(net "_NFP_PCIE0_PER2_P")
	)
	(segment
		(start 56.736996 4.542003)
		(end 57.236995 5.042002)
		(width 0.138633)
		(layer "F.Cu")
		(net "_NFP_PCIE0_PER2_N")
	)
	(via
		(at 56.736996 4.542003)
		(size 0.4826)
		(drill 0.20574)
		(layers "F.Cu" "B.Cu")
		(net "_NFP_PCIE0_PER2_N")
	)
	(via
		(at 58.389012 1.2319)
		(size 0.508)
		(drill 0.25654)
		(layers "F.Cu" "B.Cu")
		(net "_NFP_PCIE0_PER2_N")
	)
	(segment
		(start 57.010325 1.816075)
		(end 57.00936 1.815109)
		(width 0.106248)
		(layer "In6.Cu")
		(net "_NFP_PCIE0_PER2_N")
	)
	(segment
		(start 58.657795 1.2319)
		(end 58.778216 1.352321)
		(width 0.110185)
		(layer "In6.Cu")
		(net "_NFP_PCIE0_PER2_N")
	)
	(segment
		(start 56.619064 1.807896)
		(end 56.442356 1.807896)
		(width 0.106248)
		(layer "In6.Cu")
		(net "_NFP_PCIE0_PER2_N")
	)
	(segment
		(start 57.00936 1.815109)
		(end 56.963818 1.815109)
		(width 0.106248)
		(layer "In6.Cu")
		(net "_NFP_PCIE0_PER2_N")
	)
	(segment
		(start 56.442356 1.807896)
		(end 56.285155 1.965096)
		(width 0.106248)
		(layer "In6.Cu")
		(net "_NFP_PCIE0_PER2_N")
	)
	(segment
		(start 56.956731 1.808023)
		(end 56.619191 1.808023)
		(width 0.106248)
		(layer "In6.Cu")
		(net "_NFP_PCIE0_PER2_N")
	)
	(segment
		(start 56.285155 1.965096)
		(end 56.285155 1.96789)
		(width 0.106248)
		(layer "In6.Cu")
		(net "_NFP_PCIE0_PER2_N")
	)
	(segment
		(start 58.778216 1.628191)
		(end 58.590332 1.816075)
		(width 0.110185)
		(layer "In6.Cu")
		(net "_NFP_PCIE0_PER2_N")
	)
	(segment
		(start 56.133035 2.120011)
		(end 56.133035 3.938041)
		(width 0.106248)
		(layer "In6.Cu")
		(net "_NFP_PCIE0_PER2_N")
	)
	(segment
		(start 56.619191 1.808023)
		(end 56.619064 1.807896)
		(width 0.106248)
		(layer "In6.Cu")
		(net "_NFP_PCIE0_PER2_N")
	)
	(segment
		(start 56.285155 1.96789)
		(end 56.133035 2.120011)
		(width 0.106248)
		(layer "In6.Cu")
		(net "_NFP_PCIE0_PER2_N")
	)
	(segment
		(start 58.389012 1.2319)
		(end 58.657795 1.2319)
		(width 0.110185)
		(layer "In6.Cu")
		(net "_NFP_PCIE0_PER2_N")
	)
	(segment
		(start 58.778216 1.352321)
		(end 58.778216 1.628191)
		(width 0.110185)
		(layer "In6.Cu")
		(net "_NFP_PCIE0_PER2_N")
	)
	(segment
		(start 56.133035 3.938041)
		(end 56.736996 4.542003)
		(width 0.106248)
		(layer "In6.Cu")
		(net "_NFP_PCIE0_PER2_N")
	)
	(segment
		(start 56.963818 1.815109)
		(end 56.956731 1.808023)
		(width 0.106248)
		(layer "In6.Cu")
		(net "_NFP_PCIE0_PER2_N")
	)
	(segment
		(start 58.590332 1.816075)
		(end 57.010325 1.816075)
		(width 0.110185)
		(layer "In6.Cu")
		(net "_NFP_PCIE0_PER2_N")
	)
	(segment
		(start 58.73308 2.09992)
		(end 59.194598 2.09992)
		(width 0.138633)
		(layer "F.Cu")
		(net "_NFP_PCIE0_PER1_P")
	)
	(segment
		(start 59.194598 2.09992)
		(end 59.448598 1.84592)
		(width 0.138633)
		(layer "F.Cu")
		(net "_NFP_PCIE0_PER1_P")
	)
	(segment
		(start 58.236993 3.042006)
		(end 58.236993 2.596007)
		(width 0.138633)
		(layer "F.Cu")
		(net "_NFP_PCIE0_PER1_P")
	)
	(segment
		(start 60.619843 0.802843)
		(end 60.411157 0.802843)
		(width 0.138633)
		(layer "F.Cu")
		(net "_NFP_PCIE0_PER1_P")
	)
	(segment
		(start 60.706965 1.84592)
		(end 60.854539 1.698346)
		(width 0.138633)
		(layer "F.Cu")
		(net "_NFP_PCIE0_PER1_P")
	)
	(segment
		(start 60.854539 1.698346)
		(end 60.854539 1.515643)
		(width 0.138633)
		(layer "F.Cu")
		(net "_NFP_PCIE0_PER1_P")
	)
	(segment
		(start 60.306788 0.907212)
		(end 60.306788 1.213688)
		(width 0.138633)
		(layer "F.Cu")
		(net "_NFP_PCIE0_PER1_P")
	)
	(segment
		(start 60.854539 1.515643)
		(end 60.759213 1.420317)
		(width 0.138633)
		(layer "F.Cu")
		(net "_NFP_PCIE0_PER1_P")
	)
	(segment
		(start 60.759213 1.420317)
		(end 60.759213 0.942213)
		(width 0.138633)
		(layer "F.Cu")
		(net "_NFP_PCIE0_PER1_P")
	)
	(segment
		(start 60.759213 0.942213)
		(end 60.619843 0.802843)
		(width 0.138633)
		(layer "F.Cu")
		(net "_NFP_PCIE0_PER1_P")
	)
	(segment
		(start 59.448598 1.84592)
		(end 60.706965 1.84592)
		(width 0.138633)
		(layer "F.Cu")
		(net "_NFP_PCIE0_PER1_P")
	)
	(segment
		(start 60.306788 1.213688)
		(end 60.304426 1.2319)
		(width 0.138633)
		(layer "F.Cu")
		(net "_NFP_PCIE0_PER1_P")
	)
	(segment
		(start 60.411157 0.802843)
		(end 60.306788 0.907212)
		(width 0.138633)
		(layer "F.Cu")
		(net "_NFP_PCIE0_PER1_P")
	)
	(segment
		(start 58.236993 2.596007)
		(end 58.73308 2.09992)
		(width 0.138633)
		(layer "F.Cu")
		(net "_NFP_PCIE0_PER1_P")
	)
	(via
		(at 60.304426 1.2319)
		(size 0.508)
		(drill 0.25654)
		(layers "F.Cu" "B.Cu")
		(net "_NFP_PCIE0_PER1_P")
	)
	(segment
		(start 61.214 1.777975)
		(end 61.214 1.2319)
		(width 0.138633)
		(layer "F.Cu")
		(net "_NFP_PCIE0_PER1_N")
	)
	(segment
		(start 58.236993 4.042004)
		(end 58.69178 3.587217)
		(width 0.138633)
		(layer "F.Cu")
		(net "_NFP_PCIE0_PER1_N")
	)
	(segment
		(start 58.69178 2.500452)
		(end 58.838313 2.35392)
		(width 0.138633)
		(layer "F.Cu")
		(net "_NFP_PCIE0_PER1_N")
	)
	(segment
		(start 59.299831 2.35392)
		(end 59.553831 2.09992)
		(width 0.138633)
		(layer "F.Cu")
		(net "_NFP_PCIE0_PER1_N")
	)
	(segment
		(start 60.892055 2.09992)
		(end 61.214 1.777975)
		(width 0.138633)
		(layer "F.Cu")
		(net "_NFP_PCIE0_PER1_N")
	)
	(segment
		(start 58.69178 3.587217)
		(end 58.69178 2.500452)
		(width 0.138633)
		(layer "F.Cu")
		(net "_NFP_PCIE0_PER1_N")
	)
	(segment
		(start 59.553831 2.09992)
		(end 60.892055 2.09992)
		(width 0.138633)
		(layer "F.Cu")
		(net "_NFP_PCIE0_PER1_N")
	)
	(segment
		(start 58.838313 2.35392)
		(end 59.299831 2.35392)
		(width 0.138633)
		(layer "F.Cu")
		(net "_NFP_PCIE0_PER1_N")
	)
	(via
		(at 61.214 1.2319)
		(size 0.508)
		(drill 0.25654)
		(layers "F.Cu" "B.Cu")
		(net "_NFP_PCIE0_PER1_N")
	)
	(segment
		(start 59.73699 3.542005)
		(end 59.236991 4.042004)
		(width 0.138633)
		(layer "F.Cu")
		(net "_NFP_PCIE0_PER0_P")
	)
	(via
		(at 62.221999 1.2319)
		(size 0.508)
		(drill 0.25654)
		(layers "F.Cu" "B.Cu")
		(net "_NFP_PCIE0_PER0_P")
	)
	(via
		(at 59.73699 3.542005)
		(size 0.4826)
		(drill 0.20574)
		(layers "F.Cu" "B.Cu")
		(net "_NFP_PCIE0_PER0_P")
	)
	(segment
		(start 59.73699 3.729965)
		(end 59.943111 3.936086)
		(width 0.110185)
		(layer "In6.Cu")
		(net "_NFP_PCIE0_PER0_P")
	)
	(segment
		(start 60.482226 3.927069)
		(end 61.731931 3.927069)
		(width 0.110185)
		(layer "In6.Cu")
		(net "_NFP_PCIE0_PER0_P")
	)
	(segment
		(start 59.943111 3.936086)
		(end 60.473209 3.936086)
		(width 0.110185)
		(layer "In6.Cu")
		(net "_NFP_PCIE0_PER0_P")
	)
	(segment
		(start 62.865 2.794)
		(end 62.865 1.848307)
		(width 0.110185)
		(layer "In6.Cu")
		(net "_NFP_PCIE0_PER0_P")
	)
	(segment
		(start 62.717985 1.727911)
		(end 62.221999 1.2319)
		(width 0.110185)
		(layer "In6.Cu")
		(net "_NFP_PCIE0_PER0_P")
	)
	(segment
		(start 59.73699 3.542005)
		(end 59.73699 3.729965)
		(width 0.110185)
		(layer "In6.Cu")
		(net "_NFP_PCIE0_PER0_P")
	)
	(segment
		(start 62.865 1.848307)
		(end 62.744604 1.727911)
		(width 0.110185)
		(layer "In6.Cu")
		(net "_NFP_PCIE0_PER0_P")
	)
	(segment
		(start 60.473209 3.936086)
		(end 60.482226 3.927069)
		(width 0.110185)
		(layer "In6.Cu")
		(net "_NFP_PCIE0_PER0_P")
	)
	(segment
		(start 62.744604 1.727911)
		(end 62.717985 1.727911)
		(width 0.110185)
		(layer "In6.Cu")
		(net "_NFP_PCIE0_PER0_P")
	)
	(segment
		(start 61.731931 3.927069)
		(end 62.865 2.794)
		(width 0.110185)
		(layer "In6.Cu")
		(net "_NFP_PCIE0_PER0_P")
	)
	(segment
		(start 59.73699 4.542003)
		(end 59.236991 5.042002)
		(width 0.138633)
		(layer "F.Cu")
		(net "_NFP_PCIE0_PER0_N")
	)
	(via
		(at 59.73699 4.542003)
		(size 0.4826)
		(drill 0.25654)
		(layers "F.Cu" "B.Cu")
		(net "_NFP_PCIE0_PER0_N")
	)
	(via
		(at 63.213996 1.2319)
		(size 0.508)
		(drill 0.25654)
		(layers "F.Cu" "B.Cu")
		(net "_NFP_PCIE0_PER0_N")
	)
	(segment
		(start 60.131071 4.147922)
		(end 60.560966 4.147922)
		(width 0.110185)
		(layer "In6.Cu")
		(net "_NFP_PCIE0_PER0_N")
	)
	(segment
		(start 59.73699 4.542003)
		(end 60.131071 4.147922)
		(width 0.110185)
		(layer "In6.Cu")
		(net "_NFP_PCIE0_PER0_N")
	)
	(segment
		(start 63.076836 1.36906)
		(end 63.213996 1.2319)
		(width 0.110185)
		(layer "In6.Cu")
		(net "_NFP_PCIE0_PER0_N")
	)
	(segment
		(start 60.569983 4.138905)
		(end 61.819688 4.138905)
		(width 0.110185)
		(layer "In6.Cu")
		(net "_NFP_PCIE0_PER0_N")
	)
	(segment
		(start 60.560966 4.147922)
		(end 60.569983 4.138905)
		(width 0.110185)
		(layer "In6.Cu")
		(net "_NFP_PCIE0_PER0_N")
	)
	(segment
		(start 63.076836 2.881757)
		(end 63.076836 1.36906)
		(width 0.110185)
		(layer "In6.Cu")
		(net "_NFP_PCIE0_PER0_N")
	)
	(segment
		(start 61.819688 4.138905)
		(end 63.076836 2.881757)
		(width 0.110185)
		(layer "In6.Cu")
		(net "_NFP_PCIE0_PER0_N")
	)
	(segment
		(start 41.237002 15.042007)
		(end 40.737003 14.542008)
		(width 0.13208)
		(layer "F.Cu")
		(net "_NFP_JTAG_ARM_TDO")
	)
	(via
		(at 27.4701 13.97)
		(size 0.508)
		(drill 0.2667)
		(layers "F.Cu" "B.Cu")
		(net "_NFP_JTAG_ARM_TDO")
	)
	(via
		(at 40.737003 14.542008)
		(size 0.4826)
		(drill 0.20574)
		(layers "F.Cu" "B.Cu")
		(net "_NFP_JTAG_ARM_TDO")
	)
	(segment
		(start 31.242 11.557)
		(end 31.399759 11.557)
		(width 0.12065)
		(layer "In3.Cu")
		(net "_NFP_JTAG_ARM_TDO")
	)
	(segment
		(start 40.259 14.986)
		(end 40.702992 14.542008)
		(width 0.12065)
		(layer "In3.Cu")
		(net "_NFP_JTAG_ARM_TDO")
	)
	(segment
		(start 37.973 14.986)
		(end 40.259 14.986)
		(width 0.12065)
		(layer "In3.Cu")
		(net "_NFP_JTAG_ARM_TDO")
	)
	(segment
		(start 40.702992 14.542008)
		(end 40.737003 14.542008)
		(width 0.12065)
		(layer "In3.Cu")
		(net "_NFP_JTAG_ARM_TDO")
	)
	(segment
		(start 28.829 13.97)
		(end 31.242 11.557)
		(width 0.12065)
		(layer "In3.Cu")
		(net "_NFP_JTAG_ARM_TDO")
	)
	(segment
		(start 34.519591 11.43635)
		(end 36.763376 13.680135)
		(width 0.12065)
		(layer "In3.Cu")
		(net "_NFP_JTAG_ARM_TDO")
	)
	(segment
		(start 27.4701 13.97)
		(end 28.829 13.97)
		(width 0.12065)
		(layer "In3.Cu")
		(net "_NFP_JTAG_ARM_TDO")
	)
	(segment
		(start 36.763376 13.680135)
		(end 36.763376 13.776376)
		(width 0.12065)
		(layer "In3.Cu")
		(net "_NFP_JTAG_ARM_TDO")
	)
	(segment
		(start 31.399759 11.557)
		(end 31.520409 11.43635)
		(width 0.12065)
		(layer "In3.Cu")
		(net "_NFP_JTAG_ARM_TDO")
	)
	(segment
		(start 36.763376 13.776376)
		(end 37.973 14.986)
		(width 0.12065)
		(layer "In3.Cu")
		(net "_NFP_JTAG_ARM_TDO")
	)
	(segment
		(start 31.520409 11.43635)
		(end 34.519591 11.43635)
		(width 0.12065)
		(layer "In3.Cu")
		(net "_NFP_JTAG_ARM_TDO")
	)
	(segment
		(start 35.56 33.782)
		(end 34.417 34.925)
		(width 0.14732)
		(layer "F.Cu")
		(net "_NFP_CORE_VID7")
	)
	(segment
		(start 36.322 33.0581)
		(end 36.322 33.02)
		(width 0.14732)
		(layer "F.Cu")
		(net "_NFP_CORE_VID7")
	)
	(segment
		(start 33.365008 35.07232)
		(end 33.365008 35.1536)
		(width 0.14732)
		(layer "F.Cu")
		(net "_NFP_CORE_VID7")
	)
	(segment
		(start 36.322 33.02)
		(end 35.56 33.782)
		(width 0.14732)
		(layer "F.Cu")
		(net "_NFP_CORE_VID7")
	)
	(segment
		(start 33.512328 34.925)
		(end 33.365008 35.07232)
		(width 0.14732)
		(layer "F.Cu")
		(net "_NFP_CORE_VID7")
	)
	(segment
		(start 34.417 34.925)
		(end 33.512328 34.925)
		(width 0.14732)
		(layer "F.Cu")
		(net "_NFP_CORE_VID7")
	)
	(via
		(at 35.56 34.671)
		(size 0.762)
		(drill 0.381)
		(layers "F.Cu" "B.Cu")
		(net "_NFP_CORE_VID7")
	)
	(via
		(at 35.56 33.782)
		(size 0.508)
		(drill 0.254)
		(layers "F.Cu" "B.Cu")
		(net "_NFP_CORE_VID7")
	)
	(segment
		(start 35.56 33.782)
		(end 35.56 34.671)
		(width 0.14732)
		(layer "B.Cu")
		(net "_NFP_CORE_VID7")
	)
	(segment
		(start 35.7759 33.782)
		(end 35.56 33.782)
		(width 0.14732)
		(layer "B.Cu")
		(net "_NFP_CORE_VID7")
	)
	(segment
		(start 35.433 33.0581)
		(end 35.56 33.782)
		(width 0.14732)
		(layer "B.Cu")
		(net "_NFP_CORE_VID7")
	)
	(segment
		(start 36.3347 33.274)
		(end 35.7759 33.782)
		(width 0.14732)
		(layer "B.Cu")
		(net "_NFP_CORE_VID7")
	)
	(segment
		(start 34.544 34.036)
		(end 34.036 34.544)
		(width 0.14732)
		(layer "F.Cu")
		(net "_NFP_CORE_VID6")
	)
	(segment
		(start 33.837067 34.544)
		(end 33.034986 34.544)
		(width 0.14732)
		(layer "F.Cu")
		(net "_NFP_CORE_VID6")
	)
	(segment
		(start 34.544 33.0581)
		(end 35.433 33.0581)
		(width 0.14732)
		(layer "F.Cu")
		(net "_NFP_CORE_VID6")
	)
	(segment
		(start 32.865009 34.713977)
		(end 32.865009 35.1536)
		(width 0.14732)
		(layer "F.Cu")
		(net "_NFP_CORE_VID6")
	)
	(segment
		(start 34.544 34.036)
		(end 34.544 33.0581)
		(width 0.14732)
		(layer "F.Cu")
		(net "_NFP_CORE_VID6")
	)
	(segment
		(start 33.034986 34.544)
		(end 32.865009 34.713977)
		(width 0.14732)
		(layer "F.Cu")
		(net "_NFP_CORE_VID6")
	)
	(segment
		(start 34.036 34.544)
		(end 33.837067 34.544)
		(width 0.14732)
		(layer "F.Cu")
		(net "_NFP_CORE_VID6")
	)
	(via
		(at 34.544 34.036)
		(size 0.508)
		(drill 0.2667)
		(layers "F.Cu" "B.Cu")
		(net "_NFP_CORE_VID6")
	)
	(segment
		(start 34.544 33.0581)
		(end 34.544 34.036)
		(width 0.14732)
		(layer "B.Cu")
		(net "_NFP_CORE_VID6")
	)
	(segment
		(start 32.700366 34.49066)
		(end 32.639 34.49066)
		(width 0.14732)
		(layer "F.Cu")
		(net "_NFP_CORE_VID5")
	)
	(segment
		(start 33.655 33.909)
		(end 33.528 34.036)
		(width 0.14732)
		(layer "F.Cu")
		(net "_NFP_CORE_VID5")
	)
	(segment
		(start 32.36501 34.76465)
		(end 32.36501 35.1536)
		(width 0.14732)
		(layer "F.Cu")
		(net "_NFP_CORE_VID5")
	)
	(segment
		(start 33.655 33.0581)
		(end 33.655 33.909)
		(width 0.14732)
		(layer "F.Cu")
		(net "_NFP_CORE_VID5")
	)
	(segment
		(start 33.528 34.036)
		(end 33.155026 34.036)
		(width 0.14732)
		(layer "F.Cu")
		(net "_NFP_CORE_VID5")
	)
	(segment
		(start 33.155026 34.036)
		(end 32.700366 34.49066)
		(width 0.14732)
		(layer "F.Cu")
		(net "_NFP_CORE_VID5")
	)
	(segment
		(start 32.639 34.49066)
		(end 32.36501 34.76465)
		(width 0.14732)
		(layer "F.Cu")
		(net "_NFP_CORE_VID5")
	)
	(via
		(at 33.528 34.036)
		(size 0.508)
		(drill 0.2667)
		(layers "F.Cu" "B.Cu")
		(net "_NFP_CORE_VID5")
	)
	(segment
		(start 33.528 34.036)
		(end 33.655 33.655)
		(width 0.14732)
		(layer "B.Cu")
		(net "_NFP_CORE_VID5")
	)
	(segment
		(start 33.655 33.0581)
		(end 32.766 33.0581)
		(width 0.14732)
		(layer "B.Cu")
		(net "_NFP_CORE_VID5")
	)
	(segment
		(start 33.655 33.655)
		(end 33.655 33.0581)
		(width 0.14732)
		(layer "B.Cu")
		(net "_NFP_CORE_VID5")
	)
	(segment
		(start 31.865011 35.1536)
		(end 31.865011 34.619489)
		(width 0.14732)
		(layer "F.Cu")
		(net "_NFP_CORE_VID4")
	)
	(segment
		(start 32.35833 33.799348)
		(end 32.213982 33.655)
		(width 0.14732)
		(layer "F.Cu")
		(net "_NFP_CORE_VID4")
	)
	(segment
		(start 31.865011 34.301989)
		(end 31.865011 34.619489)
		(width 0.14732)
		(layer "F.Cu")
		(net "_NFP_CORE_VID4")
	)
	(segment
		(start 31.877 33.528)
		(end 31.877 33.0581)
		(width 0.14732)
		(layer "F.Cu")
		(net "_NFP_CORE_VID4")
	)
	(segment
		(start 32.512 34.036)
		(end 32.35833 33.799348)
		(width 0.14732)
		(layer "F.Cu")
		(net "_NFP_CORE_VID4")
	)
	(segment
		(start 32.004 33.655)
		(end 31.877 33.528)
		(width 0.14732)
		(layer "F.Cu")
		(net "_NFP_CORE_VID4")
	)
	(segment
		(start 32.413753 34.134247)
		(end 32.032753 34.134247)
		(width 0.14732)
		(layer "F.Cu")
		(net "_NFP_CORE_VID4")
	)
	(segment
		(start 32.032753 34.134247)
		(end 31.865011 34.301989)
		(width 0.14732)
		(layer "F.Cu")
		(net "_NFP_CORE_VID4")
	)
	(segment
		(start 31.877 33.0581)
		(end 32.766 33.0581)
		(width 0.14732)
		(layer "F.Cu")
		(net "_NFP_CORE_VID4")
	)
	(segment
		(start 32.213982 33.655)
		(end 32.004 33.655)
		(width 0.14732)
		(layer "F.Cu")
		(net "_NFP_CORE_VID4")
	)
	(segment
		(start 32.512 34.036)
		(end 32.413753 34.134247)
		(width 0.14732)
		(layer "F.Cu")
		(net "_NFP_CORE_VID4")
	)
	(via
		(at 32.512 34.036)
		(size 0.508)
		(drill 0.2667)
		(layers "F.Cu" "B.Cu")
		(net "_NFP_CORE_VID4")
	)
	(segment
		(start 31.877 33.0581)
		(end 32.512 34.036)
		(width 0.14732)
		(layer "B.Cu")
		(net "_NFP_CORE_VID4")
	)
	(segment
		(start 31.365012 34.166988)
		(end 31.496 34.036)
		(width 0.14732)
		(layer "F.Cu")
		(net "_NFP_CORE_VID3")
	)
	(segment
		(start 31.365012 34.166988)
		(end 31.365012 35.1536)
		(width 0.14732)
		(layer "F.Cu")
		(net "_NFP_CORE_VID3")
	)
	(segment
		(start 30.988 33.528)
		(end 30.988 33.0581)
		(width 0.14732)
		(layer "F.Cu")
		(net "_NFP_CORE_VID3")
	)
	(segment
		(start 31.496 34.036)
		(end 30.988 33.528)
		(width 0.14732)
		(layer "F.Cu")
		(net "_NFP_CORE_VID3")
	)
	(via
		(at 31.496 34.036)
		(size 0.508)
		(drill 0.2667)
		(layers "F.Cu" "B.Cu")
		(net "_NFP_CORE_VID3")
	)
	(segment
		(start 30.988 33.0581)
		(end 30.099 33.0581)
		(width 0.14732)
		(layer "B.Cu")
		(net "_NFP_CORE_VID3")
	)
	(segment
		(start 31.496 34.036)
		(end 30.988 33.0581)
		(width 0.14732)
		(layer "B.Cu")
		(net "_NFP_CORE_VID3")
	)
	(segment
		(start 30.48 34.036)
		(end 30.48 33.4391)
		(width 0.14732)
		(layer "F.Cu")
		(net "_NFP_CORE_VID2")
	)
	(segment
		(start 29.21 33.0581)
		(end 30.099 33.0581)
		(width 0.14732)
		(layer "F.Cu")
		(net "_NFP_CORE_VID2")
	)
	(segment
		(start 30.864988 35.1536)
		(end 30.864988 34.420988)
		(width 0.14732)
		(layer "F.Cu")
		(net "_NFP_CORE_VID2")
	)
	(segment
		(start 30.48 33.4391)
		(end 30.099 33.0581)
		(width 0.14732)
		(layer "F.Cu")
		(net "_NFP_CORE_VID2")
	)
	(segment
		(start 30.864988 34.420988)
		(end 30.48 34.036)
		(width 0.14732)
		(layer "F.Cu")
		(net "_NFP_CORE_VID2")
	)
	(via
		(at 30.48 34.036)
		(size 0.508)
		(drill 0.2667)
		(layers "F.Cu" "B.Cu")
		(net "_NFP_CORE_VID2")
	)
	(segment
		(start 29.21 33.583855)
		(end 29.21 33.0581)
		(width 0.14732)
		(layer "B.Cu")
		(net "_NFP_CORE_VID2")
	)
	(segment
		(start 30.48 34.036)
		(end 29.654652 34.036)
		(width 0.14732)
		(layer "B.Cu")
		(net "_NFP_CORE_VID2")
	)
	(segment
		(start 29.654652 34.036)
		(end 29.333215 33.714563)
		(width 0.14732)
		(layer "B.Cu")
		(net "_NFP_CORE_VID2")
	)
	(segment
		(start 29.333215 33.714563)
		(end 29.21 33.583855)
		(width 0.14732)
		(layer "B.Cu")
		(net "_NFP_CORE_VID2")
	)
	(segment
		(start 28.3337 33.782)
		(end 29.464 33.782)
		(width 0.14732)
		(layer "F.Cu")
		(net "_NFP_CORE_VID1")
	)
	(segment
		(start 30.364989 34.682989)
		(end 30.364989 35.1536)
		(width 0.14732)
		(layer "F.Cu")
		(net "_NFP_CORE_VID1")
	)
	(segment
		(start 28.321 33.7693)
		(end 28.3337 33.782)
		(width 0.14732)
		(layer "F.Cu")
		(net "_NFP_CORE_VID1")
	)
	(segment
		(start 29.464 33.782)
		(end 30.364989 34.682989)
		(width 0.14732)
		(layer "F.Cu")
		(net "_NFP_CORE_VID1")
	)
	(segment
		(start 28.321 33.0581)
		(end 28.321 33.7693)
		(width 0.14732)
		(layer "F.Cu")
		(net "_NFP_CORE_VID1")
	)
	(via
		(at 28.956 34.417)
		(size 0.762)
		(drill 0.381)
		(layers "F.Cu" "B.Cu")
		(net "_NFP_CORE_VID1")
	)
	(via
		(at 28.321 33.7693)
		(size 0.508)
		(drill 0.254)
		(layers "F.Cu" "B.Cu")
		(net "_NFP_CORE_VID1")
	)
	(segment
		(start 28.321 33.782)
		(end 28.321 33.7693)
		(width 0.14732)
		(layer "B.Cu")
		(net "_NFP_CORE_VID1")
	)
	(segment
		(start 28.956 34.417)
		(end 28.321 33.782)
		(width 0.14732)
		(layer "B.Cu")
		(net "_NFP_CORE_VID1")
	)
	(segment
		(start 28.321 33.0581)
		(end 27.432 33.0581)
		(width 0.14732)
		(layer "B.Cu")
		(net "_NFP_CORE_VID1")
	)
	(segment
		(start 28.321 33.7693)
		(end 28.321 33.0581)
		(width 0.14732)
		(layer "B.Cu")
		(net "_NFP_CORE_VID1")
	)
	(segment
		(start 29.337 34.22396)
		(end 29.86499 34.75195)
		(width 0.14732)
		(layer "F.Cu")
		(net "_NFP_CORE_VID0")
	)
	(segment
		(start 28.125014 34.21634)
		(end 28.132634 34.22396)
		(width 0.14732)
		(layer "F.Cu")
		(net "_NFP_CORE_VID0")
	)
	(segment
		(start 27.432 33.782)
		(end 27.86634 34.21634)
		(width 0.14732)
		(layer "F.Cu")
		(net "_NFP_CORE_VID0")
	)
	(segment
		(start 28.132634 34.22396)
		(end 28.509366 34.22396)
		(width 0.14732)
		(layer "F.Cu")
		(net "_NFP_CORE_VID0")
	)
	(segment
		(start 27.432 33.782)
		(end 27.432 33.0581)
		(width 0.14732)
		(layer "F.Cu")
		(net "_NFP_CORE_VID0")
	)
	(segment
		(start 27.86634 34.21634)
		(end 28.125014 34.21634)
		(width 0.14732)
		(layer "F.Cu")
		(net "_NFP_CORE_VID0")
	)
	(segment
		(start 28.516986 34.21634)
		(end 29.214369 34.21634)
		(width 0.14732)
		(layer "F.Cu")
		(net "_NFP_CORE_VID0")
	)
	(segment
		(start 27.432 33.0581)
		(end 26.543 33.0581)
		(width 0.14732)
		(layer "F.Cu")
		(net "_NFP_CORE_VID0")
	)
	(segment
		(start 29.86499 34.75195)
		(end 29.86499 35.1536)
		(width 0.14732)
		(layer "F.Cu")
		(net "_NFP_CORE_VID0")
	)
	(segment
		(start 28.509366 34.22396)
		(end 28.516986 34.21634)
		(width 0.14732)
		(layer "F.Cu")
		(net "_NFP_CORE_VID0")
	)
	(segment
		(start 29.214369 34.21634)
		(end 29.221989 34.22396)
		(width 0.14732)
		(layer "F.Cu")
		(net "_NFP_CORE_VID0")
	)
	(segment
		(start 29.221989 34.22396)
		(end 29.337 34.22396)
		(width 0.14732)
		(layer "F.Cu")
		(net "_NFP_CORE_VID0")
	)
	(via
		(at 27.432 33.782)
		(size 0.508)
		(drill 0.254)
		(layers "F.Cu" "B.Cu")
		(net "_NFP_CORE_VID0")
	)
	(via
		(at 27.432 34.671)
		(size 0.762)
		(drill 0.381)
		(layers "F.Cu" "B.Cu")
		(net "_NFP_CORE_VID0")
	)
	(segment
		(start 26.543 33.528)
		(end 26.797 33.782)
		(width 0.14732)
		(layer "B.Cu")
		(net "_NFP_CORE_VID0")
	)
	(segment
		(start 26.543 33.0581)
		(end 26.543 33.528)
		(width 0.14732)
		(layer "B.Cu")
		(net "_NFP_CORE_VID0")
	)
	(segment
		(start 27.432 33.782)
		(end 27.432 34.671)
		(width 0.14732)
		(layer "B.Cu")
		(net "_NFP_CORE_VID0")
	)
	(segment
		(start 26.797 33.782)
		(end 27.432 33.782)
		(width 0.14732)
		(layer "B.Cu")
		(net "_NFP_CORE_VID0")
	)
	(segment
		(start 61.737011 14.542008)
		(end 61.237012 14.042009)
		(width 0.254)
		(layer "F.Cu")
		(net "VDDA_DDR0_32B")
	)
	(segment
		(start 61.237012 15.042007)
		(end 61.737011 14.542008)
		(width 0.254)
		(layer "F.Cu")
		(net "VDDA_DDR0_32B")
	)
	(via
		(at 64.737005 17.542002)
		(size 0.4826)
		(drill 0.25654)
		(layers "F.Cu" "B.Cu")
		(net "VDDA_DDR0_32B")
	)
	(via
		(at 61.737011 14.542008)
		(size 0.4826)
		(drill 0.20574)
		(layers "F.Cu" "B.Cu")
		(net "VDDA_DDR0_32B")
	)
	(segment
		(start 61.237114 14.042111)
		(end 61.237114 14.042009)
		(width 0.254)
		(layer "B.Cu")
		(net "VDDA_DDR0_32B")
	)
	(segment
		(start 61.737011 14.542008)
		(end 61.237114 14.042111)
		(width 0.254)
		(layer "B.Cu")
		(net "VDDA_DDR0_32B")
	)
	(segment
		(start 62.960504 16.986504)
		(end 62.292509 16.318509)
		(width 0.2032)
		(layer "In6.Cu")
		(net "VDDA_DDR0_32B")
	)
	(segment
		(start 61.786008 14.542008)
		(end 61.737011 14.542008)
		(width 0.2032)
		(layer "In6.Cu")
		(net "VDDA_DDR0_32B")
	)
	(segment
		(start 62.292509 15.048509)
		(end 61.786008 14.542008)
		(width 0.2032)
		(layer "In6.Cu")
		(net "VDDA_DDR0_32B")
	)
	(segment
		(start 64.643 17.526)
		(end 64.103504 16.986504)
		(width 0.2032)
		(layer "In6.Cu")
		(net "VDDA_DDR0_32B")
	)
	(segment
		(start 62.292509 16.318509)
		(end 62.292509 15.048509)
		(width 0.2032)
		(layer "In6.Cu")
		(net "VDDA_DDR0_32B")
	)
	(segment
		(start 64.103504 16.986504)
		(end 62.960504 16.986504)
		(width 0.2032)
		(layer "In6.Cu")
		(net "VDDA_DDR0_32B")
	)
	(segment
		(start 64.737005 17.542002)
		(end 64.643 17.526)
		(width 0.2032)
		(layer "In6.Cu")
		(net "VDDA_DDR0_32B")
	)
	(segment
		(start 61.737011 12.542012)
		(end 61.237012 13.042011)
		(width 0.254)
		(layer "F.Cu")
		(net "VDDA_DDR0_32A")
	)
	(segment
		(start 61.737011 11.541989)
		(end 61.237012 12.041988)
		(width 0.254)
		(layer "F.Cu")
		(net "VDDA_DDR0_32A")
	)
	(via
		(at 53.737002 20.541996)
		(size 0.4826)
		(drill 0.20574)
		(layers "F.Cu" "B.Cu")
		(net "VDDA_DDR0_32A")
	)
	(via
		(at 64.643 8.636)
		(size 0.762)
		(drill 0.381)
		(layers "F.Cu" "B.Cu")
		(net "VDDA_DDR0_32A")
	)
	(via
		(at 61.737011 11.541989)
		(size 0.4826)
		(drill 0.20574)
		(layers "F.Cu" "B.Cu")
		(net "VDDA_DDR0_32A")
	)
	(via
		(at 61.737011 12.542012)
		(size 0.4826)
		(drill 0.20574)
		(layers "F.Cu" "B.Cu")
		(net "VDDA_DDR0_32A")
	)
	(segment
		(start 62.236858 11.042142)
		(end 62.236985 11.042142)
		(width 0.254)
		(layer "B.Cu")
		(net "VDDA_DDR0_32A")
	)
	(segment
		(start 64.241705 10.053295)
		(end 64.241705 9.037295)
		(width 0.254)
		(layer "B.Cu")
		(net "VDDA_DDR0_32A")
	)
	(segment
		(start 61.737011 12.542012)
		(end 61.237114 12.042115)
		(width 0.254)
		(layer "B.Cu")
		(net "VDDA_DDR0_32A")
	)
	(segment
		(start 53.7972 20.602194)
		(end 53.737002 20.541996)
		(width 0.508)
		(layer "B.Cu")
		(net "VDDA_DDR0_32A")
	)
	(segment
		(start 61.237114 13.042011)
		(end 61.237114 13.041909)
		(width 0.254)
		(layer "B.Cu")
		(net "VDDA_DDR0_32A")
	)
	(segment
		(start 62.236985 11.042142)
		(end 63.252858 11.042142)
		(width 0.254)
		(layer "B.Cu")
		(net "VDDA_DDR0_32A")
	)
	(segment
		(start 61.236987 11.042142)
		(end 61.237165 11.042142)
		(width 0.254)
		(layer "B.Cu")
		(net "VDDA_DDR0_32A")
	)
	(segment
		(start 53.237003 20.042124)
		(end 53.23713 20.042124)
		(width 0.254)
		(layer "B.Cu")
		(net "VDDA_DDR0_32A")
	)
	(segment
		(start 64.241705 9.037295)
		(end 64.643 8.636)
		(width 0.254)
		(layer "B.Cu")
		(net "VDDA_DDR0_32A")
	)
	(segment
		(start 61.237165 11.042142)
		(end 61.737011 11.541989)
		(width 0.254)
		(layer "B.Cu")
		(net "VDDA_DDR0_32A")
	)
	(segment
		(start 54.737 20.602194)
		(end 53.7972 20.602194)
		(width 0.508)
		(layer "B.Cu")
		(net "VDDA_DDR0_32A")
	)
	(segment
		(start 61.737011 11.541989)
		(end 62.236858 11.042142)
		(width 0.254)
		(layer "B.Cu")
		(net "VDDA_DDR0_32A")
	)
	(segment
		(start 61.237114 12.042115)
		(end 61.237114 12.042013)
		(width 0.254)
		(layer "B.Cu")
		(net "VDDA_DDR0_32A")
	)
	(segment
		(start 63.252858 11.042142)
		(end 64.241705 10.053295)
		(width 0.254)
		(layer "B.Cu")
		(net "VDDA_DDR0_32A")
	)
	(segment
		(start 53.23713 20.042124)
		(end 53.737002 20.541996)
		(width 0.254)
		(layer "B.Cu")
		(net "VDDA_DDR0_32A")
	)
	(segment
		(start 61.237114 13.041909)
		(end 61.737011 12.542012)
		(width 0.254)
		(layer "B.Cu")
		(net "VDDA_DDR0_32A")
	)
	(segment
		(start 58.736992 9.541993)
		(end 58.236993 10.041992)
		(width 0.099314)
		(layer "F.Cu")
		(net "PCIE0_REFCLK_P")
	)
	(via
		(at 7.7724 4.4069)
		(size 0.508)
		(drill 0.254)
		(layers "F.Cu" "B.Cu")
		(net "PCIE0_REFCLK_P")
	)
	(via
		(at 58.736992 9.541993)
		(size 0.4826)
		(drill 0.25654)
		(layers "F.Cu" "B.Cu")
		(net "PCIE0_REFCLK_P")
	)
	(segment
		(start 8.4074 3.7719)
		(end 7.7724 4.4069)
		(width 0.099314)
		(layer "B.Cu")
		(net "PCIE0_REFCLK_P")
	)
	(segment
		(start 47.731655 1.884655)
		(end 47.117076 1.270076)
		(width 0.096012)
		(layer "In3.Cu")
		(net "PCIE0_REFCLK_P")
	)
	(segment
		(start 58.344054 8.382279)
		(end 58.575118 8.151216)
		(width 0.095758)
		(layer "In3.Cu")
		(net "PCIE0_REFCLK_P")
	)
	(segment
		(start 53.179853 1.884655)
		(end 52.465757 1.884655)
		(width 0.096012)
		(layer "In3.Cu")
		(net "PCIE0_REFCLK_P")
	)
	(segment
		(start 52.115212 2.2352)
		(end 51.625398 2.2352)
		(width 0.096012)
		(layer "In3.Cu")
		(net "PCIE0_REFCLK_P")
	)
	(segment
		(start 58.344054 9.149055)
		(end 58.344054 8.382279)
		(width 0.095758)
		(layer "In3.Cu")
		(net "PCIE0_REFCLK_P")
	)
	(segment
		(start 58.736992 9.541993)
		(end 58.344054 9.149055)
		(width 0.095758)
		(layer "In3.Cu")
		(net "PCIE0_REFCLK_P")
	)
	(segment
		(start 58.983296 8.151216)
		(end 59.341893 7.792618)
		(width 0.095758)
		(layer "In3.Cu")
		(net "PCIE0_REFCLK_P")
	)
	(segment
		(start 51.625398 2.2352)
		(end 51.274853 1.884655)
		(width 0.096012)
		(layer "In3.Cu")
		(net "PCIE0_REFCLK_P")
	)
	(segment
		(start 54.070758 2.27965)
		(end 53.574848 2.27965)
		(width 0.096012)
		(layer "In3.Cu")
		(net "PCIE0_REFCLK_P")
	)
	(segment
		(start 59.363737 3.17688)
		(end 59.365007 3.17561)
		(width 0.095758)
		(layer "In3.Cu")
		(net "PCIE0_REFCLK_P")
	)
	(segment
		(start 59.365007 3.067685)
		(end 59.365007 2.722778)
		(width 0.096012)
		(layer "In3.Cu")
		(net "PCIE0_REFCLK_P")
	)
	(segment
		(start 29.90657 1.270076)
		(end 29.367759 0.731266)
		(width 0.096012)
		(layer "In3.Cu")
		(net "PCIE0_REFCLK_P")
	)
	(segment
		(start 59.341893 3.283966)
		(end 59.363737 3.262122)
		(width 0.095758)
		(layer "In3.Cu")
		(net "PCIE0_REFCLK_P")
	)
	(segment
		(start 49.526723 2.282723)
		(end 49.128655 1.884655)
		(width 0.096012)
		(layer "In3.Cu")
		(net "PCIE0_REFCLK_P")
	)
	(segment
		(start 58.575118 8.151216)
		(end 58.983296 8.151216)
		(width 0.095758)
		(layer "In3.Cu")
		(net "PCIE0_REFCLK_P")
	)
	(segment
		(start 49.128655 1.884655)
		(end 47.731655 1.884655)
		(width 0.096012)
		(layer "In3.Cu")
		(net "PCIE0_REFCLK_P")
	)
	(segment
		(start 59.365007 2.722778)
		(end 58.527264 1.885036)
		(width 0.096012)
		(layer "In3.Cu")
		(net "PCIE0_REFCLK_P")
	)
	(segment
		(start 50.041277 2.282723)
		(end 49.526723 2.282723)
		(width 0.096012)
		(layer "In3.Cu")
		(net "PCIE0_REFCLK_P")
	)
	(segment
		(start 19.88566 2.59334)
		(end 17.993462 2.59334)
		(width 0.096012)
		(layer "In3.Cu")
		(net "PCIE0_REFCLK_P")
	)
	(segment
		(start 16.903802 3.683)
		(end 8.4963 3.683)
		(width 0.096012)
		(layer "In3.Cu")
		(net "PCIE0_REFCLK_P")
	)
	(segment
		(start 17.993462 2.59334)
		(end 16.903802 3.683)
		(width 0.096012)
		(layer "In3.Cu")
		(net "PCIE0_REFCLK_P")
	)
	(segment
		(start 54.465372 1.885036)
		(end 54.070758 2.27965)
		(width 0.096012)
		(layer "In3.Cu")
		(net "PCIE0_REFCLK_P")
	)
	(segment
		(start 59.365007 3.17561)
		(end 59.365007 3.067685)
		(width 0.095758)
		(layer "In3.Cu")
		(net "PCIE0_REFCLK_P")
	)
	(segment
		(start 20.497571 1.981429)
		(end 19.88566 2.59334)
		(width 0.096012)
		(layer "In3.Cu")
		(net "PCIE0_REFCLK_P")
	)
	(segment
		(start 8.4963 3.683)
		(end 7.7724 4.4069)
		(width 0.096012)
		(layer "In3.Cu")
		(net "PCIE0_REFCLK_P")
	)
	(segment
		(start 29.367759 0.731266)
		(end 26.105841 0.731266)
		(width 0.096012)
		(layer "In3.Cu")
		(net "PCIE0_REFCLK_P")
	)
	(segment
		(start 47.117076 1.270076)
		(end 29.90657 1.270076)
		(width 0.096012)
		(layer "In3.Cu")
		(net "PCIE0_REFCLK_P")
	)
	(segment
		(start 59.363737 3.262122)
		(end 59.363737 3.17688)
		(width 0.095758)
		(layer "In3.Cu")
		(net "PCIE0_REFCLK_P")
	)
	(segment
		(start 52.465757 1.884655)
		(end 52.115212 2.2352)
		(width 0.096012)
		(layer "In3.Cu")
		(net "PCIE0_REFCLK_P")
	)
	(segment
		(start 58.527264 1.885036)
		(end 54.465372 1.885036)
		(width 0.096012)
		(layer "In3.Cu")
		(net "PCIE0_REFCLK_P")
	)
	(segment
		(start 24.855678 1.981429)
		(end 20.497571 1.981429)
		(width 0.096012)
		(layer "In3.Cu")
		(net "PCIE0_REFCLK_P")
	)
	(segment
		(start 26.105841 0.731266)
		(end 24.855678 1.981429)
		(width 0.096012)
		(layer "In3.Cu")
		(net "PCIE0_REFCLK_P")
	)
	(segment
		(start 53.574848 2.27965)
		(end 53.179853 1.884655)
		(width 0.096012)
		(layer "In3.Cu")
		(net "PCIE0_REFCLK_P")
	)
	(segment
		(start 51.274853 1.884655)
		(end 50.439345 1.884655)
		(width 0.096012)
		(layer "In3.Cu")
		(net "PCIE0_REFCLK_P")
	)
	(segment
		(start 50.439345 1.884655)
		(end 50.041277 2.282723)
		(width 0.096012)
		(layer "In3.Cu")
		(net "PCIE0_REFCLK_P")
	)
	(segment
		(start 59.341893 7.792618)
		(end 59.341893 3.283966)
		(width 0.095758)
		(layer "In3.Cu")
		(net "PCIE0_REFCLK_P")
	)
	(segment
		(start 57.736994 9.541993)
		(end 57.236995 10.041992)
		(width 0.099314)
		(layer "F.Cu")
		(net "PCIE0_REFCLK_N")
	)
	(via
		(at 9.0424 4.4069)
		(size 0.508)
		(drill 0.254)
		(layers "F.Cu" "B.Cu")
		(net "PCIE0_REFCLK_N")
	)
	(via
		(at 57.736994 9.541993)
		(size 0.4826)
		(drill 0.25654)
		(layers "F.Cu" "B.Cu")
		(net "PCIE0_REFCLK_N")
	)
	(segment
		(start 8.4074 5.0419)
		(end 9.0424 4.4069)
		(width 0.099314)
		(layer "B.Cu")
		(net "PCIE0_REFCLK_N")
	)
	(segment
		(start 49.020806 2.145005)
		(end 47.623806 2.145005)
		(width 0.096012)
		(layer "In3.Cu")
		(net "PCIE0_REFCLK_N")
	)
	(segment
		(start 24.963526 2.241779)
		(end 20.60542 2.241779)
		(width 0.096012)
		(layer "In3.Cu")
		(net "PCIE0_REFCLK_N")
	)
	(segment
		(start 52.340764 2.385568)
		(end 52.230782 2.49555)
		(width 0.096012)
		(layer "In3.Cu")
		(net "PCIE0_REFCLK_N")
	)
	(segment
		(start 52.573606 2.145005)
		(end 52.340764 2.377846)
		(width 0.096012)
		(layer "In3.Cu")
		(net "PCIE0_REFCLK_N")
	)
	(segment
		(start 54.573602 2.145005)
		(end 54.178606 2.54)
		(width 0.096012)
		(layer "In3.Cu")
		(net "PCIE0_REFCLK_N")
	)
	(segment
		(start 59.104657 3.067685)
		(end 59.104657 2.830627)
		(width 0.096012)
		(layer "In3.Cu")
		(net "PCIE0_REFCLK_N")
	)
	(segment
		(start 53.072005 2.145005)
		(end 52.573606 2.145005)
		(width 0.096012)
		(layer "In3.Cu")
		(net "PCIE0_REFCLK_N")
	)
	(segment
		(start 20.60542 2.241779)
		(end 19.993508 2.85369)
		(width 0.096012)
		(layer "In3.Cu")
		(net "PCIE0_REFCLK_N")
	)
	(segment
		(start 29.259911 0.991616)
		(end 26.213689 0.991616)
		(width 0.096012)
		(layer "In3.Cu")
		(net "PCIE0_REFCLK_N")
	)
	(segment
		(start 49.418875 2.543073)
		(end 49.020806 2.145005)
		(width 0.096012)
		(layer "In3.Cu")
		(net "PCIE0_REFCLK_N")
	)
	(segment
		(start 26.213689 0.991616)
		(end 24.963526 2.241779)
		(width 0.096012)
		(layer "In3.Cu")
		(net "PCIE0_REFCLK_N")
	)
	(segment
		(start 52.340764 2.377846)
		(end 52.340764 2.385568)
		(width 0.096012)
		(layer "In3.Cu")
		(net "PCIE0_REFCLK_N")
	)
	(segment
		(start 59.127771 7.703871)
		(end 59.127771 3.103829)
		(width 0.095758)
		(layer "In3.Cu")
		(net "PCIE0_REFCLK_N")
	)
	(segment
		(start 8.400237 4.147261)
		(end 8.400237 4.46532)
		(width 0.096012)
		(layer "In3.Cu")
		(net "PCIE0_REFCLK_N")
	)
	(segment
		(start 58.894548 7.937094)
		(end 59.127771 7.703871)
		(width 0.095758)
		(layer "In3.Cu")
		(net "PCIE0_REFCLK_N")
	)
	(segment
		(start 53.467 2.54)
		(end 53.072005 2.145005)
		(width 0.096012)
		(layer "In3.Cu")
		(net "PCIE0_REFCLK_N")
	)
	(segment
		(start 58.419035 2.145005)
		(end 54.573602 2.145005)
		(width 0.096012)
		(layer "In3.Cu")
		(net "PCIE0_REFCLK_N")
	)
	(segment
		(start 8.8773 4.572)
		(end 9.0424 4.4069)
		(width 0.096012)
		(layer "In3.Cu")
		(net "PCIE0_REFCLK_N")
	)
	(segment
		(start 18.10131 2.85369)
		(end 17.01165 3.94335)
		(width 0.096012)
		(layer "In3.Cu")
		(net "PCIE0_REFCLK_N")
	)
	(segment
		(start 58.129932 9.149055)
		(end 58.129932 8.293532)
		(width 0.095758)
		(layer "In3.Cu")
		(net "PCIE0_REFCLK_N")
	)
	(segment
		(start 57.736994 9.541993)
		(end 58.129932 9.149055)
		(width 0.095758)
		(layer "In3.Cu")
		(net "PCIE0_REFCLK_N")
	)
	(segment
		(start 51.167005 2.145005)
		(end 50.547194 2.145005)
		(width 0.096012)
		(layer "In3.Cu")
		(net "PCIE0_REFCLK_N")
	)
	(segment
		(start 19.993508 2.85369)
		(end 18.10131 2.85369)
		(width 0.096012)
		(layer "In3.Cu")
		(net "PCIE0_REFCLK_N")
	)
	(segment
		(start 47.009228 1.530426)
		(end 29.798721 1.530426)
		(width 0.096012)
		(layer "In3.Cu")
		(net "PCIE0_REFCLK_N")
	)
	(segment
		(start 29.798721 1.530426)
		(end 29.259911 0.991616)
		(width 0.096012)
		(layer "In3.Cu")
		(net "PCIE0_REFCLK_N")
	)
	(segment
		(start 51.51755 2.49555)
		(end 51.167005 2.145005)
		(width 0.096012)
		(layer "In3.Cu")
		(net "PCIE0_REFCLK_N")
	)
	(segment
		(start 47.623806 2.145005)
		(end 47.009228 1.530426)
		(width 0.096012)
		(layer "In3.Cu")
		(net "PCIE0_REFCLK_N")
	)
	(segment
		(start 58.129932 8.293532)
		(end 58.48637 7.937094)
		(width 0.095758)
		(layer "In3.Cu")
		(net "PCIE0_REFCLK_N")
	)
	(segment
		(start 59.104657 3.080715)
		(end 59.104657 3.067685)
		(width 0.095758)
		(layer "In3.Cu")
		(net "PCIE0_REFCLK_N")
	)
	(segment
		(start 59.127771 3.103829)
		(end 59.104657 3.080715)
		(width 0.095758)
		(layer "In3.Cu")
		(net "PCIE0_REFCLK_N")
	)
	(segment
		(start 8.604148 3.94335)
		(end 8.400237 4.147261)
		(width 0.096012)
		(layer "In3.Cu")
		(net "PCIE0_REFCLK_N")
	)
	(segment
		(start 50.547194 2.145005)
		(end 50.149125 2.543073)
		(width 0.096012)
		(layer "In3.Cu")
		(net "PCIE0_REFCLK_N")
	)
	(segment
		(start 58.48637 7.937094)
		(end 58.894548 7.937094)
		(width 0.095758)
		(layer "In3.Cu")
		(net "PCIE0_REFCLK_N")
	)
	(segment
		(start 54.178606 2.54)
		(end 53.467 2.54)
		(width 0.096012)
		(layer "In3.Cu")
		(net "PCIE0_REFCLK_N")
	)
	(segment
		(start 8.506917 4.572)
		(end 8.8773 4.572)
		(width 0.096012)
		(layer "In3.Cu")
		(net "PCIE0_REFCLK_N")
	)
	(segment
		(start 17.01165 3.94335)
		(end 8.604148 3.94335)
		(width 0.096012)
		(layer "In3.Cu")
		(net "PCIE0_REFCLK_N")
	)
	(segment
		(start 50.149125 2.543073)
		(end 49.418875 2.543073)
		(width 0.096012)
		(layer "In3.Cu")
		(net "PCIE0_REFCLK_N")
	)
	(segment
		(start 59.104657 2.830627)
		(end 58.419035 2.145005)
		(width 0.096012)
		(layer "In3.Cu")
		(net "PCIE0_REFCLK_N")
	)
	(segment
		(start 52.230782 2.49555)
		(end 51.51755 2.49555)
		(width 0.096012)
		(layer "In3.Cu")
		(net "PCIE0_REFCLK_N")
	)
	(segment
		(start 8.400237 4.46532)
		(end 8.506917 4.572)
		(width 0.096012)
		(layer "In3.Cu")
		(net "PCIE0_REFCLK_N")
	)
	(segment
		(start 25.4889 39.497)
		(end 25.4889 40.259)
		(width 0.254)
		(layer "F.Cu")
		(net "NFP_VDD_CORE_SENSE_VSS")
	)
	(segment
		(start 30.15234 41.91)
		(end 30.032173 41.91)
		(width 0.254)
		(layer "F.Cu")
		(net "NFP_VDD_CORE_SENSE_VSS")
	)
	(segment
		(start 47.23699 12.041988)
		(end 46.736991 11.541989)
		(width 0.254)
		(layer "F.Cu")
		(net "NFP_VDD_CORE_SENSE_VSS")
	)
	(segment
		(start 25.4889 40.259)
		(end 25.273 40.4749)
		(width 0.254)
		(layer "F.Cu")
		(net "NFP_VDD_CORE_SENSE_VSS")
	)
	(segment
		(start 30.032173 41.91)
		(end 29.86499 41.742817)
		(width 0.254)
		(layer "F.Cu")
		(net "NFP_VDD_CORE_SENSE_VSS")
	)
	(segment
		(start 25.4889 38.608)
		(end 25.4889 39.497)
		(width 0.254)
		(layer "F.Cu")
		(net "NFP_VDD_CORE_SENSE_VSS")
	)
	(segment
		(start 29.86499 41.742817)
		(end 29.86499 41.0464)
		(width 0.254)
		(layer "F.Cu")
		(net "NFP_VDD_CORE_SENSE_VSS")
	)
	(via
		(at 46.736991 11.541989)
		(size 0.4826)
		(drill 0.20574)
		(layers "F.Cu" "B.Cu")
		(net "NFP_VDD_CORE_SENSE_VSS")
	)
	(via
		(at 30.15234 41.91)
		(size 0.508)
		(drill 0.254)
		(layers "F.Cu" "B.Cu")
		(net "NFP_VDD_CORE_SENSE_VSS")
	)
	(via
		(at 25.273 40.4749)
		(size 0.508)
		(drill 0.25654)
		(layers "F.Cu" "B.Cu")
		(net "NFP_VDD_CORE_SENSE_VSS")
	)
	(segment
		(start 27.922169 41.58234)
		(end 28.343098 41.58234)
		(width 0.254)
		(layer "B.Cu")
		(net "NFP_VDD_CORE_SENSE_VSS")
	)
	(segment
		(start 46.736991 11.541989)
		(end 46.237144 12.041835)
		(width 0.254)
		(layer "B.Cu")
		(net "NFP_VDD_CORE_SENSE_VSS")
	)
	(segment
		(start 46.237144 12.041835)
		(end 46.237144 12.042013)
		(width 0.254)
		(layer "B.Cu")
		(net "NFP_VDD_CORE_SENSE_VSS")
	)
	(segment
		(start 28.343098 41.58234)
		(end 28.396438 41.529)
		(width 0.254)
		(layer "B.Cu")
		(net "NFP_VDD_CORE_SENSE_VSS")
	)
	(segment
		(start 29.77134 41.529)
		(end 30.15234 41.91)
		(width 0.254)
		(layer "B.Cu")
		(net "NFP_VDD_CORE_SENSE_VSS")
	)
	(segment
		(start 28.396438 41.529)
		(end 29.77134 41.529)
		(width 0.254)
		(layer "B.Cu")
		(net "NFP_VDD_CORE_SENSE_VSS")
	)
	(segment
		(start 25.273 41.087954)
		(end 25.968046 41.783)
		(width 0.254)
		(layer "B.Cu")
		(net "NFP_VDD_CORE_SENSE_VSS")
	)
	(segment
		(start 25.968046 41.783)
		(end 27.721509 41.783)
		(width 0.254)
		(layer "B.Cu")
		(net "NFP_VDD_CORE_SENSE_VSS")
	)
	(segment
		(start 27.721509 41.783)
		(end 27.922169 41.58234)
		(width 0.254)
		(layer "B.Cu")
		(net "NFP_VDD_CORE_SENSE_VSS")
	)
	(segment
		(start 25.273 40.4749)
		(end 25.273 41.087954)
		(width 0.254)
		(layer "B.Cu")
		(net "NFP_VDD_CORE_SENSE_VSS")
	)
	(segment
		(start 36.322 34.417)
		(end 36.576 34.163)
		(width 0.254)
		(layer "In6.Cu")
		(net "NFP_VDD_CORE_SENSE_VSS")
	)
	(segment
		(start 45.602525 31.011901)
		(end 45.931658 31.011901)
		(width 0.254)
		(layer "In6.Cu")
		(net "NFP_VDD_CORE_SENSE_VSS")
	)
	(segment
		(start 44.93166 32.011899)
		(end 45.206895 31.736665)
		(width 0.254)
		(layer "In6.Cu")
		(net "NFP_VDD_CORE_SENSE_VSS")
	)
	(segment
		(start 36.576 34.163)
		(end 38.1 34.163)
		(width 0.254)
		(layer "In6.Cu")
		(net "NFP_VDD_CORE_SENSE_VSS")
	)
	(segment
		(start 46.228 12.065)
		(end 46.736991 11.556009)
		(width 0.254)
		(layer "In6.Cu")
		(net "NFP_VDD_CORE_SENSE_VSS")
	)
	(segment
		(start 31.480608 40.655418)
		(end 32.428713 40.655418)
		(width 0.254)
		(layer "In6.Cu")
		(net "NFP_VDD_CORE_SENSE_VSS")
	)
	(segment
		(start 30.15234 41.91)
		(end 30.111751 41.897249)
		(width 0.254)
		(layer "In6.Cu")
		(net "NFP_VDD_CORE_SENSE_VSS")
	)
	(segment
		(start 45.206895 31.407532)
		(end 45.602525 31.011901)
		(width 0.254)
		(layer "In6.Cu")
		(net "NFP_VDD_CORE_SENSE_VSS")
	)
	(segment
		(start 36.0045 34.714536)
		(end 36.302036 34.417)
		(width 0.254)
		(layer "In6.Cu")
		(net "NFP_VDD_CORE_SENSE_VSS")
	)
	(segment
		(start 43.03174 33.453095)
		(end 44.472936 32.011899)
		(width 0.254)
		(layer "In6.Cu")
		(net "NFP_VDD_CORE_SENSE_VSS")
	)
	(segment
		(start 38.1 34.163)
		(end 38.251105 34.011895)
		(width 0.254)
		(layer "In6.Cu")
		(net "NFP_VDD_CORE_SENSE_VSS")
	)
	(segment
		(start 38.251105 34.011895)
		(end 39.93167 34.011895)
		(width 0.254)
		(layer "In6.Cu")
		(net "NFP_VDD_CORE_SENSE_VSS")
	)
	(segment
		(start 40.49047 33.453095)
		(end 43.03174 33.453095)
		(width 0.254)
		(layer "In6.Cu")
		(net "NFP_VDD_CORE_SENSE_VSS")
	)
	(segment
		(start 35.696525 35.042475)
		(end 36.0045 34.7345)
		(width 0.254)
		(layer "In6.Cu")
		(net "NFP_VDD_CORE_SENSE_VSS")
	)
	(segment
		(start 33.3248 39.759331)
		(end 33.3248 35.667036)
		(width 0.254)
		(layer "In6.Cu")
		(net "NFP_VDD_CORE_SENSE_VSS")
	)
	(segment
		(start 44.472936 32.011899)
		(end 44.93166 32.011899)
		(width 0.254)
		(layer "In6.Cu")
		(net "NFP_VDD_CORE_SENSE_VSS")
	)
	(segment
		(start 39.93167 34.011895)
		(end 40.49047 33.453095)
		(width 0.254)
		(layer "In6.Cu")
		(net "NFP_VDD_CORE_SENSE_VSS")
	)
	(segment
		(start 35.271227 35.042475)
		(end 35.696525 35.042475)
		(width 0.254)
		(layer "In6.Cu")
		(net "NFP_VDD_CORE_SENSE_VSS")
	)
	(segment
		(start 33.8963 35.095536)
		(end 35.218167 35.095536)
		(width 0.254)
		(layer "In6.Cu")
		(net "NFP_VDD_CORE_SENSE_VSS")
	)
	(segment
		(start 36.302036 34.417)
		(end 36.322 34.417)
		(width 0.254)
		(layer "In6.Cu")
		(net "NFP_VDD_CORE_SENSE_VSS")
	)
	(segment
		(start 46.228 30.71556)
		(end 46.228 12.065)
		(width 0.254)
		(layer "In6.Cu")
		(net "NFP_VDD_CORE_SENSE_VSS")
	)
	(segment
		(start 45.206895 31.736665)
		(end 45.206895 31.407532)
		(width 0.254)
		(layer "In6.Cu")
		(net "NFP_VDD_CORE_SENSE_VSS")
	)
	(segment
		(start 36.0045 34.7345)
		(end 36.0045 34.714536)
		(width 0.254)
		(layer "In6.Cu")
		(net "NFP_VDD_CORE_SENSE_VSS")
	)
	(segment
		(start 30.238776 41.897249)
		(end 31.480608 40.655418)
		(width 0.254)
		(layer "In6.Cu")
		(net "NFP_VDD_CORE_SENSE_VSS")
	)
	(segment
		(start 45.931658 31.011901)
		(end 46.228 30.71556)
		(width 0.254)
		(layer "In6.Cu")
		(net "NFP_VDD_CORE_SENSE_VSS")
	)
	(segment
		(start 46.736991 11.556009)
		(end 46.736991 11.541989)
		(width 0.254)
		(layer "In6.Cu")
		(net "NFP_VDD_CORE_SENSE_VSS")
	)
	(segment
		(start 33.3248 35.667036)
		(end 33.8963 35.095536)
		(width 0.254)
		(layer "In6.Cu")
		(net "NFP_VDD_CORE_SENSE_VSS")
	)
	(segment
		(start 30.111751 41.897249)
		(end 30.238776 41.897249)
		(width 0.254)
		(layer "In6.Cu")
		(net "NFP_VDD_CORE_SENSE_VSS")
	)
	(segment
		(start 35.218167 35.095536)
		(end 35.271227 35.042475)
		(width 0.254)
		(layer "In6.Cu")
		(net "NFP_VDD_CORE_SENSE_VSS")
	)
	(segment
		(start 32.428713 40.655418)
		(end 33.3248 39.759331)
		(width 0.254)
		(layer "In6.Cu")
		(net "NFP_VDD_CORE_SENSE_VSS")
	)
	(segment
		(start 31.369 45.72)
		(end 31.907836 46.258836)
		(width 0.254)
		(layer "F.Cu")
		(net "NFP_VDD_CORE_SENSE_VDD")
	)
	(segment
		(start 46.236992 12.041988)
		(end 45.736993 11.541989)
		(width 0.254)
		(layer "F.Cu")
		(net "NFP_VDD_CORE_SENSE_VDD")
	)
	(segment
		(start 30.6451 45.72)
		(end 31.369 45.72)
		(width 0.254)
		(layer "F.Cu")
		(net "NFP_VDD_CORE_SENSE_VDD")
	)
	(segment
		(start 31.369 45.72)
		(end 31.369 44.3611)
		(width 0.254)
		(layer "F.Cu")
		(net "NFP_VDD_CORE_SENSE_VDD")
	)
	(via
		(at 45.736993 11.541989)
		(size 0.4826)
		(drill 0.20574)
		(layers "F.Cu" "B.Cu")
		(net "NFP_VDD_CORE_SENSE_VDD")
	)
	(via
		(at 31.907836 46.258836)
		(size 0.762)
		(drill 0.381)
		(layers "F.Cu" "B.Cu")
		(net "NFP_VDD_CORE_SENSE_VDD")
	)
	(via
		(at 29.2735 42.0878)
		(size 0.508)
		(drill 0.254)
		(layers "F.Cu" "B.Cu")
		(net "NFP_VDD_CORE_SENSE_VDD")
	)
	(via
		(at 31.369 45.72)
		(size 0.508)
		(drill 0.254)
		(layers "F.Cu" "B.Cu")
		(net "NFP_VDD_CORE_SENSE_VDD")
	)
	(segment
		(start 29.2735 42.0878)
		(end 28.829 42.5323)
		(width 0.254)
		(layer "B.Cu")
		(net "NFP_VDD_CORE_SENSE_VDD")
	)
	(segment
		(start 30.226 45.72)
		(end 31.369 45.72)
		(width 0.254)
		(layer "B.Cu")
		(net "NFP_VDD_CORE_SENSE_VDD")
	)
	(segment
		(start 45.736993 11.541989)
		(end 46.236966 11.042015)
		(width 0.254)
		(layer "B.Cu")
		(net "NFP_VDD_CORE_SENSE_VDD")
	)
	(segment
		(start 28.829 42.5323)
		(end 28.829 44.323)
		(width 0.254)
		(layer "B.Cu")
		(net "NFP_VDD_CORE_SENSE_VDD")
	)
	(segment
		(start 46.236966 11.042015)
		(end 46.237144 11.042015)
		(width 0.254)
		(layer "B.Cu")
		(net "NFP_VDD_CORE_SENSE_VDD")
	)
	(segment
		(start 28.829 44.323)
		(end 30.226 45.72)
		(width 0.254)
		(layer "B.Cu")
		(net "NFP_VDD_CORE_SENSE_VDD")
	)
	(segment
		(start 35.442525 34.661475)
		(end 36.322 33.782)
		(width 0.254)
		(layer "In6.Cu")
		(net "NFP_VDD_CORE_SENSE_VDD")
	)
	(segment
		(start 38.267107 33.34733)
		(end 38.542341 33.072095)
		(width 0.254)
		(layer "In6.Cu")
		(net "NFP_VDD_CORE_SENSE_VDD")
	)
	(segment
		(start 32.9438 39.601496)
		(end 32.9438 35.5092)
		(width 0.254)
		(layer "In6.Cu")
		(net "NFP_VDD_CORE_SENSE_VDD")
	)
	(segment
		(start 43.561 31.496)
		(end 43.942 31.115)
		(width 0.254)
		(layer "In6.Cu")
		(net "NFP_VDD_CORE_SENSE_VDD")
	)
	(segment
		(start 44.96628 31.10672)
		(end 45.206895 30.866105)
		(width 0.254)
		(layer "In6.Cu")
		(net "NFP_VDD_CORE_SENSE_VDD")
	)
	(segment
		(start 35.060331 34.714536)
		(end 35.113392 34.661475)
		(width 0.254)
		(layer "In6.Cu")
		(net "NFP_VDD_CORE_SENSE_VDD")
	)
	(segment
		(start 38.542341 33.072095)
		(end 42.873905 33.072095)
		(width 0.254)
		(layer "In6.Cu")
		(net "NFP_VDD_CORE_SENSE_VDD")
	)
	(segment
		(start 45.206895 30.866105)
		(end 45.206895 12.070105)
		(width 0.254)
		(layer "In6.Cu")
		(net "NFP_VDD_CORE_SENSE_VDD")
	)
	(segment
		(start 43.942 31.115)
		(end 44.499428 31.115)
		(width 0.254)
		(layer "In6.Cu")
		(net "NFP_VDD_CORE_SENSE_VDD")
	)
	(segment
		(start 36.322 33.782)
		(end 37.87742 33.782)
		(width 0.254)
		(layer "In6.Cu")
		(net "NFP_VDD_CORE_SENSE_VDD")
	)
	(segment
		(start 29.64434 41.699536)
		(end 31.069458 40.274418)
		(width 0.254)
		(layer "In6.Cu")
		(net "NFP_VDD_CORE_SENSE_VDD")
	)
	(segment
		(start 32.9438 35.5092)
		(end 33.738464 34.714536)
		(width 0.254)
		(layer "In6.Cu")
		(net "NFP_VDD_CORE_SENSE_VDD")
	)
	(segment
		(start 32.270878 40.274418)
		(end 32.9438 39.601496)
		(width 0.254)
		(layer "In6.Cu")
		(net "NFP_VDD_CORE_SENSE_VDD")
	)
	(segment
		(start 33.738464 34.714536)
		(end 35.060331 34.714536)
		(width 0.254)
		(layer "In6.Cu")
		(net "NFP_VDD_CORE_SENSE_VDD")
	)
	(segment
		(start 42.873905 33.072095)
		(end 43.561 32.385)
		(width 0.254)
		(layer "In6.Cu")
		(net "NFP_VDD_CORE_SENSE_VDD")
	)
	(segment
		(start 35.113392 34.661475)
		(end 35.442525 34.661475)
		(width 0.254)
		(layer "In6.Cu")
		(net "NFP_VDD_CORE_SENSE_VDD")
	)
	(segment
		(start 29.64434 41.71696)
		(end 29.64434 41.699536)
		(width 0.254)
		(layer "In6.Cu")
		(net "NFP_VDD_CORE_SENSE_VDD")
	)
	(segment
		(start 43.561 32.385)
		(end 43.561 31.496)
		(width 0.254)
		(layer "In6.Cu")
		(net "NFP_VDD_CORE_SENSE_VDD")
	)
	(segment
		(start 44.93166 31.072099)
		(end 44.96628 31.10672)
		(width 0.254)
		(layer "In6.Cu")
		(net "NFP_VDD_CORE_SENSE_VDD")
	)
	(segment
		(start 44.542329 31.072099)
		(end 44.93166 31.072099)
		(width 0.254)
		(layer "In6.Cu")
		(net "NFP_VDD_CORE_SENSE_VDD")
	)
	(segment
		(start 29.2735 42.0878)
		(end 29.64434 41.71696)
		(width 0.254)
		(layer "In6.Cu")
		(net "NFP_VDD_CORE_SENSE_VDD")
	)
	(segment
		(start 45.206895 12.070105)
		(end 45.735011 11.541989)
		(width 0.254)
		(layer "In6.Cu")
		(net "NFP_VDD_CORE_SENSE_VDD")
	)
	(segment
		(start 38.267107 33.392313)
		(end 38.267107 33.34733)
		(width 0.254)
		(layer "In6.Cu")
		(net "NFP_VDD_CORE_SENSE_VDD")
	)
	(segment
		(start 45.735011 11.541989)
		(end 45.736993 11.541989)
		(width 0.254)
		(layer "In6.Cu")
		(net "NFP_VDD_CORE_SENSE_VDD")
	)
	(segment
		(start 37.87742 33.782)
		(end 38.267107 33.392313)
		(width 0.254)
		(layer "In6.Cu")
		(net "NFP_VDD_CORE_SENSE_VDD")
	)
	(segment
		(start 31.069458 40.274418)
		(end 32.270878 40.274418)
		(width 0.254)
		(layer "In6.Cu")
		(net "NFP_VDD_CORE_SENSE_VDD")
	)
	(segment
		(start 44.499428 31.115)
		(end 44.542329 31.072099)
		(width 0.254)
		(layer "In6.Cu")
		(net "NFP_VDD_CORE_SENSE_VDD")
	)
	(segment
		(start 36.7157 41.656)
		(end 36.6903 40.767)
		(width 0.254)
		(layer "F.Cu")
		(net "NFP_VDD_CORE_ISEN2_P")
	)
	(via
		(at 36.7157 41.656)
		(size 0.508)
		(drill 0.25654)
		(layers "F.Cu" "B.Cu")
		(net "NFP_VDD_CORE_ISEN2_P")
	)
	(via
		(at 51.3969 36.957)
		(size 0.508)
		(drill 0.25654)
		(layers "F.Cu" "B.Cu")
		(net "NFP_VDD_CORE_ISEN2_P")
	)
	(segment
		(start 41.01465 38.227)
		(end 42.893336 38.227)
		(width 0.254)
		(layer "In6.Cu")
		(net "NFP_VDD_CORE_ISEN2_P")
	)
	(segment
		(start 42.893336 38.227)
		(end 43.312436 37.8079)
		(width 0.254)
		(layer "In6.Cu")
		(net "NFP_VDD_CORE_ISEN2_P")
	)
	(segment
		(start 43.725998 37.4269)
		(end 43.8912 37.4269)
		(width 0.254)
		(layer "In6.Cu")
		(net "NFP_VDD_CORE_ISEN2_P")
	)
	(segment
		(start 47.624898 36.195)
		(end 50.673 36.195)
		(width 0.254)
		(layer "In6.Cu")
		(net "NFP_VDD_CORE_ISEN2_P")
	)
	(segment
		(start 36.39881 41.85981)
		(end 36.195 41.656)
		(width 0.254)
		(layer "In6.Cu")
		(net "NFP_VDD_CORE_ISEN2_P")
	)
	(segment
		(start 36.195 41.244241)
		(end 38.710591 38.72865)
		(width 0.254)
		(layer "In6.Cu")
		(net "NFP_VDD_CORE_ISEN2_P")
	)
	(segment
		(start 50.673 36.2331)
		(end 51.3969 36.957)
		(width 0.254)
		(layer "In6.Cu")
		(net "NFP_VDD_CORE_ISEN2_P")
	)
	(segment
		(start 36.51189 41.85981)
		(end 36.39881 41.85981)
		(width 0.254)
		(layer "In6.Cu")
		(net "NFP_VDD_CORE_ISEN2_P")
	)
	(segment
		(start 43.344998 37.8079)
		(end 43.725998 37.4269)
		(width 0.254)
		(layer "In6.Cu")
		(net "NFP_VDD_CORE_ISEN2_P")
	)
	(segment
		(start 46.608898 37.211)
		(end 47.624898 36.195)
		(width 0.254)
		(layer "In6.Cu")
		(net "NFP_VDD_CORE_ISEN2_P")
	)
	(segment
		(start 36.7157 41.656)
		(end 36.51189 41.85981)
		(width 0.254)
		(layer "In6.Cu")
		(net "NFP_VDD_CORE_ISEN2_P")
	)
	(segment
		(start 43.312436 37.8079)
		(end 43.344998 37.8079)
		(width 0.254)
		(layer "In6.Cu")
		(net "NFP_VDD_CORE_ISEN2_P")
	)
	(segment
		(start 43.8912 37.4269)
		(end 44.1071 37.211)
		(width 0.254)
		(layer "In6.Cu")
		(net "NFP_VDD_CORE_ISEN2_P")
	)
	(segment
		(start 36.195 41.656)
		(end 36.195 41.244241)
		(width 0.254)
		(layer "In6.Cu")
		(net "NFP_VDD_CORE_ISEN2_P")
	)
	(segment
		(start 44.1071 37.211)
		(end 46.608898 37.211)
		(width 0.254)
		(layer "In6.Cu")
		(net "NFP_VDD_CORE_ISEN2_P")
	)
	(segment
		(start 40.513 38.72865)
		(end 41.01465 38.227)
		(width 0.254)
		(layer "In6.Cu")
		(net "NFP_VDD_CORE_ISEN2_P")
	)
	(segment
		(start 50.673 36.195)
		(end 50.673 36.2331)
		(width 0.254)
		(layer "In6.Cu")
		(net "NFP_VDD_CORE_ISEN2_P")
	)
	(segment
		(start 38.710591 38.72865)
		(end 40.513 38.72865)
		(width 0.254)
		(layer "In6.Cu")
		(net "NFP_VDD_CORE_ISEN2_P")
	)
	(via
		(at 36.7157 42.545)
		(size 0.508)
		(drill 0.25654)
		(layers "F.Cu" "B.Cu")
		(net "NFP_VDD_CORE_ISEN2_N")
	)
	(via
		(at 54.0131 36.957)
		(size 0.508)
		(drill 0.25654)
		(layers "F.Cu" "B.Cu")
		(net "NFP_VDD_CORE_ISEN2_N")
	)
	(segment
		(start 43.1546 37.4269)
		(end 42.7355 37.846)
		(width 0.254)
		(layer "In6.Cu")
		(net "NFP_VDD_CORE_ISEN2_N")
	)
	(segment
		(start 40.856814 37.846)
		(end 40.355164 38.34765)
		(width 0.254)
		(layer "In6.Cu")
		(net "NFP_VDD_CORE_ISEN2_N")
	)
	(segment
		(start 36.240974 42.24081)
		(end 36.429036 42.24081)
		(width 0.254)
		(layer "In6.Cu")
		(net "NFP_VDD_CORE_ISEN2_N")
	)
	(segment
		(start 35.814 41.086405)
		(end 35.814 41.813836)
		(width 0.254)
		(layer "In6.Cu")
		(net "NFP_VDD_CORE_ISEN2_N")
	)
	(segment
		(start 46.451063 36.83)
		(end 43.949264 36.83)
		(width 0.254)
		(layer "In6.Cu")
		(net "NFP_VDD_CORE_ISEN2_N")
	)
	(segment
		(start 54.0131 36.957)
		(end 52.115364 36.957)
		(width 0.254)
		(layer "In6.Cu")
		(net "NFP_VDD_CORE_ISEN2_N")
	)
	(segment
		(start 41.178785 37.846)
		(end 40.856814 37.846)
		(width 0.254)
		(layer "In6.Cu")
		(net "NFP_VDD_CORE_ISEN2_N")
	)
	(segment
		(start 35.814 41.813836)
		(end 36.240974 42.24081)
		(width 0.254)
		(layer "In6.Cu")
		(net "NFP_VDD_CORE_ISEN2_N")
	)
	(segment
		(start 36.429036 42.24081)
		(end 36.7157 42.545)
		(width 0.254)
		(layer "In6.Cu")
		(net "NFP_VDD_CORE_ISEN2_N")
	)
	(segment
		(start 52.115364 36.957)
		(end 50.972364 35.814)
		(width 0.254)
		(layer "In6.Cu")
		(net "NFP_VDD_CORE_ISEN2_N")
	)
	(segment
		(start 43.568163 37.0459)
		(end 43.187163 37.4269)
		(width 0.254)
		(layer "In6.Cu")
		(net "NFP_VDD_CORE_ISEN2_N")
	)
	(segment
		(start 41.17881 37.845975)
		(end 41.178785 37.846)
		(width 0.254)
		(layer "In6.Cu")
		(net "NFP_VDD_CORE_ISEN2_N")
	)
	(segment
		(start 47.467063 35.814)
		(end 46.451063 36.83)
		(width 0.254)
		(layer "In6.Cu")
		(net "NFP_VDD_CORE_ISEN2_N")
	)
	(segment
		(start 43.949264 36.83)
		(end 43.733364 37.0459)
		(width 0.254)
		(layer "In6.Cu")
		(net "NFP_VDD_CORE_ISEN2_N")
	)
	(segment
		(start 50.972364 35.814)
		(end 47.467063 35.814)
		(width 0.254)
		(layer "In6.Cu")
		(net "NFP_VDD_CORE_ISEN2_N")
	)
	(segment
		(start 42.7355 37.846)
		(end 41.178836 37.846)
		(width 0.254)
		(layer "In6.Cu")
		(net "NFP_VDD_CORE_ISEN2_N")
	)
	(segment
		(start 40.355164 38.34765)
		(end 38.552755 38.34765)
		(width 0.254)
		(layer "In6.Cu")
		(net "NFP_VDD_CORE_ISEN2_N")
	)
	(segment
		(start 38.552755 38.34765)
		(end 35.814 41.086405)
		(width 0.254)
		(layer "In6.Cu")
		(net "NFP_VDD_CORE_ISEN2_N")
	)
	(segment
		(start 43.187163 37.4269)
		(end 43.1546 37.4269)
		(width 0.254)
		(layer "In6.Cu")
		(net "NFP_VDD_CORE_ISEN2_N")
	)
	(segment
		(start 43.733364 37.0459)
		(end 43.568163 37.0459)
		(width 0.254)
		(layer "In6.Cu")
		(net "NFP_VDD_CORE_ISEN2_N")
	)
	(segment
		(start 41.178836 37.846)
		(end 41.17881 37.845975)
		(width 0.254)
		(layer "In6.Cu")
		(net "NFP_VDD_CORE_ISEN2_N")
	)
	(segment
		(start 36.7411 39.1287)
		(end 36.7411 39.878)
		(width 0.254)
		(layer "F.Cu")
		(net "NFP_VDD_CORE_ISEN1_P")
	)
	(segment
		(start 67.2211 36.5379)
		(end 67.31 36.449)
		(width 0.254)
		(layer "F.Cu")
		(net "NFP_VDD_CORE_ISEN1_P")
	)
	(segment
		(start 67.2211 36.957)
		(end 67.2211 36.5379)
		(width 0.254)
		(layer "F.Cu")
		(net "NFP_VDD_CORE_ISEN1_P")
	)
	(segment
		(start 67.31 36.449)
		(end 67.31 36.322)
		(width 0.254)
		(layer "F.Cu")
		(net "NFP_VDD_CORE_ISEN1_P")
	)
	(segment
		(start 67.31 36.322)
		(end 67.3735 36.2585)
		(width 0.254)
		(layer "F.Cu")
		(net "NFP_VDD_CORE_ISEN1_P")
	)
	(via
		(at 67.3735 36.2585)
		(size 0.508)
		(drill 0.254)
		(layers "F.Cu" "B.Cu")
		(net "NFP_VDD_CORE_ISEN1_P")
	)
	(via
		(at 36.7411 39.1287)
		(size 0.508)
		(drill 0.25654)
		(layers "F.Cu" "B.Cu")
		(net "NFP_VDD_CORE_ISEN1_P")
	)
	(segment
		(start 65.532025 35.306)
		(end 65.237919 35.011893)
		(width 0.254)
		(layer "In6.Cu")
		(net "NFP_VDD_CORE_ISEN1_P")
	)
	(segment
		(start 65.237919 35.011893)
		(end 55.372 35.011893)
		(width 0.254)
		(layer "In6.Cu")
		(net "NFP_VDD_CORE_ISEN1_P")
	)
	(segment
		(start 37.942164 36.703)
		(end 37.040464 37.6047)
		(width 0.254)
		(layer "In6.Cu")
		(net "NFP_VDD_CORE_ISEN1_P")
	)
	(segment
		(start 36.530636 37.6047)
		(end 36.2331 37.902236)
		(width 0.254)
		(layer "In6.Cu")
		(net "NFP_VDD_CORE_ISEN1_P")
	)
	(segment
		(start 54.396107 34.036)
		(end 45.593 34.036)
		(width 0.254)
		(layer "In6.Cu")
		(net "NFP_VDD_CORE_ISEN1_P")
	)
	(segment
		(start 44.267095 34.980905)
		(end 43.684393 35.563607)
		(width 0.254)
		(layer "In6.Cu")
		(net "NFP_VDD_CORE_ISEN1_P")
	)
	(segment
		(start 44.542329 34.072093)
		(end 44.267095 34.347328)
		(width 0.254)
		(layer "In6.Cu")
		(net "NFP_VDD_CORE_ISEN1_P")
	)
	(segment
		(start 41.198749 36.703)
		(end 37.942164 36.703)
		(width 0.254)
		(layer "In6.Cu")
		(net "NFP_VDD_CORE_ISEN1_P")
	)
	(segment
		(start 43.684393 35.563607)
		(end 42.338142 35.563607)
		(width 0.254)
		(layer "In6.Cu")
		(net "NFP_VDD_CORE_ISEN1_P")
	)
	(segment
		(start 45.593 34.036)
		(end 45.556907 34.072093)
		(width 0.254)
		(layer "In6.Cu")
		(net "NFP_VDD_CORE_ISEN1_P")
	)
	(segment
		(start 66.421 35.306)
		(end 65.532025 35.306)
		(width 0.254)
		(layer "In6.Cu")
		(net "NFP_VDD_CORE_ISEN1_P")
	)
	(segment
		(start 44.267095 34.347328)
		(end 44.267095 34.980905)
		(width 0.254)
		(layer "In6.Cu")
		(net "NFP_VDD_CORE_ISEN1_P")
	)
	(segment
		(start 36.2331 37.902236)
		(end 36.2331 38.5318)
		(width 0.254)
		(layer "In6.Cu")
		(net "NFP_VDD_CORE_ISEN1_P")
	)
	(segment
		(start 45.556907 34.072093)
		(end 44.542329 34.072093)
		(width 0.254)
		(layer "In6.Cu")
		(net "NFP_VDD_CORE_ISEN1_P")
	)
	(segment
		(start 67.3735 36.2585)
		(end 66.421 35.306)
		(width 0.254)
		(layer "In6.Cu")
		(net "NFP_VDD_CORE_ISEN1_P")
	)
	(segment
		(start 42.338142 35.563607)
		(end 41.198749 36.703)
		(width 0.254)
		(layer "In6.Cu")
		(net "NFP_VDD_CORE_ISEN1_P")
	)
	(segment
		(start 37.040464 37.6047)
		(end 36.530636 37.6047)
		(width 0.254)
		(layer "In6.Cu")
		(net "NFP_VDD_CORE_ISEN1_P")
	)
	(segment
		(start 55.372 35.011893)
		(end 54.396107 34.036)
		(width 0.254)
		(layer "In6.Cu")
		(net "NFP_VDD_CORE_ISEN1_P")
	)
	(segment
		(start 36.2331 38.5318)
		(end 36.7411 39.1287)
		(width 0.254)
		(layer "In6.Cu")
		(net "NFP_VDD_CORE_ISEN1_P")
	)
	(via
		(at 36.7411 38.1127)
		(size 0.508)
		(drill 0.25654)
		(layers "F.Cu" "B.Cu")
		(net "NFP_VDD_CORE_ISEN1_N")
	)
	(via
		(at 64.6049 36.83)
		(size 0.508)
		(drill 0.25654)
		(layers "F.Cu" "B.Cu")
		(net "NFP_VDD_CORE_ISEN1_N")
	)
	(segment
		(start 38.1 37.084)
		(end 37.0713 38.1127)
		(width 0.254)
		(layer "In6.Cu")
		(net "NFP_VDD_CORE_ISEN1_N")
	)
	(segment
		(start 42.495978 35.944607)
		(end 41.356585 37.084)
		(width 0.254)
		(layer "In6.Cu")
		(net "NFP_VDD_CORE_ISEN1_N")
	)
	(segment
		(start 66.294 36.83)
		(end 66.04 36.576)
		(width 0.254)
		(layer "In6.Cu")
		(net "NFP_VDD_CORE_ISEN1_N")
	)
	(segment
		(start 65.588236 36.576)
		(end 65.278 36.265764)
		(width 0.254)
		(layer "In6.Cu")
		(net "NFP_VDD_CORE_ISEN1_N")
	)
	(segment
		(start 55.214164 35.392893)
		(end 54.833164 35.011893)
		(width 0.254)
		(layer "In6.Cu")
		(net "NFP_VDD_CORE_ISEN1_N")
	)
	(segment
		(start 37.0713 38.1127)
		(end 36.7411 38.1127)
		(width 0.254)
		(layer "In6.Cu")
		(net "NFP_VDD_CORE_ISEN1_N")
	)
	(segment
		(start 64.6049 36.909096)
		(end 65.033804 37.338)
		(width 0.254)
		(layer "In6.Cu")
		(net "NFP_VDD_CORE_ISEN1_N")
	)
	(segment
		(start 66.04 37.338)
		(end 66.294 37.084)
		(width 0.254)
		(layer "In6.Cu")
		(net "NFP_VDD_CORE_ISEN1_N")
	)
	(segment
		(start 43.842229 35.944607)
		(end 42.495978 35.944607)
		(width 0.254)
		(layer "In6.Cu")
		(net "NFP_VDD_CORE_ISEN1_N")
	)
	(segment
		(start 44.774942 35.011893)
		(end 43.842229 35.944607)
		(width 0.254)
		(layer "In6.Cu")
		(net "NFP_VDD_CORE_ISEN1_N")
	)
	(segment
		(start 41.356585 37.084)
		(end 38.1 37.084)
		(width 0.254)
		(layer "In6.Cu")
		(net "NFP_VDD_CORE_ISEN1_N")
	)
	(segment
		(start 64.6049 36.83)
		(end 64.6049 36.909096)
		(width 0.254)
		(layer "In6.Cu")
		(net "NFP_VDD_CORE_ISEN1_N")
	)
	(segment
		(start 54.833164 35.011893)
		(end 44.774942 35.011893)
		(width 0.254)
		(layer "In6.Cu")
		(net "NFP_VDD_CORE_ISEN1_N")
	)
	(segment
		(start 65.278 35.646919)
		(end 65.023975 35.392893)
		(width 0.254)
		(layer "In6.Cu")
		(net "NFP_VDD_CORE_ISEN1_N")
	)
	(segment
		(start 66.294 37.084)
		(end 66.294 36.83)
		(width 0.254)
		(layer "In6.Cu")
		(net "NFP_VDD_CORE_ISEN1_N")
	)
	(segment
		(start 65.023975 35.392893)
		(end 55.214164 35.392893)
		(width 0.254)
		(layer "In6.Cu")
		(net "NFP_VDD_CORE_ISEN1_N")
	)
	(segment
		(start 65.278 36.265764)
		(end 65.278 35.646919)
		(width 0.254)
		(layer "In6.Cu")
		(net "NFP_VDD_CORE_ISEN1_N")
	)
	(segment
		(start 65.033804 37.338)
		(end 66.04 37.338)
		(width 0.254)
		(layer "In6.Cu")
		(net "NFP_VDD_CORE_ISEN1_N")
	)
	(segment
		(start 66.04 36.576)
		(end 65.588236 36.576)
		(width 0.254)
		(layer "In6.Cu")
		(net "NFP_VDD_CORE_ISEN1_N")
	)
	(via
		(at 25.4 45.9105)
		(size 0.508)
		(drill 0.254)
		(layers "F.Cu" "B.Cu")
		(net "NFP_UART_SR_TX")
	)
	(via
		(at 22.6187 28.2702)
		(size 0.508)
		(drill 0.25654)
		(layers "F.Cu" "B.Cu")
		(net "NFP_UART_SR_TX")
	)
	(via
		(at 43.18 46.228)
		(size 0.508)
		(drill 0.25654)
		(layers "F.Cu" "B.Cu")
		(net "NFP_UART_SR_TX")
	)
	(segment
		(start 25.4 47.8155)
		(end 25.4 45.9105)
		(width 0.14732)
		(layer "B.Cu")
		(net "NFP_UART_SR_TX")
	)
	(segment
		(start 23.3299 27.94)
		(end 22.9489 27.94)
		(width 0.14732)
		(layer "B.Cu")
		(net "NFP_UART_SR_TX")
	)
	(segment
		(start 22.9489 27.94)
		(end 22.6187 28.2702)
		(width 0.14732)
		(layer "B.Cu")
		(net "NFP_UART_SR_TX")
	)
	(segment
		(start 37.509983 48.823829)
		(end 38.547675 48.823829)
		(width 0.12065)
		(layer "In6.Cu")
		(net "NFP_UART_SR_TX")
	)
	(segment
		(start 36.885829 48.199675)
		(end 37.509983 48.823829)
		(width 0.12065)
		(layer "In6.Cu")
		(net "NFP_UART_SR_TX")
	)
	(segment
		(start 35.72383 48.180701)
		(end 35.736505 48.199675)
		(width 0.12065)
		(layer "In6.Cu")
		(net "NFP_UART_SR_TX")
	)
	(segment
		(start 32.636155 47.196375)
		(end 33.86135 47.196375)
		(width 0.12065)
		(layer "In6.Cu")
		(net "NFP_UART_SR_TX")
	)
	(segment
		(start 38.806171 49.082325)
		(end 39.69065 49.082325)
		(width 0.12065)
		(layer "In6.Cu")
		(net "NFP_UART_SR_TX")
	)
	(segment
		(start 43.18 47.360129)
		(end 43.18 46.228)
		(width 0.12065)
		(layer "In6.Cu")
		(net "NFP_UART_SR_TX")
	)
	(segment
		(start 32.255155 47.577375)
		(end 32.636155 47.196375)
		(width 0.12065)
		(layer "In6.Cu")
		(net "NFP_UART_SR_TX")
	)
	(segment
		(start 26.415898 46.99)
		(end 27.950871 46.99)
		(width 0.12065)
		(layer "In6.Cu")
		(net "NFP_UART_SR_TX")
	)
	(segment
		(start 39.69065 49.082325)
		(end 40.59235 48.180625)
		(width 0.12065)
		(layer "In6.Cu")
		(net "NFP_UART_SR_TX")
	)
	(segment
		(start 34.48365 47.818675)
		(end 35.361804 47.818675)
		(width 0.12065)
		(layer "In6.Cu")
		(net "NFP_UART_SR_TX")
	)
	(segment
		(start 30.135779 47.577375)
		(end 32.255155 47.577375)
		(width 0.12065)
		(layer "In6.Cu")
		(net "NFP_UART_SR_TX")
	)
	(segment
		(start 42.359504 48.180625)
		(end 43.18 47.360129)
		(width 0.12065)
		(layer "In6.Cu")
		(net "NFP_UART_SR_TX")
	)
	(segment
		(start 35.361804 47.818675)
		(end 35.72383 48.180701)
		(width 0.12065)
		(layer "In6.Cu")
		(net "NFP_UART_SR_TX")
	)
	(segment
		(start 25.4 45.9105)
		(end 25.4 45.974102)
		(width 0.12065)
		(layer "In6.Cu")
		(net "NFP_UART_SR_TX")
	)
	(segment
		(start 35.736505 48.199675)
		(end 36.885829 48.199675)
		(width 0.12065)
		(layer "In6.Cu")
		(net "NFP_UART_SR_TX")
	)
	(segment
		(start 33.86135 47.196375)
		(end 34.48365 47.818675)
		(width 0.12065)
		(layer "In6.Cu")
		(net "NFP_UART_SR_TX")
	)
	(segment
		(start 29.519829 48.193325)
		(end 30.135779 47.577375)
		(width 0.12065)
		(layer "In6.Cu")
		(net "NFP_UART_SR_TX")
	)
	(segment
		(start 29.154196 48.193325)
		(end 29.519829 48.193325)
		(width 0.12065)
		(layer "In6.Cu")
		(net "NFP_UART_SR_TX")
	)
	(segment
		(start 38.547675 48.823829)
		(end 38.806171 49.082325)
		(width 0.12065)
		(layer "In6.Cu")
		(net "NFP_UART_SR_TX")
	)
	(segment
		(start 25.4 45.974102)
		(end 26.415898 46.99)
		(width 0.12065)
		(layer "In6.Cu")
		(net "NFP_UART_SR_TX")
	)
	(segment
		(start 27.950871 46.99)
		(end 29.154196 48.193325)
		(width 0.12065)
		(layer "In6.Cu")
		(net "NFP_UART_SR_TX")
	)
	(segment
		(start 40.59235 48.180625)
		(end 42.359504 48.180625)
		(width 0.12065)
		(layer "In6.Cu")
		(net "NFP_UART_SR_TX")
	)
	(segment
		(start 24.765 39.444473)
		(end 23.622 40.587473)
		(width 0.12065)
		(layer "In7.Cu")
		(net "NFP_UART_SR_TX")
	)
	(segment
		(start 24.765 37.767946)
		(end 24.765 39.444473)
		(width 0.12065)
		(layer "In7.Cu")
		(net "NFP_UART_SR_TX")
	)
	(segment
		(start 24.892 29.591)
		(end 24.892 30.998846)
		(width 0.12065)
		(layer "In7.Cu")
		(net "NFP_UART_SR_TX")
	)
	(segment
		(start 23.622 40.587473)
		(end 23.622 45.085)
		(width 0.12065)
		(layer "In7.Cu")
		(net "NFP_UART_SR_TX")
	)
	(segment
		(start 22.6187 28.2702)
		(end 23.431449 29.082949)
		(width 0.12065)
		(layer "In7.Cu")
		(net "NFP_UART_SR_TX")
	)
	(segment
		(start 25.079325 31.186171)
		(end 25.079325 31.551829)
		(width 0.12065)
		(layer "In7.Cu")
		(net "NFP_UART_SR_TX")
	)
	(segment
		(start 25.019 31.612154)
		(end 25.019 34.9139)
		(width 0.12065)
		(layer "In7.Cu")
		(net "NFP_UART_SR_TX")
	)
	(segment
		(start 25.13965 35.03455)
		(end 25.13965 37.393296)
		(width 0.12065)
		(layer "In7.Cu")
		(net "NFP_UART_SR_TX")
	)
	(segment
		(start 24.383949 29.082949)
		(end 24.892 29.591)
		(width 0.12065)
		(layer "In7.Cu")
		(net "NFP_UART_SR_TX")
	)
	(segment
		(start 23.622 45.085)
		(end 24.384 45.847)
		(width 0.12065)
		(layer "In7.Cu")
		(net "NFP_UART_SR_TX")
	)
	(segment
		(start 25.079325 31.551829)
		(end 25.019 31.612154)
		(width 0.12065)
		(layer "In7.Cu")
		(net "NFP_UART_SR_TX")
	)
	(segment
		(start 25.3365 45.847)
		(end 25.4 45.9105)
		(width 0.12065)
		(layer "In7.Cu")
		(net "NFP_UART_SR_TX")
	)
	(segment
		(start 25.019 34.9139)
		(end 25.13965 35.03455)
		(width 0.12065)
		(layer "In7.Cu")
		(net "NFP_UART_SR_TX")
	)
	(segment
		(start 24.384 45.847)
		(end 25.3365 45.847)
		(width 0.12065)
		(layer "In7.Cu")
		(net "NFP_UART_SR_TX")
	)
	(segment
		(start 24.892 30.998846)
		(end 25.079325 31.186171)
		(width 0.12065)
		(layer "In7.Cu")
		(net "NFP_UART_SR_TX")
	)
	(segment
		(start 25.13965 37.393296)
		(end 24.765 37.767946)
		(width 0.12065)
		(layer "In7.Cu")
		(net "NFP_UART_SR_TX")
	)
	(segment
		(start 23.431449 29.082949)
		(end 24.383949 29.082949)
		(width 0.12065)
		(layer "In7.Cu")
		(net "NFP_UART_SR_TX")
	)
	(segment
		(start 40.237004 22.041993)
		(end 39.737005 22.541992)
		(width 0.13208)
		(layer "F.Cu")
		(net "NFP_UART_SR_RX")
	)
	(via
		(at 39.737005 22.541992)
		(size 0.4826)
		(drill 0.20574)
		(layers "F.Cu" "B.Cu")
		(net "NFP_UART_SR_RX")
	)
	(via
		(at 45.085 46.228)
		(size 0.508)
		(drill 0.25654)
		(layers "F.Cu" "B.Cu")
		(net "NFP_UART_SR_RX")
	)
	(via
		(at 25.4 44.577)
		(size 0.508)
		(drill 0.25654)
		(layers "F.Cu" "B.Cu")
		(net "NFP_UART_SR_RX")
	)
	(segment
		(start 41.010154 47.244)
		(end 41.451479 46.802675)
		(width 0.12065)
		(layer "In3.Cu")
		(net "NFP_UART_SR_RX")
	)
	(segment
		(start 41.451479 46.802675)
		(end 42.854829 46.802675)
		(width 0.12065)
		(layer "In3.Cu")
		(net "NFP_UART_SR_RX")
	)
	(segment
		(start 25.4 44.577)
		(end 25.650825 44.326175)
		(width 0.12065)
		(layer "In3.Cu")
		(net "NFP_UART_SR_RX")
	)
	(segment
		(start 44.45 46.863)
		(end 45.085 46.228)
		(width 0.12065)
		(layer "In3.Cu")
		(net "NFP_UART_SR_RX")
	)
	(segment
		(start 27.498675 45.204329)
		(end 27.757171 45.462825)
		(width 0.12065)
		(layer "In3.Cu")
		(net "NFP_UART_SR_RX")
	)
	(segment
		(start 27.757171 45.462825)
		(end 30.027728 45.462825)
		(width 0.12065)
		(layer "In3.Cu")
		(net "NFP_UART_SR_RX")
	)
	(segment
		(start 35.687 45.085)
		(end 35.687 45.847)
		(width 0.12065)
		(layer "In3.Cu")
		(net "NFP_UART_SR_RX")
	)
	(segment
		(start 36.449 46.609)
		(end 39.37 46.609)
		(width 0.12065)
		(layer "In3.Cu")
		(net "NFP_UART_SR_RX")
	)
	(segment
		(start 35.687 45.847)
		(end 36.449 46.609)
		(width 0.12065)
		(layer "In3.Cu")
		(net "NFP_UART_SR_RX")
	)
	(segment
		(start 31.164378 44.326175)
		(end 34.928175 44.326175)
		(width 0.12065)
		(layer "In3.Cu")
		(net "NFP_UART_SR_RX")
	)
	(segment
		(start 30.027728 45.462825)
		(end 31.164378 44.326175)
		(width 0.12065)
		(layer "In3.Cu")
		(net "NFP_UART_SR_RX")
	)
	(segment
		(start 39.37 46.609)
		(end 40.005 47.244)
		(width 0.12065)
		(layer "In3.Cu")
		(net "NFP_UART_SR_RX")
	)
	(segment
		(start 26.852829 44.326175)
		(end 27.498675 44.972021)
		(width 0.12065)
		(layer "In3.Cu")
		(net "NFP_UART_SR_RX")
	)
	(segment
		(start 34.928175 44.326175)
		(end 35.687 45.085)
		(width 0.12065)
		(layer "In3.Cu")
		(net "NFP_UART_SR_RX")
	)
	(segment
		(start 42.854829 46.802675)
		(end 42.915154 46.863)
		(width 0.12065)
		(layer "In3.Cu")
		(net "NFP_UART_SR_RX")
	)
	(segment
		(start 25.650825 44.326175)
		(end 26.852829 44.326175)
		(width 0.12065)
		(layer "In3.Cu")
		(net "NFP_UART_SR_RX")
	)
	(segment
		(start 42.915154 46.863)
		(end 44.45 46.863)
		(width 0.12065)
		(layer "In3.Cu")
		(net "NFP_UART_SR_RX")
	)
	(segment
		(start 27.498675 44.972021)
		(end 27.498675 45.204329)
		(width 0.12065)
		(layer "In3.Cu")
		(net "NFP_UART_SR_RX")
	)
	(segment
		(start 40.005 47.244)
		(end 41.010154 47.244)
		(width 0.12065)
		(layer "In3.Cu")
		(net "NFP_UART_SR_RX")
	)
	(segment
		(start 39.737005 22.541992)
		(end 40.259 23.063987)
		(width 0.12065)
		(layer "In7.Cu")
		(net "NFP_UART_SR_RX")
	)
	(segment
		(start 39.690675 44.516675)
		(end 40.64 45.466)
		(width 0.12065)
		(layer "In7.Cu")
		(net "NFP_UART_SR_RX")
	)
	(segment
		(start 40.259 35.306)
		(end 39.690675 35.874325)
		(width 0.12065)
		(layer "In7.Cu")
		(net "NFP_UART_SR_RX")
	)
	(segment
		(start 39.690675 35.874325)
		(end 39.690675 44.516675)
		(width 0.12065)
		(layer "In7.Cu")
		(net "NFP_UART_SR_RX")
	)
	(segment
		(start 44.323 45.466)
		(end 45.085 46.228)
		(width 0.12065)
		(layer "In7.Cu")
		(net "NFP_UART_SR_RX")
	)
	(segment
		(start 40.259 23.063987)
		(end 40.259 35.306)
		(width 0.12065)
		(layer "In7.Cu")
		(net "NFP_UART_SR_RX")
	)
	(segment
		(start 40.64 45.466)
		(end 44.323 45.466)
		(width 0.12065)
		(layer "In7.Cu")
		(net "NFP_UART_SR_RX")
	)
	(segment
		(start 42.237 23.041991)
		(end 41.737001 23.54199)
		(width 0.13208)
		(layer "F.Cu")
		(net "NFP_SRESET_L")
	)
	(via
		(at 28.6258 21.1074)
		(size 0.4572)
		(drill 0.20574)
		(layers "F.Cu" "B.Cu")
		(net "NFP_SRESET_L")
	)
	(via
		(at 41.737001 23.54199)
		(size 0.4826)
		(drill 0.20574)
		(layers "F.Cu" "B.Cu")
		(net "NFP_SRESET_L")
	)
	(segment
		(start 27.813 21.9329)
		(end 27.813 21.9202)
		(width 0.127)
		(layer "B.Cu")
		(net "NFP_SRESET_L")
	)
	(segment
		(start 27.813 21.9202)
		(end 28.6258 21.1074)
		(width 0.127)
		(layer "B.Cu")
		(net "NFP_SRESET_L")
	)
	(segment
		(start 28.745993 22.548393)
		(end 28.745993 21.227593)
		(width 0.127)
		(layer "In1.Cu")
		(net "NFP_SRESET_L")
	)
	(segment
		(start 28.745993 21.227593)
		(end 28.6258 21.1074)
		(width 0.127)
		(layer "In1.Cu")
		(net "NFP_SRESET_L")
	)
	(segment
		(start 30.063059 22.544659)
		(end 28.6258 21.1074)
		(width 0.12065)
		(layer "In6.Cu")
		(net "NFP_SRESET_L")
	)
	(segment
		(start 40.333778 22.709048)
		(end 40.333778 22.553778)
		(width 0.12065)
		(layer "In6.Cu")
		(net "NFP_SRESET_L")
	)
	(segment
		(start 40.73873 23.114)
		(end 40.333778 22.709048)
		(width 0.12065)
		(layer "In6.Cu")
		(net "NFP_SRESET_L")
	)
	(segment
		(start 37.907341 22.544659)
		(end 30.063059 22.544659)
		(width 0.12065)
		(layer "In6.Cu")
		(net "NFP_SRESET_L")
	)
	(segment
		(start 41.70299 23.54199)
		(end 41.275 23.114)
		(width 0.12065)
		(layer "In6.Cu")
		(net "NFP_SRESET_L")
	)
	(segment
		(start 40.333778 22.553778)
		(end 39.878 22.098)
		(width 0.12065)
		(layer "In6.Cu")
		(net "NFP_SRESET_L")
	)
	(segment
		(start 41.275 23.114)
		(end 40.73873 23.114)
		(width 0.12065)
		(layer "In6.Cu")
		(net "NFP_SRESET_L")
	)
	(segment
		(start 41.737001 23.54199)
		(end 41.70299 23.54199)
		(width 0.12065)
		(layer "In6.Cu")
		(net "NFP_SRESET_L")
	)
	(segment
		(start 38.354 22.098)
		(end 37.907341 22.544659)
		(width 0.12065)
		(layer "In6.Cu")
		(net "NFP_SRESET_L")
	)
	(segment
		(start 39.878 22.098)
		(end 38.354 22.098)
		(width 0.12065)
		(layer "In6.Cu")
		(net "NFP_SRESET_L")
	)
	(segment
		(start 27.94 19.304)
		(end 27.94 20.066)
		(width 0.14732)
		(layer "F.Cu")
		(net "NFP_PGOOD4")
	)
	(segment
		(start 27.94 20.066)
		(end 27.0129 20.9931)
		(width 0.14732)
		(layer "F.Cu")
		(net "NFP_PGOOD4")
	)
	(segment
		(start 43.236998 20.041997)
		(end 42.736999 20.541996)
		(width 0.13208)
		(layer "F.Cu")
		(net "NFP_PGOOD4")
	)
	(segment
		(start 27.813 19.177)
		(end 27.94 19.304)
		(width 0.14732)
		(layer "F.Cu")
		(net "NFP_PGOOD4")
	)
	(segment
		(start 27.516201 21.585301)
		(end 27.516201 21.8186)
		(width 0.127)
		(layer "F.Cu")
		(net "NFP_PGOOD4")
	)
	(segment
		(start 27.813 17.907)
		(end 27.813 19.177)
		(width 0.14732)
		(layer "F.Cu")
		(net "NFP_PGOOD4")
	)
	(segment
		(start 27.0129 20.9931)
		(end 26.924 20.9931)
		(width 0.14732)
		(layer "F.Cu")
		(net "NFP_PGOOD4")
	)
	(segment
		(start 26.924 20.9931)
		(end 27.516201 21.585301)
		(width 0.127)
		(layer "F.Cu")
		(net "NFP_PGOOD4")
	)
	(segment
		(start 27.516201 21.8186)
		(end 28.245994 22.548393)
		(width 0.127)
		(layer "F.Cu")
		(net "NFP_PGOOD4")
	)
	(via
		(at 26.924 20.9931)
		(size 0.4572)
		(drill 0.20574)
		(layers "F.Cu" "B.Cu")
		(net "NFP_PGOOD4")
	)
	(via
		(at 27.813 17.907)
		(size 0.762)
		(drill 0.381)
		(layers "F.Cu" "B.Cu")
		(net "NFP_PGOOD4")
	)
	(via
		(at 42.736999 20.541996)
		(size 0.4826)
		(drill 0.20574)
		(layers "F.Cu" "B.Cu")
		(net "NFP_PGOOD4")
	)
	(segment
		(start 27.2161 20.701)
		(end 27.396059 20.701)
		(width 0.12065)
		(layer "In6.Cu")
		(net "NFP_PGOOD4")
	)
	(segment
		(start 36.068 19.05)
		(end 37.118925 17.999075)
		(width 0.12065)
		(layer "In6.Cu")
		(net "NFP_PGOOD4")
	)
	(segment
		(start 42.736999 20.130999)
		(end 42.736999 20.541996)
		(width 0.12065)
		(layer "In6.Cu")
		(net "NFP_PGOOD4")
	)
	(segment
		(start 42.291 19.431)
		(end 42.291 19.685)
		(width 0.12065)
		(layer "In6.Cu")
		(net "NFP_PGOOD4")
	)
	(segment
		(start 33.390154 19.05)
		(end 36.068 19.05)
		(width 0.12065)
		(layer "In6.Cu")
		(net "NFP_PGOOD4")
	)
	(segment
		(start 29.047059 19.05)
		(end 32.903846 19.05)
		(width 0.12065)
		(layer "In6.Cu")
		(net "NFP_PGOOD4")
	)
	(segment
		(start 27.396059 20.701)
		(end 29.047059 19.05)
		(width 0.12065)
		(layer "In6.Cu")
		(net "NFP_PGOOD4")
	)
	(segment
		(start 32.964171 19.110325)
		(end 33.329829 19.110325)
		(width 0.12065)
		(layer "In6.Cu")
		(net "NFP_PGOOD4")
	)
	(segment
		(start 37.118925 17.999075)
		(end 40.859075 17.999075)
		(width 0.12065)
		(layer "In6.Cu")
		(net "NFP_PGOOD4")
	)
	(segment
		(start 32.903846 19.05)
		(end 32.964171 19.110325)
		(width 0.12065)
		(layer "In6.Cu")
		(net "NFP_PGOOD4")
	)
	(segment
		(start 42.291 19.685)
		(end 42.736999 20.130999)
		(width 0.12065)
		(layer "In6.Cu")
		(net "NFP_PGOOD4")
	)
	(segment
		(start 33.329829 19.110325)
		(end 33.390154 19.05)
		(width 0.12065)
		(layer "In6.Cu")
		(net "NFP_PGOOD4")
	)
	(segment
		(start 26.924 20.9931)
		(end 27.2161 20.701)
		(width 0.12065)
		(layer "In6.Cu")
		(net "NFP_PGOOD4")
	)
	(segment
		(start 40.859075 17.999075)
		(end 42.291 19.431)
		(width 0.12065)
		(layer "In6.Cu")
		(net "NFP_PGOOD4")
	)
	(segment
		(start 52.237005 6.042)
		(end 51.737006 5.542001)
		(width 0.138633)
		(layer "F.Cu")
		(net "NFP_PCIE0_PET7_P")
	)
	(via
		(at 51.737006 5.542001)
		(size 0.4826)
		(drill 0.20574)
		(layers "F.Cu" "B.Cu")
		(net "NFP_PCIE0_PET7_P")
	)
	(via
		(at 15.3924 22.1869)
		(size 0.762)
		(drill 0.254)
		(layers "F.Cu" "B.Cu")
		(net "NFP_PCIE0_PET7_P")
	)
	(segment
		(start 16.0274 22.8219)
		(end 15.3924 22.1869)
		(width 0.138633)
		(layer "B.Cu")
		(net "NFP_PCIE0_PET7_P")
	)
	(segment
		(start 22.687407 7.874)
		(end 21.396198 9.165209)
		(width 0.110185)
		(layer "In3.Cu")
		(net "NFP_PCIE0_PET7_P")
	)
	(segment
		(start 18.288025 9.525)
		(end 17.87713 9.935896)
		(width 0.110185)
		(layer "In3.Cu")
		(net "NFP_PCIE0_PET7_P")
	)
	(segment
		(start 47.671152 6.69483)
		(end 47.671152 7.406894)
		(width 0.106248)
		(layer "In3.Cu")
		(net "NFP_PCIE0_PET7_P")
	)
	(segment
		(start 34.869907 5.643093)
		(end 33.596834 6.916166)
		(width 0.110185)
		(layer "In3.Cu")
		(net "NFP_PCIE0_PET7_P")
	)
	(segment
		(start 47.108059 7.740015)
		(end 47.096832 7.74225)
		(width 0.106248)
		(layer "In3.Cu")
		(net "NFP_PCIE0_PET7_P")
	)
	(segment
		(start 20.585024 9.525)
		(end 18.288025 9.525)
		(width 0.110185)
		(layer "In3.Cu")
		(net "NFP_PCIE0_PET7_P")
	)
	(segment
		(start 30.640223 7.541209)
		(end 25.859765 7.541209)
		(width 0.110185)
		(layer "In3.Cu")
		(net "NFP_PCIE0_PET7_P")
	)
	(segment
		(start 43.133848 6.898894)
		(end 42.173042 5.938088)
		(width 0.106248)
		(layer "In3.Cu")
		(net "NFP_PCIE0_PET7_P")
	)
	(segment
		(start 17.732731 18.923)
		(end 17.187164 19.468567)
		(width 0.110185)
		(layer "In3.Cu")
		(net "NFP_PCIE0_PET7_P")
	)
	(segment
		(start 37.719 5.588)
		(end 35.757663 5.588)
		(width 0.110185)
		(layer "In3.Cu")
		(net "NFP_PCIE0_PET7_P")
	)
	(segment
		(start 43.133848 7.660894)
		(end 43.133848 6.898894)
		(width 0.106248)
		(layer "In3.Cu")
		(net "NFP_PCIE0_PET7_P")
	)
	(segment
		(start 38.354 5.936082)
		(end 38.067082 5.936082)
		(width 0.110185)
		(layer "In3.Cu")
		(net "NFP_PCIE0_PET7_P")
	)
	(segment
		(start 47.671152 7.406894)
		(end 47.338031 7.740015)
		(width 0.106248)
		(layer "In3.Cu")
		(net "NFP_PCIE0_PET7_P")
	)
	(segment
		(start 19.158966 16.626256)
		(end 19.158966 17.925034)
		(width 0.110185)
		(layer "In3.Cu")
		(net "NFP_PCIE0_PET7_P")
	)
	(segment
		(start 48.427894 5.938088)
		(end 47.671152 6.69483)
		(width 0.106248)
		(layer "In3.Cu")
		(net "NFP_PCIE0_PET7_P")
	)
	(segment
		(start 17.87713 9.935896)
		(end 17.87713 11.259947)
		(width 0.110185)
		(layer "In3.Cu")
		(net "NFP_PCIE0_PET7_P")
	)
	(segment
		(start 42.173042 5.938088)
		(end 38.38255 5.938088)
		(width 0.106248)
		(layer "In3.Cu")
		(net "NFP_PCIE0_PET7_P")
	)
	(segment
		(start 46.900973 7.93811)
		(end 43.411064 7.93811)
		(width 0.106248)
		(layer "In3.Cu")
		(net "NFP_PCIE0_PET7_P")
	)
	(segment
		(start 31.265266 6.916166)
		(end 30.640223 7.541209)
		(width 0.110185)
		(layer "In3.Cu")
		(net "NFP_PCIE0_PET7_P")
	)
	(segment
		(start 51.737006 5.542001)
		(end 51.340918 5.938088)
		(width 0.106248)
		(layer "In3.Cu")
		(net "NFP_PCIE0_PET7_P")
	)
	(segment
		(start 17.187164 22.391218)
		(end 16.8624 22.715982)
		(width 0.110185)
		(layer "In3.Cu")
		(net "NFP_PCIE0_PET7_P")
	)
	(segment
		(start 17.81683 15.28412)
		(end 19.158966 16.626256)
		(width 0.110185)
		(layer "In3.Cu")
		(net "NFP_PCIE0_PET7_P")
	)
	(segment
		(start 19.158966 17.925034)
		(end 18.161 18.923)
		(width 0.110185)
		(layer "In3.Cu")
		(net "NFP_PCIE0_PET7_P")
	)
	(segment
		(start 17.81683 11.320247)
		(end 17.81683 15.28412)
		(width 0.110185)
		(layer "In3.Cu")
		(net "NFP_PCIE0_PET7_P")
	)
	(segment
		(start 25.859765 7.541209)
		(end 25.526975 7.874)
		(width 0.110185)
		(layer "In3.Cu")
		(net "NFP_PCIE0_PET7_P")
	)
	(segment
		(start 21.396198 9.453778)
		(end 21.137778 9.712198)
		(width 0.110185)
		(layer "In3.Cu")
		(net "NFP_PCIE0_PET7_P")
	)
	(segment
		(start 47.338031 7.740015)
		(end 47.108059 7.740015)
		(width 0.106248)
		(layer "In3.Cu")
		(net "NFP_PCIE0_PET7_P")
	)
	(segment
		(start 18.161 18.923)
		(end 17.732731 18.923)
		(width 0.110185)
		(layer "In3.Cu")
		(net "NFP_PCIE0_PET7_P")
	)
	(segment
		(start 20.772222 9.712198)
		(end 20.585024 9.525)
		(width 0.110185)
		(layer "In3.Cu")
		(net "NFP_PCIE0_PET7_P")
	)
	(segment
		(start 21.396198 9.165209)
		(end 21.396198 9.453778)
		(width 0.110185)
		(layer "In3.Cu")
		(net "NFP_PCIE0_PET7_P")
	)
	(segment
		(start 15.921482 22.715982)
		(end 15.3924 22.1869)
		(width 0.110185)
		(layer "In3.Cu")
		(net "NFP_PCIE0_PET7_P")
	)
	(segment
		(start 21.137778 9.712198)
		(end 20.772222 9.712198)
		(width 0.110185)
		(layer "In3.Cu")
		(net "NFP_PCIE0_PET7_P")
	)
	(segment
		(start 38.38255 5.938088)
		(end 38.380543 5.936082)
		(width 0.106248)
		(layer "In3.Cu")
		(net "NFP_PCIE0_PET7_P")
	)
	(segment
		(start 35.757663 5.588)
		(end 35.70257 5.643093)
		(width 0.110185)
		(layer "In3.Cu")
		(net "NFP_PCIE0_PET7_P")
	)
	(segment
		(start 33.596834 6.916166)
		(end 31.265266 6.916166)
		(width 0.110185)
		(layer "In3.Cu")
		(net "NFP_PCIE0_PET7_P")
	)
	(segment
		(start 47.096832 7.74225)
		(end 46.900973 7.93811)
		(width 0.106248)
		(layer "In3.Cu")
		(net "NFP_PCIE0_PET7_P")
	)
	(segment
		(start 17.187164 19.468567)
		(end 17.187164 22.391218)
		(width 0.110185)
		(layer "In3.Cu")
		(net "NFP_PCIE0_PET7_P")
	)
	(segment
		(start 43.411064 7.93811)
		(end 43.133848 7.660894)
		(width 0.106248)
		(layer "In3.Cu")
		(net "NFP_PCIE0_PET7_P")
	)
	(segment
		(start 38.067082 5.936082)
		(end 37.719 5.588)
		(width 0.110185)
		(layer "In3.Cu")
		(net "NFP_PCIE0_PET7_P")
	)
	(segment
		(start 17.87713 11.259947)
		(end 17.81683 11.320247)
		(width 0.110185)
		(layer "In3.Cu")
		(net "NFP_PCIE0_PET7_P")
	)
	(segment
		(start 25.526975 7.874)
		(end 22.687407 7.874)
		(width 0.110185)
		(layer "In3.Cu")
		(net "NFP_PCIE0_PET7_P")
	)
	(segment
		(start 35.70257 5.643093)
		(end 34.869907 5.643093)
		(width 0.110185)
		(layer "In3.Cu")
		(net "NFP_PCIE0_PET7_P")
	)
	(segment
		(start 38.380543 5.936082)
		(end 38.354 5.936082)
		(width 0.106248)
		(layer "In3.Cu")
		(net "NFP_PCIE0_PET7_P")
	)
	(segment
		(start 51.340918 5.938088)
		(end 48.427894 5.938088)
		(width 0.106248)
		(layer "In3.Cu")
		(net "NFP_PCIE0_PET7_P")
	)
	(segment
		(start 16.8624 22.715982)
		(end 15.921482 22.715982)
		(width 0.110185)
		(layer "In3.Cu")
		(net "NFP_PCIE0_PET7_P")
	)
	(segment
		(start 52.237005 7.041998)
		(end 51.737006 6.541999)
		(width 0.138633)
		(layer "F.Cu")
		(net "NFP_PCIE0_PET7_N")
	)
	(via
		(at 51.737006 6.541999)
		(size 0.4826)
		(drill 0.20574)
		(layers "F.Cu" "B.Cu")
		(net "NFP_PCIE0_PET7_N")
	)
	(via
		(at 15.3924 23.4569)
		(size 0.762)
		(drill 0.2667)
		(layers "F.Cu" "B.Cu")
		(net "NFP_PCIE0_PET7_N")
	)
	(segment
		(start 16.0274 24.0919)
		(end 15.3924 23.4569)
		(width 0.138633)
		(layer "B.Cu")
		(net "NFP_PCIE0_PET7_N")
	)
	(segment
		(start 19.370802 16.538499)
		(end 19.370802 18.012791)
		(width 0.110185)
		(layer "In3.Cu")
		(net "NFP_PCIE0_PET7_N")
	)
	(segment
		(start 47.185174 7.947863)
		(end 46.987079 8.145958)
		(width 0.106248)
		(layer "In3.Cu")
		(net "NFP_PCIE0_PET7_N")
	)
	(segment
		(start 51.340944 6.145936)
		(end 48.514 6.145936)
		(width 0.106248)
		(layer "In3.Cu")
		(net "NFP_PCIE0_PET7_N")
	)
	(segment
		(start 38.354 6.147918)
		(end 37.979325 6.147918)
		(width 0.110185)
		(layer "In3.Cu")
		(net "NFP_PCIE0_PET7_N")
	)
	(segment
		(start 30.72798 7.753045)
		(end 25.947522 7.753045)
		(width 0.110185)
		(layer "In3.Cu")
		(net "NFP_PCIE0_PET7_N")
	)
	(segment
		(start 22.775164 8.085836)
		(end 21.608034 9.252966)
		(width 0.110185)
		(layer "In3.Cu")
		(net "NFP_PCIE0_PET7_N")
	)
	(segment
		(start 20.497267 9.736836)
		(end 18.375782 9.736836)
		(width 0.110185)
		(layer "In3.Cu")
		(net "NFP_PCIE0_PET7_N")
	)
	(segment
		(start 43.324958 8.145958)
		(end 42.926 7.747)
		(width 0.106248)
		(layer "In3.Cu")
		(net "NFP_PCIE0_PET7_N")
	)
	(segment
		(start 51.737006 6.541999)
		(end 51.340944 6.145936)
		(width 0.106248)
		(layer "In3.Cu")
		(net "NFP_PCIE0_PET7_N")
	)
	(segment
		(start 38.382524 6.145936)
		(end 38.380543 6.147918)
		(width 0.106248)
		(layer "In3.Cu")
		(net "NFP_PCIE0_PET7_N")
	)
	(segment
		(start 46.987079 8.145958)
		(end 43.324958 8.145958)
		(width 0.106248)
		(layer "In3.Cu")
		(net "NFP_PCIE0_PET7_N")
	)
	(segment
		(start 35.84542 5.799836)
		(end 35.790327 5.854929)
		(width 0.110185)
		(layer "In3.Cu")
		(net "NFP_PCIE0_PET7_N")
	)
	(segment
		(start 42.926 6.985)
		(end 42.086936 6.145936)
		(width 0.106248)
		(layer "In3.Cu")
		(net "NFP_PCIE0_PET7_N")
	)
	(segment
		(start 19.370802 18.012791)
		(end 18.248757 19.134836)
		(width 0.110185)
		(layer "In3.Cu")
		(net "NFP_PCIE0_PET7_N")
	)
	(segment
		(start 37.979325 6.147918)
		(end 37.631243 5.799836)
		(width 0.110185)
		(layer "In3.Cu")
		(net "NFP_PCIE0_PET7_N")
	)
	(segment
		(start 17.399 22.478975)
		(end 16.950157 22.927818)
		(width 0.110185)
		(layer "In3.Cu")
		(net "NFP_PCIE0_PET7_N")
	)
	(segment
		(start 18.375782 9.736836)
		(end 18.088966 10.023653)
		(width 0.110185)
		(layer "In3.Cu")
		(net "NFP_PCIE0_PET7_N")
	)
	(segment
		(start 35.790327 5.854929)
		(end 34.957664 5.854929)
		(width 0.110185)
		(layer "In3.Cu")
		(net "NFP_PCIE0_PET7_N")
	)
	(segment
		(start 25.947522 7.753045)
		(end 25.614732 8.085836)
		(width 0.110185)
		(layer "In3.Cu")
		(net "NFP_PCIE0_PET7_N")
	)
	(segment
		(start 18.028666 11.408004)
		(end 18.028666 15.196363)
		(width 0.110185)
		(layer "In3.Cu")
		(net "NFP_PCIE0_PET7_N")
	)
	(segment
		(start 48.514 6.145936)
		(end 47.879 6.780936)
		(width 0.106248)
		(layer "In3.Cu")
		(net "NFP_PCIE0_PET7_N")
	)
	(segment
		(start 47.424137 7.947863)
		(end 47.185174 7.947863)
		(width 0.106248)
		(layer "In3.Cu")
		(net "NFP_PCIE0_PET7_N")
	)
	(segment
		(start 21.608034 9.252966)
		(end 21.608034 9.541535)
		(width 0.110185)
		(layer "In3.Cu")
		(net "NFP_PCIE0_PET7_N")
	)
	(segment
		(start 42.086936 6.145936)
		(end 38.382524 6.145936)
		(width 0.106248)
		(layer "In3.Cu")
		(net "NFP_PCIE0_PET7_N")
	)
	(segment
		(start 17.820488 19.134836)
		(end 17.399 19.556324)
		(width 0.110185)
		(layer "In3.Cu")
		(net "NFP_PCIE0_PET7_N")
	)
	(segment
		(start 20.684465 9.924034)
		(end 20.497267 9.736836)
		(width 0.110185)
		(layer "In3.Cu")
		(net "NFP_PCIE0_PET7_N")
	)
	(segment
		(start 18.088966 11.347704)
		(end 18.028666 11.408004)
		(width 0.110185)
		(layer "In3.Cu")
		(net "NFP_PCIE0_PET7_N")
	)
	(segment
		(start 31.353023 7.128002)
		(end 30.72798 7.753045)
		(width 0.110185)
		(layer "In3.Cu")
		(net "NFP_PCIE0_PET7_N")
	)
	(segment
		(start 47.879 6.780936)
		(end 47.879 7.493)
		(width 0.106248)
		(layer "In3.Cu")
		(net "NFP_PCIE0_PET7_N")
	)
	(segment
		(start 16.950157 22.927818)
		(end 15.921482 22.927818)
		(width 0.110185)
		(layer "In3.Cu")
		(net "NFP_PCIE0_PET7_N")
	)
	(segment
		(start 21.225535 9.924034)
		(end 20.684465 9.924034)
		(width 0.110185)
		(layer "In3.Cu")
		(net "NFP_PCIE0_PET7_N")
	)
	(segment
		(start 34.957664 5.854929)
		(end 33.684591 7.128002)
		(width 0.110185)
		(layer "In3.Cu")
		(net "NFP_PCIE0_PET7_N")
	)
	(segment
		(start 18.028666 15.196363)
		(end 19.370802 16.538499)
		(width 0.110185)
		(layer "In3.Cu")
		(net "NFP_PCIE0_PET7_N")
	)
	(segment
		(start 47.879 7.493)
		(end 47.424137 7.947863)
		(width 0.106248)
		(layer "In3.Cu")
		(net "NFP_PCIE0_PET7_N")
	)
	(segment
		(start 42.926 7.747)
		(end 42.926 6.985)
		(width 0.106248)
		(layer "In3.Cu")
		(net "NFP_PCIE0_PET7_N")
	)
	(segment
		(start 25.614732 8.085836)
		(end 22.775164 8.085836)
		(width 0.110185)
		(layer "In3.Cu")
		(net "NFP_PCIE0_PET7_N")
	)
	(segment
		(start 15.921482 22.927818)
		(end 15.3924 23.4569)
		(width 0.110185)
		(layer "In3.Cu")
		(net "NFP_PCIE0_PET7_N")
	)
	(segment
		(start 33.684591 7.128002)
		(end 31.353023 7.128002)
		(width 0.110185)
		(layer "In3.Cu")
		(net "NFP_PCIE0_PET7_N")
	)
	(segment
		(start 18.248757 19.134836)
		(end 17.820488 19.134836)
		(width 0.110185)
		(layer "In3.Cu")
		(net "NFP_PCIE0_PET7_N")
	)
	(segment
		(start 18.088966 10.023653)
		(end 18.088966 11.347704)
		(width 0.110185)
		(layer "In3.Cu")
		(net "NFP_PCIE0_PET7_N")
	)
	(segment
		(start 21.608034 9.541535)
		(end 21.225535 9.924034)
		(width 0.110185)
		(layer "In3.Cu")
		(net "NFP_PCIE0_PET7_N")
	)
	(segment
		(start 38.380543 6.147918)
		(end 38.354 6.147918)
		(width 0.106248)
		(layer "In3.Cu")
		(net "NFP_PCIE0_PET7_N")
	)
	(segment
		(start 17.399 19.556324)
		(end 17.399 22.478975)
		(width 0.110185)
		(layer "In3.Cu")
		(net "NFP_PCIE0_PET7_N")
	)
	(segment
		(start 37.631243 5.799836)
		(end 35.84542 5.799836)
		(width 0.110185)
		(layer "In3.Cu")
		(net "NFP_PCIE0_PET7_N")
	)
	(segment
		(start 53.237003 7.041998)
		(end 52.737004 6.541999)
		(width 0.138633)
		(layer "F.Cu")
		(net "NFP_PCIE0_PET6_P")
	)
	(via
		(at 52.737004 6.541999)
		(size 0.4826)
		(drill 0.20574)
		(layers "F.Cu" "B.Cu")
		(net "NFP_PCIE0_PET6_P")
	)
	(via
		(at 17.9324 19.6469)
		(size 0.762)
		(drill 0.254)
		(layers "F.Cu" "B.Cu")
		(net "NFP_PCIE0_PET6_P")
	)
	(segment
		(start 17.2974 20.2819)
		(end 17.9324 19.6469)
		(width 0.138633)
		(layer "B.Cu")
		(net "NFP_PCIE0_PET6_P")
	)
	(segment
		(start 52.737004 6.541999)
		(end 52.737004 6.952996)
		(width 0.106248)
		(layer "In2.Cu")
		(net "NFP_PCIE0_PET6_P")
	)
	(segment
		(start 22.995687 12.768631)
		(end 22.664369 12.768631)
		(width 0.110185)
		(layer "In2.Cu")
		(net "NFP_PCIE0_PET6_P")
	)
	(segment
		(start 29.291407 9.398)
		(end 29.104209 9.585198)
		(width 0.110185)
		(layer "In2.Cu")
		(net "NFP_PCIE0_PET6_P")
	)
	(segment
		(start 38.987146 6.938086)
		(end 38.572973 6.938086)
		(width 0.106248)
		(layer "In2.Cu")
		(net "NFP_PCIE0_PET6_P")
	)
	(segment
		(start 52.133119 9.74791)
		(end 51.943 9.938029)
		(width 0.106248)
		(layer "In2.Cu")
		(net "NFP_PCIE0_PET6_P")
	)
	(segment
		(start 40.561108 8.938108)
		(end 39.340968 7.717968)
		(width 0.106248)
		(layer "In2.Cu")
		(net "NFP_PCIE0_PET6_P")
	)
	(segment
		(start 37.354535 6.839966)
		(end 35.405416 6.839966)
		(width 0.110185)
		(layer "In2.Cu")
		(net "NFP_PCIE0_PET6_P")
	)
	(segment
		(start 39.340968 7.291908)
		(end 38.987146 6.938086)
		(width 0.106248)
		(layer "In2.Cu")
		(net "NFP_PCIE0_PET6_P")
	)
	(segment
		(start 42.340886 9.291828)
		(end 41.987191 8.938108)
		(width 0.106248)
		(layer "In2.Cu")
		(net "NFP_PCIE0_PET6_P")
	)
	(segment
		(start 23.343032 12.089968)
		(end 23.343032 12.421286)
		(width 0.110185)
		(layer "In2.Cu")
		(net "NFP_PCIE0_PET6_P")
	)
	(segment
		(start 20.32 18.496382)
		(end 18.850559 19.965822)
		(width 0.110185)
		(layer "In2.Cu")
		(net "NFP_PCIE0_PET6_P")
	)
	(segment
		(start 39.340968 7.717968)
		(end 39.340968 7.291908)
		(width 0.106248)
		(layer "In2.Cu")
		(net "NFP_PCIE0_PET6_P")
	)
	(segment
		(start 26.355599 9.585198)
		(end 25.273127 10.668)
		(width 0.110185)
		(layer "In2.Cu")
		(net "NFP_PCIE0_PET6_P")
	)
	(segment
		(start 20.32 15.113)
		(end 20.32 18.496382)
		(width 0.110185)
		(layer "In2.Cu")
		(net "NFP_PCIE0_PET6_P")
	)
	(segment
		(start 18.850559 19.965822)
		(end 18.251322 19.965822)
		(width 0.110185)
		(layer "In2.Cu")
		(net "NFP_PCIE0_PET6_P")
	)
	(segment
		(start 23.902162 12.980416)
		(end 23.902162 13.13622)
		(width 0.110185)
		(layer "In2.Cu")
		(net "NFP_PCIE0_PET6_P")
	)
	(segment
		(start 35.253473 6.845071)
		(end 32.700544 9.398)
		(width 0.110185)
		(layer "In2.Cu")
		(net "NFP_PCIE0_PET6_P")
	)
	(segment
		(start 23.554817 13.327761)
		(end 22.995687 12.768631)
		(width 0.110185)
		(layer "In2.Cu")
		(net "NFP_PCIE0_PET6_P")
	)
	(segment
		(start 38.353009 6.94276)
		(end 38.350546 6.945224)
		(width 0.106248)
		(layer "In2.Cu")
		(net "NFP_PCIE0_PET6_P")
	)
	(segment
		(start 42.489984 9.938029)
		(end 42.340886 9.788931)
		(width 0.106248)
		(layer "In2.Cu")
		(net "NFP_PCIE0_PET6_P")
	)
	(segment
		(start 35.405416 6.839966)
		(end 35.40031 6.845071)
		(width 0.110185)
		(layer "In2.Cu")
		(net "NFP_PCIE0_PET6_P")
	)
	(segment
		(start 38.344907 6.945224)
		(end 38.26797 7.02216)
		(width 0.106248)
		(layer "In2.Cu")
		(net "NFP_PCIE0_PET6_P")
	)
	(segment
		(start 23.343032 12.421286)
		(end 23.902162 12.980416)
		(width 0.110185)
		(layer "In2.Cu")
		(net "NFP_PCIE0_PET6_P")
	)
	(segment
		(start 38.26797 7.02216)
		(end 37.53673 7.02216)
		(width 0.110185)
		(layer "In2.Cu")
		(net "NFP_PCIE0_PET6_P")
	)
	(segment
		(start 42.340886 9.788931)
		(end 42.340886 9.291828)
		(width 0.106248)
		(layer "In2.Cu")
		(net "NFP_PCIE0_PET6_P")
	)
	(segment
		(start 24.765 10.668)
		(end 23.343032 12.089968)
		(width 0.110185)
		(layer "In2.Cu")
		(net "NFP_PCIE0_PET6_P")
	)
	(segment
		(start 41.987191 8.938108)
		(end 40.561108 8.938108)
		(width 0.106248)
		(layer "In2.Cu")
		(net "NFP_PCIE0_PET6_P")
	)
	(segment
		(start 18.251322 19.965822)
		(end 17.9324 19.6469)
		(width 0.110185)
		(layer "In2.Cu")
		(net "NFP_PCIE0_PET6_P")
	)
	(segment
		(start 35.40031 6.845071)
		(end 35.253473 6.845071)
		(width 0.110185)
		(layer "In2.Cu")
		(net "NFP_PCIE0_PET6_P")
	)
	(segment
		(start 23.902162 13.13622)
		(end 23.710621 13.327761)
		(width 0.110185)
		(layer "In2.Cu")
		(net "NFP_PCIE0_PET6_P")
	)
	(segment
		(start 23.710621 13.327761)
		(end 23.554817 13.327761)
		(width 0.110185)
		(layer "In2.Cu")
		(net "NFP_PCIE0_PET6_P")
	)
	(segment
		(start 51.943 9.938029)
		(end 42.489984 9.938029)
		(width 0.106248)
		(layer "In2.Cu")
		(net "NFP_PCIE0_PET6_P")
	)
	(segment
		(start 52.133119 7.556881)
		(end 52.133119 9.74791)
		(width 0.106248)
		(layer "In2.Cu")
		(net "NFP_PCIE0_PET6_P")
	)
	(segment
		(start 22.664369 12.768631)
		(end 20.32 15.113)
		(width 0.110185)
		(layer "In2.Cu")
		(net "NFP_PCIE0_PET6_P")
	)
	(segment
		(start 38.572973 6.938086)
		(end 38.5683 6.94276)
		(width 0.106248)
		(layer "In2.Cu")
		(net "NFP_PCIE0_PET6_P")
	)
	(segment
		(start 52.737004 6.952996)
		(end 52.133119 7.556881)
		(width 0.106248)
		(layer "In2.Cu")
		(net "NFP_PCIE0_PET6_P")
	)
	(segment
		(start 32.700544 9.398)
		(end 29.291407 9.398)
		(width 0.110185)
		(layer "In2.Cu")
		(net "NFP_PCIE0_PET6_P")
	)
	(segment
		(start 29.104209 9.585198)
		(end 26.355599 9.585198)
		(width 0.110185)
		(layer "In2.Cu")
		(net "NFP_PCIE0_PET6_P")
	)
	(segment
		(start 38.350546 6.945224)
		(end 38.344907 6.945224)
		(width 0.106248)
		(layer "In2.Cu")
		(net "NFP_PCIE0_PET6_P")
	)
	(segment
		(start 37.53673 7.02216)
		(end 37.354535 6.839966)
		(width 0.110185)
		(layer "In2.Cu")
		(net "NFP_PCIE0_PET6_P")
	)
	(segment
		(start 25.273127 10.668)
		(end 24.765 10.668)
		(width 0.110185)
		(layer "In2.Cu")
		(net "NFP_PCIE0_PET6_P")
	)
	(segment
		(start 38.5683 6.94276)
		(end 38.353009 6.94276)
		(width 0.106248)
		(layer "In2.Cu")
		(net "NFP_PCIE0_PET6_P")
	)
	(segment
		(start 53.237003 8.041996)
		(end 52.737004 7.541997)
		(width 0.138633)
		(layer "F.Cu")
		(net "NFP_PCIE0_PET6_N")
	)
	(via
		(at 52.737004 7.541997)
		(size 0.4826)
		(drill 0.20574)
		(layers "F.Cu" "B.Cu")
		(net "NFP_PCIE0_PET6_N")
	)
	(via
		(at 17.9324 20.9169)
		(size 0.762)
		(drill 0.2667)
		(layers "F.Cu" "B.Cu")
		(net "NFP_PCIE0_PET6_N")
	)
	(segment
		(start 17.2974 21.5519)
		(end 17.9324 20.9169)
		(width 0.138633)
		(layer "B.Cu")
		(net "NFP_PCIE0_PET6_N")
	)
	(segment
		(start 38.26797 7.233996)
		(end 37.448973 7.233996)
		(width 0.110185)
		(layer "In2.Cu")
		(net "NFP_PCIE0_PET6_N")
	)
	(segment
		(start 24.113998 12.892659)
		(end 24.113998 13.223977)
		(width 0.110185)
		(layer "In2.Cu")
		(net "NFP_PCIE0_PET6_N")
	)
	(segment
		(start 22.752126 12.980467)
		(end 20.531836 15.200757)
		(width 0.110185)
		(layer "In2.Cu")
		(net "NFP_PCIE0_PET6_N")
	)
	(segment
		(start 29.191966 9.797034)
		(end 26.443381 9.797034)
		(width 0.110185)
		(layer "In2.Cu")
		(net "NFP_PCIE0_PET6_N")
	)
	(segment
		(start 26.443381 9.797034)
		(end 25.360909 10.879836)
		(width 0.110185)
		(layer "In2.Cu")
		(net "NFP_PCIE0_PET6_N")
	)
	(segment
		(start 35.34123 7.056907)
		(end 32.788301 9.609836)
		(width 0.110185)
		(layer "In2.Cu")
		(net "NFP_PCIE0_PET6_N")
	)
	(segment
		(start 18.176316 20.177658)
		(end 17.932298 20.421676)
		(width 0.110185)
		(layer "In2.Cu")
		(net "NFP_PCIE0_PET6_N")
	)
	(segment
		(start 52.737004 7.541997)
		(end 52.447215 7.541997)
		(width 0.106248)
		(layer "In2.Cu")
		(net "NFP_PCIE0_PET6_N")
	)
	(segment
		(start 38.659079 7.145934)
		(end 38.654406 7.150608)
		(width 0.106248)
		(layer "In2.Cu")
		(net "NFP_PCIE0_PET6_N")
	)
	(segment
		(start 40.475002 9.145956)
		(end 39.13312 7.804074)
		(width 0.106248)
		(layer "In2.Cu")
		(net "NFP_PCIE0_PET6_N")
	)
	(segment
		(start 42.133037 9.377934)
		(end 41.901085 9.145956)
		(width 0.106248)
		(layer "In2.Cu")
		(net "NFP_PCIE0_PET6_N")
	)
	(segment
		(start 18.938316 20.177658)
		(end 18.176316 20.177658)
		(width 0.110185)
		(layer "In2.Cu")
		(net "NFP_PCIE0_PET6_N")
	)
	(segment
		(start 39.13312 7.804074)
		(end 39.13312 7.378014)
		(width 0.106248)
		(layer "In2.Cu")
		(net "NFP_PCIE0_PET6_N")
	)
	(segment
		(start 35.488067 7.056907)
		(end 35.34123 7.056907)
		(width 0.110185)
		(layer "In2.Cu")
		(net "NFP_PCIE0_PET6_N")
	)
	(segment
		(start 23.798378 13.539597)
		(end 23.46706 13.539597)
		(width 0.110185)
		(layer "In2.Cu")
		(net "NFP_PCIE0_PET6_N")
	)
	(segment
		(start 35.493173 7.051802)
		(end 35.488067 7.056907)
		(width 0.110185)
		(layer "In2.Cu")
		(net "NFP_PCIE0_PET6_N")
	)
	(segment
		(start 24.113998 13.223977)
		(end 23.798378 13.539597)
		(width 0.110185)
		(layer "In2.Cu")
		(net "NFP_PCIE0_PET6_N")
	)
	(segment
		(start 38.436271 7.150608)
		(end 38.354889 7.23199)
		(width 0.106248)
		(layer "In2.Cu")
		(net "NFP_PCIE0_PET6_N")
	)
	(segment
		(start 52.340967 7.648245)
		(end 52.340967 9.834016)
		(width 0.106248)
		(layer "In2.Cu")
		(net "NFP_PCIE0_PET6_N")
	)
	(segment
		(start 38.354889 7.23199)
		(end 38.294539 7.23199)
		(width 0.106248)
		(layer "In2.Cu")
		(net "NFP_PCIE0_PET6_N")
	)
	(segment
		(start 32.788301 9.609836)
		(end 29.379164 9.609836)
		(width 0.110185)
		(layer "In2.Cu")
		(net "NFP_PCIE0_PET6_N")
	)
	(segment
		(start 20.531836 15.200757)
		(end 20.531836 18.584139)
		(width 0.110185)
		(layer "In2.Cu")
		(net "NFP_PCIE0_PET6_N")
	)
	(segment
		(start 25.360909 10.879836)
		(end 24.852757 10.879836)
		(width 0.110185)
		(layer "In2.Cu")
		(net "NFP_PCIE0_PET6_N")
	)
	(segment
		(start 52.029106 10.145878)
		(end 42.403878 10.145878)
		(width 0.106248)
		(layer "In2.Cu")
		(net "NFP_PCIE0_PET6_N")
	)
	(segment
		(start 38.292532 7.233996)
		(end 38.26797 7.233996)
		(width 0.106248)
		(layer "In2.Cu")
		(net "NFP_PCIE0_PET6_N")
	)
	(segment
		(start 23.46706 13.539597)
		(end 22.90793 12.980467)
		(width 0.110185)
		(layer "In2.Cu")
		(net "NFP_PCIE0_PET6_N")
	)
	(segment
		(start 38.90104 7.145934)
		(end 38.659079 7.145934)
		(width 0.106248)
		(layer "In2.Cu")
		(net "NFP_PCIE0_PET6_N")
	)
	(segment
		(start 17.932298 20.421676)
		(end 17.932298 20.916798)
		(width 0.110185)
		(layer "In2.Cu")
		(net "NFP_PCIE0_PET6_N")
	)
	(segment
		(start 22.90793 12.980467)
		(end 22.752126 12.980467)
		(width 0.110185)
		(layer "In2.Cu")
		(net "NFP_PCIE0_PET6_N")
	)
	(segment
		(start 37.448973 7.233996)
		(end 37.266778 7.051802)
		(width 0.110185)
		(layer "In2.Cu")
		(net "NFP_PCIE0_PET6_N")
	)
	(segment
		(start 52.447215 7.541997)
		(end 52.340967 7.648245)
		(width 0.106248)
		(layer "In2.Cu")
		(net "NFP_PCIE0_PET6_N")
	)
	(segment
		(start 29.379164 9.609836)
		(end 29.191966 9.797034)
		(width 0.110185)
		(layer "In2.Cu")
		(net "NFP_PCIE0_PET6_N")
	)
	(segment
		(start 20.531836 18.584139)
		(end 18.938316 20.177658)
		(width 0.110185)
		(layer "In2.Cu")
		(net "NFP_PCIE0_PET6_N")
	)
	(segment
		(start 42.133037 9.875037)
		(end 42.133037 9.377934)
		(width 0.106248)
		(layer "In2.Cu")
		(net "NFP_PCIE0_PET6_N")
	)
	(segment
		(start 41.901085 9.145956)
		(end 40.475002 9.145956)
		(width 0.106248)
		(layer "In2.Cu")
		(net "NFP_PCIE0_PET6_N")
	)
	(segment
		(start 23.554868 12.333529)
		(end 24.113998 12.892659)
		(width 0.110185)
		(layer "In2.Cu")
		(net "NFP_PCIE0_PET6_N")
	)
	(segment
		(start 23.554868 12.177725)
		(end 23.554868 12.333529)
		(width 0.110185)
		(layer "In2.Cu")
		(net "NFP_PCIE0_PET6_N")
	)
	(segment
		(start 42.403878 10.145878)
		(end 42.133037 9.875037)
		(width 0.106248)
		(layer "In2.Cu")
		(net "NFP_PCIE0_PET6_N")
	)
	(segment
		(start 38.654406 7.150608)
		(end 38.436271 7.150608)
		(width 0.106248)
		(layer "In2.Cu")
		(net "NFP_PCIE0_PET6_N")
	)
	(segment
		(start 37.266778 7.051802)
		(end 35.493173 7.051802)
		(width 0.110185)
		(layer "In2.Cu")
		(net "NFP_PCIE0_PET6_N")
	)
	(segment
		(start 24.852757 10.879836)
		(end 23.554868 12.177725)
		(width 0.110185)
		(layer "In2.Cu")
		(net "NFP_PCIE0_PET6_N")
	)
	(segment
		(start 17.932298 20.916798)
		(end 17.9324 20.9169)
		(width 0.110185)
		(layer "In2.Cu")
		(net "NFP_PCIE0_PET6_N")
	)
	(segment
		(start 39.13312 7.378014)
		(end 38.90104 7.145934)
		(width 0.106248)
		(layer "In2.Cu")
		(net "NFP_PCIE0_PET6_N")
	)
	(segment
		(start 38.294539 7.23199)
		(end 38.292532 7.233996)
		(width 0.106248)
		(layer "In2.Cu")
		(net "NFP_PCIE0_PET6_N")
	)
	(segment
		(start 52.340967 9.834016)
		(end 52.029106 10.145878)
		(width 0.106248)
		(layer "In2.Cu")
		(net "NFP_PCIE0_PET6_N")
	)
	(segment
		(start 54.237001 6.042)
		(end 53.737002 5.542001)
		(width 0.138633)
		(layer "F.Cu")
		(net "NFP_PCIE0_PET5_P")
	)
	(via
		(at 16.6624 17.1069)
		(size 0.762)
		(drill 0.254)
		(layers "F.Cu" "B.Cu")
		(net "NFP_PCIE0_PET5_P")
	)
	(via
		(at 53.737002 5.542001)
		(size 0.4826)
		(drill 0.20574)
		(layers "F.Cu" "B.Cu")
		(net "NFP_PCIE0_PET5_P")
	)
	(segment
		(start 16.0274 17.7419)
		(end 16.6624 17.1069)
		(width 0.138633)
		(layer "B.Cu")
		(net "NFP_PCIE0_PET5_P")
	)
	(segment
		(start 17.163898 9.379102)
		(end 18.288 8.255)
		(width 0.110185)
		(layer "In3.Cu")
		(net "NFP_PCIE0_PET5_P")
	)
	(segment
		(start 17.163898 10.964494)
		(end 17.163898 9.379102)
		(width 0.110185)
		(layer "In3.Cu")
		(net "NFP_PCIE0_PET5_P")
	)
	(segment
		(start 18.435625 17.227652)
		(end 18.435625 16.911625)
		(width 0.110185)
		(layer "In3.Cu")
		(net "NFP_PCIE0_PET5_P")
	)
	(segment
		(start 17.103598 15.579598)
		(end 17.103598 11.024794)
		(width 0.110185)
		(layer "In3.Cu")
		(net "NFP_PCIE0_PET5_P")
	)
	(segment
		(start 20.447 8.255)
		(end 21.547836 7.154164)
		(width 0.110185)
		(layer "In3.Cu")
		(net "NFP_PCIE0_PET5_P")
	)
	(segment
		(start 37.573991 4.426966)
		(end 38.083058 4.936033)
		(width 0.110185)
		(layer "In3.Cu")
		(net "NFP_PCIE0_PET5_P")
	)
	(segment
		(start 21.547836 7.154164)
		(end 25.238126 7.154164)
		(width 0.110185)
		(layer "In3.Cu")
		(net "NFP_PCIE0_PET5_P")
	)
	(segment
		(start 17.2085 17.653)
		(end 18.010276 17.653)
		(width 0.110185)
		(layer "In3.Cu")
		(net "NFP_PCIE0_PET5_P")
	)
	(segment
		(start 17.103598 11.024794)
		(end 17.163898 10.964494)
		(width 0.110185)
		(layer "In3.Cu")
		(net "NFP_PCIE0_PET5_P")
	)
	(segment
		(start 25.238126 7.154164)
		(end 25.564313 6.827977)
		(width 0.110185)
		(layer "In3.Cu")
		(net "NFP_PCIE0_PET5_P")
	)
	(segment
		(start 18.010276 17.653)
		(end 18.435625 17.227652)
		(width 0.110185)
		(layer "In3.Cu")
		(net "NFP_PCIE0_PET5_P")
	)
	(segment
		(start 30.434432 5.588)
		(end 33.782 5.588)
		(width 0.110185)
		(layer "In3.Cu")
		(net "NFP_PCIE0_PET5_P")
	)
	(segment
		(start 53.594 5.842)
		(end 53.737002 5.698998)
		(width 0.106248)
		(layer "In3.Cu")
		(net "NFP_PCIE0_PET5_P")
	)
	(segment
		(start 16.6624 17.1069)
		(end 17.2085 17.653)
		(width 0.110185)
		(layer "In3.Cu")
		(net "NFP_PCIE0_PET5_P")
	)
	(segment
		(start 38.354 4.936033)
		(end 38.380543 4.936033)
		(width 0.106248)
		(layer "In3.Cu")
		(net "NFP_PCIE0_PET5_P")
	)
	(segment
		(start 38.083058 4.936033)
		(end 38.354 4.936033)
		(width 0.110185)
		(layer "In3.Cu")
		(net "NFP_PCIE0_PET5_P")
	)
	(segment
		(start 53.737002 5.698998)
		(end 53.737002 5.542001)
		(width 0.106248)
		(layer "In3.Cu")
		(net "NFP_PCIE0_PET5_P")
	)
	(segment
		(start 33.782 5.588)
		(end 34.943034 4.426966)
		(width 0.110185)
		(layer "In3.Cu")
		(net "NFP_PCIE0_PET5_P")
	)
	(segment
		(start 52.987092 4.938039)
		(end 53.34 5.290947)
		(width 0.106248)
		(layer "In3.Cu")
		(net "NFP_PCIE0_PET5_P")
	)
	(segment
		(start 18.288 8.255)
		(end 20.447 8.255)
		(width 0.110185)
		(layer "In3.Cu")
		(net "NFP_PCIE0_PET5_P")
	)
	(segment
		(start 53.34 5.290947)
		(end 53.34 5.741949)
		(width 0.106248)
		(layer "In3.Cu")
		(net "NFP_PCIE0_PET5_P")
	)
	(segment
		(start 34.943034 4.426966)
		(end 37.573991 4.426966)
		(width 0.110185)
		(layer "In3.Cu")
		(net "NFP_PCIE0_PET5_P")
	)
	(segment
		(start 38.38255 4.938039)
		(end 52.987092 4.938039)
		(width 0.106248)
		(layer "In3.Cu")
		(net "NFP_PCIE0_PET5_P")
	)
	(segment
		(start 53.34 5.741949)
		(end 53.440051 5.842)
		(width 0.106248)
		(layer "In3.Cu")
		(net "NFP_PCIE0_PET5_P")
	)
	(segment
		(start 29.194455 6.827977)
		(end 30.434432 5.588)
		(width 0.110185)
		(layer "In3.Cu")
		(net "NFP_PCIE0_PET5_P")
	)
	(segment
		(start 38.380543 4.936033)
		(end 38.38255 4.938039)
		(width 0.106248)
		(layer "In3.Cu")
		(net "NFP_PCIE0_PET5_P")
	)
	(segment
		(start 25.564313 6.827977)
		(end 29.194455 6.827977)
		(width 0.110185)
		(layer "In3.Cu")
		(net "NFP_PCIE0_PET5_P")
	)
	(segment
		(start 53.440051 5.842)
		(end 53.594 5.842)
		(width 0.106248)
		(layer "In3.Cu")
		(net "NFP_PCIE0_PET5_P")
	)
	(segment
		(start 18.435625 16.911625)
		(end 17.103598 15.579598)
		(width 0.110185)
		(layer "In3.Cu")
		(net "NFP_PCIE0_PET5_P")
	)
	(segment
		(start 54.237001 7.041998)
		(end 53.737002 6.541999)
		(width 0.138633)
		(layer "F.Cu")
		(net "NFP_PCIE0_PET5_N")
	)
	(via
		(at 16.6624 18.3769)
		(size 0.762)
		(drill 0.2667)
		(layers "F.Cu" "B.Cu")
		(net "NFP_PCIE0_PET5_N")
	)
	(via
		(at 53.737002 6.541999)
		(size 0.4826)
		(drill 0.20574)
		(layers "F.Cu" "B.Cu")
		(net "NFP_PCIE0_PET5_N")
	)
	(segment
		(start 16.0274 19.0119)
		(end 16.6624 18.3769)
		(width 0.138633)
		(layer "B.Cu")
		(net "NFP_PCIE0_PET5_N")
	)
	(segment
		(start 25.325883 7.366)
		(end 25.65207 7.039813)
		(width 0.110185)
		(layer "In3.Cu")
		(net "NFP_PCIE0_PET5_N")
	)
	(segment
		(start 25.65207 7.039813)
		(end 29.282212 7.039813)
		(width 0.110185)
		(layer "In3.Cu")
		(net "NFP_PCIE0_PET5_N")
	)
	(segment
		(start 35.030791 4.638802)
		(end 37.486234 4.638802)
		(width 0.110185)
		(layer "In3.Cu")
		(net "NFP_PCIE0_PET5_N")
	)
	(segment
		(start 38.354 5.147869)
		(end 38.380543 5.147869)
		(width 0.106248)
		(layer "In3.Cu")
		(net "NFP_PCIE0_PET5_N")
	)
	(segment
		(start 17.375734 9.466859)
		(end 18.375757 8.466836)
		(width 0.110185)
		(layer "In3.Cu")
		(net "NFP_PCIE0_PET5_N")
	)
	(segment
		(start 18.647461 16.823868)
		(end 17.315434 15.491841)
		(width 0.110185)
		(layer "In3.Cu")
		(net "NFP_PCIE0_PET5_N")
	)
	(segment
		(start 53.133041 5.938037)
		(end 53.737002 6.541999)
		(width 0.106248)
		(layer "In3.Cu")
		(net "NFP_PCIE0_PET5_N")
	)
	(segment
		(start 17.315434 15.491841)
		(end 17.315434 11.112551)
		(width 0.110185)
		(layer "In3.Cu")
		(net "NFP_PCIE0_PET5_N")
	)
	(segment
		(start 18.375757 8.466836)
		(end 20.534757 8.466836)
		(width 0.110185)
		(layer "In3.Cu")
		(net "NFP_PCIE0_PET5_N")
	)
	(segment
		(start 53.133041 5.377942)
		(end 53.133041 5.938037)
		(width 0.106248)
		(layer "In3.Cu")
		(net "NFP_PCIE0_PET5_N")
	)
	(segment
		(start 33.869757 5.799836)
		(end 35.030791 4.638802)
		(width 0.110185)
		(layer "In3.Cu")
		(net "NFP_PCIE0_PET5_N")
	)
	(segment
		(start 21.635593 7.366)
		(end 25.325883 7.366)
		(width 0.110185)
		(layer "In3.Cu")
		(net "NFP_PCIE0_PET5_N")
	)
	(segment
		(start 17.174464 17.864836)
		(end 18.098033 17.864836)
		(width 0.110185)
		(layer "In3.Cu")
		(net "NFP_PCIE0_PET5_N")
	)
	(segment
		(start 29.282212 7.039813)
		(end 30.522189 5.799836)
		(width 0.110185)
		(layer "In3.Cu")
		(net "NFP_PCIE0_PET5_N")
	)
	(segment
		(start 17.375734 11.052251)
		(end 17.375734 9.466859)
		(width 0.110185)
		(layer "In3.Cu")
		(net "NFP_PCIE0_PET5_N")
	)
	(segment
		(start 17.315434 11.112551)
		(end 17.375734 11.052251)
		(width 0.110185)
		(layer "In3.Cu")
		(net "NFP_PCIE0_PET5_N")
	)
	(segment
		(start 38.382524 5.145888)
		(end 52.900986 5.145888)
		(width 0.106248)
		(layer "In3.Cu")
		(net "NFP_PCIE0_PET5_N")
	)
	(segment
		(start 18.098033 17.864836)
		(end 18.647461 17.315409)
		(width 0.110185)
		(layer "In3.Cu")
		(net "NFP_PCIE0_PET5_N")
	)
	(segment
		(start 16.6624 18.3769)
		(end 17.174464 17.864836)
		(width 0.110185)
		(layer "In3.Cu")
		(net "NFP_PCIE0_PET5_N")
	)
	(segment
		(start 30.522189 5.799836)
		(end 33.869757 5.799836)
		(width 0.110185)
		(layer "In3.Cu")
		(net "NFP_PCIE0_PET5_N")
	)
	(segment
		(start 37.995301 5.147869)
		(end 38.354 5.147869)
		(width 0.110185)
		(layer "In3.Cu")
		(net "NFP_PCIE0_PET5_N")
	)
	(segment
		(start 18.647461 17.315409)
		(end 18.647461 16.823868)
		(width 0.110185)
		(layer "In3.Cu")
		(net "NFP_PCIE0_PET5_N")
	)
	(segment
		(start 37.486234 4.638802)
		(end 37.995301 5.147869)
		(width 0.110185)
		(layer "In3.Cu")
		(net "NFP_PCIE0_PET5_N")
	)
	(segment
		(start 20.534757 8.466836)
		(end 21.635593 7.366)
		(width 0.110185)
		(layer "In3.Cu")
		(net "NFP_PCIE0_PET5_N")
	)
	(segment
		(start 52.900986 5.145888)
		(end 53.133041 5.377942)
		(width 0.106248)
		(layer "In3.Cu")
		(net "NFP_PCIE0_PET5_N")
	)
	(segment
		(start 38.380543 5.147869)
		(end 38.382524 5.145888)
		(width 0.106248)
		(layer "In3.Cu")
		(net "NFP_PCIE0_PET5_N")
	)
	(segment
		(start 55.736998 6.541999)
		(end 55.236999 7.041998)
		(width 0.138633)
		(layer "F.Cu")
		(net "NFP_PCIE0_PET4_P")
	)
	(via
		(at 16.6624 14.5669)
		(size 0.762)
		(drill 0.254)
		(layers "F.Cu" "B.Cu")
		(net "NFP_PCIE0_PET4_P")
	)
	(via
		(at 55.736998 6.541999)
		(size 0.4826)
		(drill 0.20574)
		(layers "F.Cu" "B.Cu")
		(net "NFP_PCIE0_PET4_P")
	)
	(segment
		(start 17.2974 15.2019)
		(end 16.6624 14.5669)
		(width 0.138633)
		(layer "B.Cu")
		(net "NFP_PCIE0_PET4_P")
	)
	(segment
		(start 17.78 13.081)
		(end 20.43557 10.42543)
		(width 0.110185)
		(layer "In2.Cu")
		(net "NFP_PCIE0_PET4_P")
	)
	(segment
		(start 38.38255 5.938037)
		(end 39.987093 5.938037)
		(width 0.106248)
		(layer "In2.Cu")
		(net "NFP_PCIE0_PET4_P")
	)
	(segment
		(start 54.483 6.604)
		(end 55.674997 6.604)
		(width 0.106248)
		(layer "In2.Cu")
		(net "NFP_PCIE0_PET4_P")
	)
	(segment
		(start 16.6624 14.5669)
		(end 16.6624 15.113254)
		(width 0.110185)
		(layer "In2.Cu")
		(net "NFP_PCIE0_PET4_P")
	)
	(segment
		(start 16.6624 15.113254)
		(end 17.17421 15.625064)
		(width 0.110185)
		(layer "In2.Cu")
		(net "NFP_PCIE0_PET4_P")
	)
	(segment
		(start 30.560975 8.382)
		(end 31.300166 7.642809)
		(width 0.110185)
		(layer "In2.Cu")
		(net "NFP_PCIE0_PET4_P")
	)
	(segment
		(start 53.460066 6.938112)
		(end 54.148888 6.938112)
		(width 0.106248)
		(layer "In2.Cu")
		(net "NFP_PCIE0_PET4_P")
	)
	(segment
		(start 43.029988 7.938033)
		(end 44.029986 8.938031)
		(width 0.106248)
		(layer "In2.Cu")
		(net "NFP_PCIE0_PET4_P")
	)
	(segment
		(start 40.34089 7.705979)
		(end 40.572944 7.938033)
		(width 0.106248)
		(layer "In2.Cu")
		(net "NFP_PCIE0_PET4_P")
	)
	(segment
		(start 34.036 6.858)
		(end 35.197034 5.696966)
		(width 0.110185)
		(layer "In2.Cu")
		(net "NFP_PCIE0_PET4_P")
	)
	(segment
		(start 44.029986 8.938031)
		(end 50.966014 8.938031)
		(width 0.106248)
		(layer "In2.Cu")
		(net "NFP_PCIE0_PET4_P")
	)
	(segment
		(start 37.446966 5.696966)
		(end 37.686031 5.936031)
		(width 0.110185)
		(layer "In2.Cu")
		(net "NFP_PCIE0_PET4_P")
	)
	(segment
		(start 40.34089 6.291834)
		(end 40.34089 7.705979)
		(width 0.106248)
		(layer "In2.Cu")
		(net "NFP_PCIE0_PET4_P")
	)
	(segment
		(start 54.148888 6.938112)
		(end 54.483 6.604)
		(width 0.106248)
		(layer "In2.Cu")
		(net "NFP_PCIE0_PET4_P")
	)
	(segment
		(start 51.901065 6.938035)
		(end 52.133043 6.706057)
		(width 0.106248)
		(layer "In2.Cu")
		(net "NFP_PCIE0_PET4_P")
	)
	(segment
		(start 35.197034 5.696966)
		(end 37.446966 5.696966)
		(width 0.110185)
		(layer "In2.Cu")
		(net "NFP_PCIE0_PET4_P")
	)
	(segment
		(start 52.133043 6.706057)
		(end 52.133043 6.291859)
		(width 0.106248)
		(layer "In2.Cu")
		(net "NFP_PCIE0_PET4_P")
	)
	(segment
		(start 22.666198 9.453778)
		(end 22.666198 8.956802)
		(width 0.110185)
		(layer "In2.Cu")
		(net "NFP_PCIE0_PET4_P")
	)
	(segment
		(start 51.133121 8.770925)
		(end 51.133121 7.291832)
		(width 0.106248)
		(layer "In2.Cu")
		(net "NFP_PCIE0_PET4_P")
	)
	(segment
		(start 53.340889 6.818935)
		(end 53.460066 6.938112)
		(width 0.106248)
		(layer "In2.Cu")
		(net "NFP_PCIE0_PET4_P")
	)
	(segment
		(start 31.300166 7.328408)
		(end 31.770574 6.858)
		(width 0.110185)
		(layer "In2.Cu")
		(net "NFP_PCIE0_PET4_P")
	)
	(segment
		(start 39.987093 5.938037)
		(end 40.34089 6.291834)
		(width 0.106248)
		(layer "In2.Cu")
		(net "NFP_PCIE0_PET4_P")
	)
	(segment
		(start 17.648936 15.625064)
		(end 17.78 15.494)
		(width 0.110185)
		(layer "In2.Cu")
		(net "NFP_PCIE0_PET4_P")
	)
	(segment
		(start 53.340889 6.291834)
		(end 53.340889 6.818935)
		(width 0.106248)
		(layer "In2.Cu")
		(net "NFP_PCIE0_PET4_P")
	)
	(segment
		(start 40.572944 7.938033)
		(end 43.029988 7.938033)
		(width 0.106248)
		(layer "In2.Cu")
		(net "NFP_PCIE0_PET4_P")
	)
	(segment
		(start 23.241 8.382)
		(end 30.560975 8.382)
		(width 0.110185)
		(layer "In2.Cu")
		(net "NFP_PCIE0_PET4_P")
	)
	(segment
		(start 22.666198 8.956802)
		(end 23.241 8.382)
		(width 0.110185)
		(layer "In2.Cu")
		(net "NFP_PCIE0_PET4_P")
	)
	(segment
		(start 17.78 15.494)
		(end 17.78 13.081)
		(width 0.110185)
		(layer "In2.Cu")
		(net "NFP_PCIE0_PET4_P")
	)
	(segment
		(start 51.133121 7.291832)
		(end 51.486918 6.938035)
		(width 0.106248)
		(layer "In2.Cu")
		(net "NFP_PCIE0_PET4_P")
	)
	(segment
		(start 31.300166 7.642809)
		(end 31.300166 7.328408)
		(width 0.110185)
		(layer "In2.Cu")
		(net "NFP_PCIE0_PET4_P")
	)
	(segment
		(start 37.686031 5.936031)
		(end 38.354 5.936031)
		(width 0.110185)
		(layer "In2.Cu")
		(net "NFP_PCIE0_PET4_P")
	)
	(segment
		(start 55.674997 6.604)
		(end 55.736998 6.541999)
		(width 0.106248)
		(layer "In2.Cu")
		(net "NFP_PCIE0_PET4_P")
	)
	(segment
		(start 21.694546 10.42543)
		(end 22.666198 9.453778)
		(width 0.110185)
		(layer "In2.Cu")
		(net "NFP_PCIE0_PET4_P")
	)
	(segment
		(start 17.17421 15.625064)
		(end 17.648936 15.625064)
		(width 0.110185)
		(layer "In2.Cu")
		(net "NFP_PCIE0_PET4_P")
	)
	(segment
		(start 31.770574 6.858)
		(end 34.036 6.858)
		(width 0.110185)
		(layer "In2.Cu")
		(net "NFP_PCIE0_PET4_P")
	)
	(segment
		(start 52.486865 5.938037)
		(end 52.987092 5.938037)
		(width 0.106248)
		(layer "In2.Cu")
		(net "NFP_PCIE0_PET4_P")
	)
	(segment
		(start 20.43557 10.42543)
		(end 21.694546 10.42543)
		(width 0.110185)
		(layer "In2.Cu")
		(net "NFP_PCIE0_PET4_P")
	)
	(segment
		(start 51.486918 6.938035)
		(end 51.901065 6.938035)
		(width 0.106248)
		(layer "In2.Cu")
		(net "NFP_PCIE0_PET4_P")
	)
	(segment
		(start 38.354 5.936031)
		(end 38.380543 5.936031)
		(width 0.106248)
		(layer "In2.Cu")
		(net "NFP_PCIE0_PET4_P")
	)
	(segment
		(start 50.966014 8.938031)
		(end 51.133121 8.770925)
		(width 0.106248)
		(layer "In2.Cu")
		(net "NFP_PCIE0_PET4_P")
	)
	(segment
		(start 38.380543 5.936031)
		(end 38.38255 5.938037)
		(width 0.106248)
		(layer "In2.Cu")
		(net "NFP_PCIE0_PET4_P")
	)
	(segment
		(start 52.133043 6.291859)
		(end 52.486865 5.938037)
		(width 0.106248)
		(layer "In2.Cu")
		(net "NFP_PCIE0_PET4_P")
	)
	(segment
		(start 52.987092 5.938037)
		(end 53.340889 6.291834)
		(width 0.106248)
		(layer "In2.Cu")
		(net "NFP_PCIE0_PET4_P")
	)
	(segment
		(start 55.736998 7.541997)
		(end 55.236999 8.041996)
		(width 0.138633)
		(layer "F.Cu")
		(net "NFP_PCIE0_PET4_N")
	)
	(via
		(at 55.736998 7.541997)
		(size 0.4826)
		(drill 0.20574)
		(layers "F.Cu" "B.Cu")
		(net "NFP_PCIE0_PET4_N")
	)
	(via
		(at 16.6624 15.8369)
		(size 0.762)
		(drill 0.2667)
		(layers "F.Cu" "B.Cu")
		(net "NFP_PCIE0_PET4_N")
	)
	(segment
		(start 17.2974 16.4719)
		(end 16.6624 15.8369)
		(width 0.138633)
		(layer "B.Cu")
		(net "NFP_PCIE0_PET4_N")
	)
	(segment
		(start 51.573024 7.145884)
		(end 51.987171 7.145884)
		(width 0.106248)
		(layer "In2.Cu")
		(net "NFP_PCIE0_PET4_N")
	)
	(segment
		(start 51.987171 7.145884)
		(end 52.340967 6.792087)
		(width 0.106248)
		(layer "In2.Cu")
		(net "NFP_PCIE0_PET4_N")
	)
	(segment
		(start 43.94388 9.14588)
		(end 51.05212 9.14588)
		(width 0.106248)
		(layer "In2.Cu")
		(net "NFP_PCIE0_PET4_N")
	)
	(segment
		(start 35.284791 5.908802)
		(end 37.359209 5.908802)
		(width 0.110185)
		(layer "In2.Cu")
		(net "NFP_PCIE0_PET4_N")
	)
	(segment
		(start 52.340967 6.792087)
		(end 52.340967 6.37794)
		(width 0.106248)
		(layer "In2.Cu")
		(net "NFP_PCIE0_PET4_N")
	)
	(segment
		(start 21.782303 10.637266)
		(end 22.878034 9.541535)
		(width 0.110185)
		(layer "In2.Cu")
		(net "NFP_PCIE0_PET4_N")
	)
	(segment
		(start 31.512002 7.416165)
		(end 31.858331 7.069836)
		(width 0.110185)
		(layer "In2.Cu")
		(net "NFP_PCIE0_PET4_N")
	)
	(segment
		(start 55.446752 6.811848)
		(end 55.572939 6.938035)
		(width 0.106248)
		(layer "In2.Cu")
		(net "NFP_PCIE0_PET4_N")
	)
	(segment
		(start 40.133041 7.792085)
		(end 40.486838 8.145882)
		(width 0.106248)
		(layer "In2.Cu")
		(net "NFP_PCIE0_PET4_N")
	)
	(segment
		(start 53.133041 6.905041)
		(end 53.37396 7.14596)
		(width 0.106248)
		(layer "In2.Cu")
		(net "NFP_PCIE0_PET4_N")
	)
	(segment
		(start 31.512002 7.730566)
		(end 31.512002 7.416165)
		(width 0.110185)
		(layer "In2.Cu")
		(net "NFP_PCIE0_PET4_N")
	)
	(segment
		(start 54.234994 7.14596)
		(end 54.569106 6.811848)
		(width 0.106248)
		(layer "In2.Cu")
		(net "NFP_PCIE0_PET4_N")
	)
	(segment
		(start 39.900987 6.145886)
		(end 40.133041 6.37794)
		(width 0.106248)
		(layer "In2.Cu")
		(net "NFP_PCIE0_PET4_N")
	)
	(segment
		(start 52.572945 6.145962)
		(end 52.90091 6.145962)
		(width 0.106248)
		(layer "In2.Cu")
		(net "NFP_PCIE0_PET4_N")
	)
	(segment
		(start 52.90091 6.145962)
		(end 52.900986 6.145886)
		(width 0.106248)
		(layer "In2.Cu")
		(net "NFP_PCIE0_PET4_N")
	)
	(segment
		(start 40.133041 6.37794)
		(end 40.133041 7.792085)
		(width 0.106248)
		(layer "In2.Cu")
		(net "NFP_PCIE0_PET4_N")
	)
	(segment
		(start 17.736693 15.8369)
		(end 17.991836 15.581757)
		(width 0.110185)
		(layer "In2.Cu")
		(net "NFP_PCIE0_PET4_N")
	)
	(segment
		(start 31.858331 7.069836)
		(end 34.123757 7.069836)
		(width 0.110185)
		(layer "In2.Cu")
		(net "NFP_PCIE0_PET4_N")
	)
	(segment
		(start 38.380543 6.147867)
		(end 38.382524 6.145886)
		(width 0.106248)
		(layer "In2.Cu")
		(net "NFP_PCIE0_PET4_N")
	)
	(segment
		(start 52.900986 6.145886)
		(end 53.133041 6.37794)
		(width 0.106248)
		(layer "In2.Cu")
		(net "NFP_PCIE0_PET4_N")
	)
	(segment
		(start 51.340969 7.377938)
		(end 51.573024 7.145884)
		(width 0.106248)
		(layer "In2.Cu")
		(net "NFP_PCIE0_PET4_N")
	)
	(segment
		(start 16.6624 15.8369)
		(end 17.736693 15.8369)
		(width 0.110185)
		(layer "In2.Cu")
		(net "NFP_PCIE0_PET4_N")
	)
	(segment
		(start 22.878034 9.541535)
		(end 22.878034 9.044559)
		(width 0.110185)
		(layer "In2.Cu")
		(net "NFP_PCIE0_PET4_N")
	)
	(segment
		(start 53.37396 7.14596)
		(end 54.234994 7.14596)
		(width 0.106248)
		(layer "In2.Cu")
		(net "NFP_PCIE0_PET4_N")
	)
	(segment
		(start 52.340967 6.37794)
		(end 52.572945 6.145962)
		(width 0.106248)
		(layer "In2.Cu")
		(net "NFP_PCIE0_PET4_N")
	)
	(segment
		(start 38.354 6.147867)
		(end 38.380543 6.147867)
		(width 0.106248)
		(layer "In2.Cu")
		(net "NFP_PCIE0_PET4_N")
	)
	(segment
		(start 37.359209 5.908802)
		(end 37.598274 6.147867)
		(width 0.110185)
		(layer "In2.Cu")
		(net "NFP_PCIE0_PET4_N")
	)
	(segment
		(start 53.133041 6.37794)
		(end 53.133041 6.905041)
		(width 0.106248)
		(layer "In2.Cu")
		(net "NFP_PCIE0_PET4_N")
	)
	(segment
		(start 51.05212 9.14588)
		(end 51.340969 8.857031)
		(width 0.106248)
		(layer "In2.Cu")
		(net "NFP_PCIE0_PET4_N")
	)
	(segment
		(start 55.572939 6.938035)
		(end 55.773726 6.938035)
		(width 0.106248)
		(layer "In2.Cu")
		(net "NFP_PCIE0_PET4_N")
	)
	(segment
		(start 20.523327 10.637266)
		(end 21.782303 10.637266)
		(width 0.110185)
		(layer "In2.Cu")
		(net "NFP_PCIE0_PET4_N")
	)
	(segment
		(start 51.340969 8.857031)
		(end 51.340969 7.377938)
		(width 0.106248)
		(layer "In2.Cu")
		(net "NFP_PCIE0_PET4_N")
	)
	(segment
		(start 30.648732 8.593836)
		(end 31.512002 7.730566)
		(width 0.110185)
		(layer "In2.Cu")
		(net "NFP_PCIE0_PET4_N")
	)
	(segment
		(start 54.569106 6.811848)
		(end 55.446752 6.811848)
		(width 0.106248)
		(layer "In2.Cu")
		(net "NFP_PCIE0_PET4_N")
	)
	(segment
		(start 40.486838 8.145882)
		(end 42.943882 8.145882)
		(width 0.106248)
		(layer "In2.Cu")
		(net "NFP_PCIE0_PET4_N")
	)
	(segment
		(start 17.991836 13.168757)
		(end 20.523327 10.637266)
		(width 0.110185)
		(layer "In2.Cu")
		(net "NFP_PCIE0_PET4_N")
	)
	(segment
		(start 34.123757 7.069836)
		(end 35.284791 5.908802)
		(width 0.110185)
		(layer "In2.Cu")
		(net "NFP_PCIE0_PET4_N")
	)
	(segment
		(start 38.382524 6.145886)
		(end 39.900987 6.145886)
		(width 0.106248)
		(layer "In2.Cu")
		(net "NFP_PCIE0_PET4_N")
	)
	(segment
		(start 22.878034 9.044559)
		(end 23.328757 8.593836)
		(width 0.110185)
		(layer "In2.Cu")
		(net "NFP_PCIE0_PET4_N")
	)
	(segment
		(start 55.773726 6.938035)
		(end 55.88 7.044309)
		(width 0.106248)
		(layer "In2.Cu")
		(net "NFP_PCIE0_PET4_N")
	)
	(segment
		(start 23.328757 8.593836)
		(end 30.648732 8.593836)
		(width 0.110185)
		(layer "In2.Cu")
		(net "NFP_PCIE0_PET4_N")
	)
	(segment
		(start 55.88 7.044309)
		(end 55.88 7.398995)
		(width 0.106248)
		(layer "In2.Cu")
		(net "NFP_PCIE0_PET4_N")
	)
	(segment
		(start 37.598274 6.147867)
		(end 38.354 6.147867)
		(width 0.110185)
		(layer "In2.Cu")
		(net "NFP_PCIE0_PET4_N")
	)
	(segment
		(start 55.88 7.398995)
		(end 55.736998 7.541997)
		(width 0.106248)
		(layer "In2.Cu")
		(net "NFP_PCIE0_PET4_N")
	)
	(segment
		(start 42.943882 8.145882)
		(end 43.94388 9.14588)
		(width 0.106248)
		(layer "In2.Cu")
		(net "NFP_PCIE0_PET4_N")
	)
	(segment
		(start 17.991836 15.581757)
		(end 17.991836 13.168757)
		(width 0.110185)
		(layer "In2.Cu")
		(net "NFP_PCIE0_PET4_N")
	)
	(segment
		(start 56.736996 5.542001)
		(end 56.236997 6.042)
		(width 0.138633)
		(layer "F.Cu")
		(net "NFP_PCIE0_PET3_P")
	)
	(via
		(at 56.736996 5.542001)
		(size 0.4826)
		(drill 0.20574)
		(layers "F.Cu" "B.Cu")
		(net "NFP_PCIE0_PET3_P")
	)
	(via
		(at 15.3924 12.0269)
		(size 0.762)
		(drill 0.254)
		(layers "F.Cu" "B.Cu")
		(net "NFP_PCIE0_PET3_P")
	)
	(segment
		(start 16.0274 12.6619)
		(end 15.3924 12.0269)
		(width 0.138633)
		(layer "B.Cu")
		(net "NFP_PCIE0_PET3_P")
	)
	(segment
		(start 44.340882 7.851927)
		(end 44.427064 7.93811)
		(width 0.106248)
		(layer "In2.Cu")
		(net "NFP_PCIE0_PET3_P")
	)
	(segment
		(start 34.689034 4.426966)
		(end 37.354535 4.426966)
		(width 0.110185)
		(layer "In2.Cu")
		(net "NFP_PCIE0_PET3_P")
	)
	(segment
		(start 22.733 7.62)
		(end 30.226 7.62)
		(width 0.110185)
		(layer "In2.Cu")
		(net "NFP_PCIE0_PET3_P")
	)
	(segment
		(start 38.354 4.936109)
		(end 38.380543 4.936109)
		(width 0.106248)
		(layer "In2.Cu")
		(net "NFP_PCIE0_PET3_P")
	)
	(segment
		(start 33.528 5.588)
		(end 34.689034 4.426966)
		(width 0.110185)
		(layer "In2.Cu")
		(net "NFP_PCIE0_PET3_P")
	)
	(segment
		(start 44.427064 7.93811)
		(end 47.037015 7.93811)
		(width 0.106248)
		(layer "In2.Cu")
		(net "NFP_PCIE0_PET3_P")
	)
	(segment
		(start 37.863678 4.936109)
		(end 38.354 4.936109)
		(width 0.110185)
		(layer "In2.Cu")
		(net "NFP_PCIE0_PET3_P")
	)
	(segment
		(start 49.486845 4.938116)
		(end 54.12707 4.938116)
		(width 0.106248)
		(layer "In2.Cu")
		(net "NFP_PCIE0_PET3_P")
	)
	(segment
		(start 30.226 7.62)
		(end 30.586934 7.259066)
		(width 0.110185)
		(layer "In2.Cu")
		(net "NFP_PCIE0_PET3_P")
	)
	(segment
		(start 40.987193 4.938116)
		(end 41.340888 5.291861)
		(width 0.106248)
		(layer "In2.Cu")
		(net "NFP_PCIE0_PET3_P")
	)
	(segment
		(start 41.776066 6.938112)
		(end 43.987161 6.938112)
		(width 0.106248)
		(layer "In2.Cu")
		(net "NFP_PCIE0_PET3_P")
	)
	(segment
		(start 56.379034 5.938114)
		(end 56.447131 5.870016)
		(width 0.106248)
		(layer "In2.Cu")
		(net "NFP_PCIE0_PET3_P")
	)
	(segment
		(start 30.861 6.201054)
		(end 31.474054 5.588)
		(width 0.110185)
		(layer "In2.Cu")
		(net "NFP_PCIE0_PET3_P")
	)
	(segment
		(start 30.586934 7.259066)
		(end 30.586934 7.032955)
		(width 0.110185)
		(layer "In2.Cu")
		(net "NFP_PCIE0_PET3_P")
	)
	(segment
		(start 43.987161 6.938112)
		(end 44.340882 7.291832)
		(width 0.106248)
		(layer "In2.Cu")
		(net "NFP_PCIE0_PET3_P")
	)
	(segment
		(start 54.12707 4.938116)
		(end 55.127068 5.938114)
		(width 0.106248)
		(layer "In2.Cu")
		(net "NFP_PCIE0_PET3_P")
	)
	(segment
		(start 37.354535 4.426966)
		(end 37.863678 4.936109)
		(width 0.110185)
		(layer "In2.Cu")
		(net "NFP_PCIE0_PET3_P")
	)
	(segment
		(start 38.380543 4.936109)
		(end 38.38255 4.938116)
		(width 0.106248)
		(layer "In2.Cu")
		(net "NFP_PCIE0_PET3_P")
	)
	(segment
		(start 30.586934 7.032955)
		(end 30.861 6.758889)
		(width 0.110185)
		(layer "In2.Cu")
		(net "NFP_PCIE0_PET3_P")
	)
	(segment
		(start 31.474054 5.588)
		(end 33.528 5.588)
		(width 0.110185)
		(layer "In2.Cu")
		(net "NFP_PCIE0_PET3_P")
	)
	(segment
		(start 19.960184 9.712198)
		(end 21.137778 9.712198)
		(width 0.110185)
		(layer "In2.Cu")
		(net "NFP_PCIE0_PET3_P")
	)
	(segment
		(start 55.127068 5.938114)
		(end 56.379034 5.938114)
		(width 0.106248)
		(layer "In2.Cu")
		(net "NFP_PCIE0_PET3_P")
	)
	(segment
		(start 17.099382 12.573)
		(end 19.960184 9.712198)
		(width 0.110185)
		(layer "In2.Cu")
		(net "NFP_PCIE0_PET3_P")
	)
	(segment
		(start 49.133125 5.842)
		(end 49.133125 5.291836)
		(width 0.106248)
		(layer "In2.Cu")
		(net "NFP_PCIE0_PET3_P")
	)
	(segment
		(start 38.38255 4.938116)
		(end 40.987193 4.938116)
		(width 0.106248)
		(layer "In2.Cu")
		(net "NFP_PCIE0_PET3_P")
	)
	(segment
		(start 21.396198 9.453778)
		(end 21.396198 8.956802)
		(width 0.110185)
		(layer "In2.Cu")
		(net "NFP_PCIE0_PET3_P")
	)
	(segment
		(start 56.736996 5.763768)
		(end 56.736996 5.542001)
		(width 0.106248)
		(layer "In2.Cu")
		(net "NFP_PCIE0_PET3_P")
	)
	(segment
		(start 21.137778 9.712198)
		(end 21.396198 9.453778)
		(width 0.110185)
		(layer "In2.Cu")
		(net "NFP_PCIE0_PET3_P")
	)
	(segment
		(start 41.340888 5.291861)
		(end 41.340888 6.502933)
		(width 0.106248)
		(layer "In2.Cu")
		(net "NFP_PCIE0_PET3_P")
	)
	(segment
		(start 56.447131 5.870016)
		(end 56.630748 5.870016)
		(width 0.106248)
		(layer "In2.Cu")
		(net "NFP_PCIE0_PET3_P")
	)
	(segment
		(start 56.630748 5.870016)
		(end 56.736996 5.763768)
		(width 0.106248)
		(layer "In2.Cu")
		(net "NFP_PCIE0_PET3_P")
	)
	(segment
		(start 44.340882 7.291832)
		(end 44.340882 7.851927)
		(width 0.106248)
		(layer "In2.Cu")
		(net "NFP_PCIE0_PET3_P")
	)
	(segment
		(start 49.133125 5.291836)
		(end 49.486845 4.938116)
		(width 0.106248)
		(layer "In2.Cu")
		(net "NFP_PCIE0_PET3_P")
	)
	(segment
		(start 21.396198 8.956802)
		(end 22.733 7.62)
		(width 0.110185)
		(layer "In2.Cu")
		(net "NFP_PCIE0_PET3_P")
	)
	(segment
		(start 41.340888 6.502933)
		(end 41.776066 6.938112)
		(width 0.106248)
		(layer "In2.Cu")
		(net "NFP_PCIE0_PET3_P")
	)
	(segment
		(start 15.9385 12.573)
		(end 17.099382 12.573)
		(width 0.110185)
		(layer "In2.Cu")
		(net "NFP_PCIE0_PET3_P")
	)
	(segment
		(start 30.861 6.758889)
		(end 30.861 6.201054)
		(width 0.110185)
		(layer "In2.Cu")
		(net "NFP_PCIE0_PET3_P")
	)
	(segment
		(start 47.037015 7.93811)
		(end 49.133125 5.842)
		(width 0.106248)
		(layer "In2.Cu")
		(net "NFP_PCIE0_PET3_P")
	)
	(segment
		(start 15.3924 12.0269)
		(end 15.9385 12.573)
		(width 0.110185)
		(layer "In2.Cu")
		(net "NFP_PCIE0_PET3_P")
	)
	(segment
		(start 56.736996 6.541999)
		(end 56.236997 7.041998)
		(width 0.138633)
		(layer "F.Cu")
		(net "NFP_PCIE0_PET3_N")
	)
	(via
		(at 15.3924 13.2969)
		(size 0.762)
		(drill 0.2667)
		(layers "F.Cu" "B.Cu")
		(net "NFP_PCIE0_PET3_N")
	)
	(via
		(at 56.736996 6.541999)
		(size 0.4826)
		(drill 0.20574)
		(layers "F.Cu" "B.Cu")
		(net "NFP_PCIE0_PET3_N")
	)
	(segment
		(start 16.0274 13.9319)
		(end 15.3924 13.2969)
		(width 0.138633)
		(layer "B.Cu")
		(net "NFP_PCIE0_PET3_N")
	)
	(segment
		(start 41.68996 7.14596)
		(end 43.901055 7.14596)
		(width 0.106248)
		(layer "In2.Cu")
		(net "NFP_PCIE0_PET3_N")
	)
	(segment
		(start 47.123121 8.145958)
		(end 49.340973 5.928106)
		(width 0.106248)
		(layer "In2.Cu")
		(net "NFP_PCIE0_PET3_N")
	)
	(segment
		(start 30.79877 7.120712)
		(end 31.072836 6.846646)
		(width 0.110185)
		(layer "In2.Cu")
		(net "NFP_PCIE0_PET3_N")
	)
	(segment
		(start 21.608034 9.044559)
		(end 22.820757 7.831836)
		(width 0.110185)
		(layer "In2.Cu")
		(net "NFP_PCIE0_PET3_N")
	)
	(segment
		(start 56.736996 6.444971)
		(end 56.736996 6.541999)
		(width 0.106248)
		(layer "In2.Cu")
		(net "NFP_PCIE0_PET3_N")
	)
	(segment
		(start 15.3924 13.2969)
		(end 15.904464 12.784836)
		(width 0.110185)
		(layer "In2.Cu")
		(net "NFP_PCIE0_PET3_N")
	)
	(segment
		(start 37.266778 4.638802)
		(end 37.775921 5.147945)
		(width 0.110185)
		(layer "In2.Cu")
		(net "NFP_PCIE0_PET3_N")
	)
	(segment
		(start 17.187139 12.784836)
		(end 20.047941 9.924034)
		(width 0.110185)
		(layer "In2.Cu")
		(net "NFP_PCIE0_PET3_N")
	)
	(segment
		(start 15.904464 12.784836)
		(end 17.187139 12.784836)
		(width 0.110185)
		(layer "In2.Cu")
		(net "NFP_PCIE0_PET3_N")
	)
	(segment
		(start 38.380543 5.147945)
		(end 38.382524 5.145964)
		(width 0.106248)
		(layer "In2.Cu")
		(net "NFP_PCIE0_PET3_N")
	)
	(segment
		(start 44.133033 7.377938)
		(end 44.133033 7.938033)
		(width 0.106248)
		(layer "In2.Cu")
		(net "NFP_PCIE0_PET3_N")
	)
	(segment
		(start 54.040964 5.145964)
		(end 55.040962 6.145962)
		(width 0.106248)
		(layer "In2.Cu")
		(net "NFP_PCIE0_PET3_N")
	)
	(segment
		(start 40.901087 5.145964)
		(end 41.133039 5.377942)
		(width 0.106248)
		(layer "In2.Cu")
		(net "NFP_PCIE0_PET3_N")
	)
	(segment
		(start 22.820757 7.831836)
		(end 30.313757 7.831836)
		(width 0.110185)
		(layer "In2.Cu")
		(net "NFP_PCIE0_PET3_N")
	)
	(segment
		(start 31.561811 5.799836)
		(end 33.615757 5.799836)
		(width 0.110185)
		(layer "In2.Cu")
		(net "NFP_PCIE0_PET3_N")
	)
	(segment
		(start 41.133039 6.589039)
		(end 41.68996 7.14596)
		(width 0.106248)
		(layer "In2.Cu")
		(net "NFP_PCIE0_PET3_N")
	)
	(segment
		(start 49.572951 5.145964)
		(end 54.040964 5.145964)
		(width 0.106248)
		(layer "In2.Cu")
		(net "NFP_PCIE0_PET3_N")
	)
	(segment
		(start 21.225535 9.924034)
		(end 21.608034 9.541535)
		(width 0.110185)
		(layer "In2.Cu")
		(net "NFP_PCIE0_PET3_N")
	)
	(segment
		(start 20.047941 9.924034)
		(end 21.225535 9.924034)
		(width 0.110185)
		(layer "In2.Cu")
		(net "NFP_PCIE0_PET3_N")
	)
	(segment
		(start 33.615757 5.799836)
		(end 34.776791 4.638802)
		(width 0.110185)
		(layer "In2.Cu")
		(net "NFP_PCIE0_PET3_N")
	)
	(segment
		(start 41.133039 5.377942)
		(end 41.133039 6.589039)
		(width 0.106248)
		(layer "In2.Cu")
		(net "NFP_PCIE0_PET3_N")
	)
	(segment
		(start 30.313757 7.831836)
		(end 30.79877 7.346823)
		(width 0.110185)
		(layer "In2.Cu")
		(net "NFP_PCIE0_PET3_N")
	)
	(segment
		(start 44.340958 8.145958)
		(end 47.123121 8.145958)
		(width 0.106248)
		(layer "In2.Cu")
		(net "NFP_PCIE0_PET3_N")
	)
	(segment
		(start 34.776791 4.638802)
		(end 37.266778 4.638802)
		(width 0.110185)
		(layer "In2.Cu")
		(net "NFP_PCIE0_PET3_N")
	)
	(segment
		(start 37.775921 5.147945)
		(end 38.354 5.147945)
		(width 0.110185)
		(layer "In2.Cu")
		(net "NFP_PCIE0_PET3_N")
	)
	(segment
		(start 38.382524 5.145964)
		(end 40.901087 5.145964)
		(width 0.106248)
		(layer "In2.Cu")
		(net "NFP_PCIE0_PET3_N")
	)
	(segment
		(start 21.608034 9.541535)
		(end 21.608034 9.044559)
		(width 0.110185)
		(layer "In2.Cu")
		(net "NFP_PCIE0_PET3_N")
	)
	(segment
		(start 49.340973 5.377942)
		(end 49.572951 5.145964)
		(width 0.106248)
		(layer "In2.Cu")
		(net "NFP_PCIE0_PET3_N")
	)
	(segment
		(start 31.072836 6.846646)
		(end 31.072836 6.288811)
		(width 0.110185)
		(layer "In2.Cu")
		(net "NFP_PCIE0_PET3_N")
	)
	(segment
		(start 43.901055 7.14596)
		(end 44.133033 7.377938)
		(width 0.106248)
		(layer "In2.Cu")
		(net "NFP_PCIE0_PET3_N")
	)
	(segment
		(start 44.133033 7.938033)
		(end 44.340958 8.145958)
		(width 0.106248)
		(layer "In2.Cu")
		(net "NFP_PCIE0_PET3_N")
	)
	(segment
		(start 49.340973 5.928106)
		(end 49.340973 5.377942)
		(width 0.106248)
		(layer "In2.Cu")
		(net "NFP_PCIE0_PET3_N")
	)
	(segment
		(start 31.072836 6.288811)
		(end 31.561811 5.799836)
		(width 0.110185)
		(layer "In2.Cu")
		(net "NFP_PCIE0_PET3_N")
	)
	(segment
		(start 30.79877 7.346823)
		(end 30.79877 7.120712)
		(width 0.110185)
		(layer "In2.Cu")
		(net "NFP_PCIE0_PET3_N")
	)
	(segment
		(start 56.437987 6.145962)
		(end 56.736996 6.444971)
		(width 0.106248)
		(layer "In2.Cu")
		(net "NFP_PCIE0_PET3_N")
	)
	(segment
		(start 55.040962 6.145962)
		(end 56.437987 6.145962)
		(width 0.106248)
		(layer "In2.Cu")
		(net "NFP_PCIE0_PET3_N")
	)
	(segment
		(start 38.354 5.147945)
		(end 38.380543 5.147945)
		(width 0.106248)
		(layer "In2.Cu")
		(net "NFP_PCIE0_PET3_N")
	)
	(segment
		(start 57.736994 6.541999)
		(end 57.236995 7.041998)
		(width 0.138633)
		(layer "F.Cu")
		(net "NFP_PCIE0_PET2_P")
	)
	(via
		(at 16.6624 9.4869)
		(size 0.762)
		(drill 0.254)
		(layers "F.Cu" "B.Cu")
		(net "NFP_PCIE0_PET2_P")
	)
	(via
		(at 57.736994 6.541999)
		(size 0.4826)
		(drill 0.20574)
		(layers "F.Cu" "B.Cu")
		(net "NFP_PCIE0_PET2_P")
	)
	(segment
		(start 17.2974 10.1219)
		(end 16.6624 9.4869)
		(width 0.138633)
		(layer "B.Cu")
		(net "NFP_PCIE0_PET2_P")
	)
	(segment
		(start 46.133106 2.792171)
		(end 46.133106 2.378024)
		(width 0.106248)
		(layer "In3.Cu")
		(net "NFP_PCIE0_PET2_P")
	)
	(segment
		(start 26.211505 4.656836)
		(end 18.375757 4.656836)
		(width 0.110185)
		(layer "In3.Cu")
		(net "NFP_PCIE0_PET2_P")
	)
	(segment
		(start 38.788035 2.14597)
		(end 38.193701 2.740304)
		(width 0.110185)
		(layer "In3.Cu")
		(net "NFP_PCIE0_PET2_P")
	)
	(segment
		(start 57.470853 6.80814)
		(end 57.470853 6.958406)
		(width 0.106248)
		(layer "In3.Cu")
		(net "NFP_PCIE0_PET2_P")
	)
	(segment
		(start 28.477896 5.301285)
		(end 28.477845 5.301234)
		(width 0.110185)
		(layer "In3.Cu")
		(net "NFP_PCIE0_PET2_P")
	)
	(segment
		(start 58.133107 6.851929)
		(end 58.133107 3.817061)
		(width 0.106248)
		(layer "In3.Cu")
		(net "NFP_PCIE0_PET2_P")
	)
	(segment
		(start 28.653308 5.301285)
		(end 28.477896 5.301285)
		(width 0.110185)
		(layer "In3.Cu")
		(net "NFP_PCIE0_PET2_P")
	)
	(segment
		(start 57.461937 3.145892)
		(end 46.486826 3.145892)
		(width 0.106248)
		(layer "In3.Cu")
		(net "NFP_PCIE0_PET2_P")
	)
	(segment
		(start 38.131623 2.805201)
		(end 37.80089 3.135935)
		(width 0.110185)
		(layer "In3.Cu")
		(net "NFP_PCIE0_PET2_P")
	)
	(segment
		(start 17.483836 5.548757)
		(end 17.483836 7.199757)
		(width 0.110185)
		(layer "In3.Cu")
		(net "NFP_PCIE0_PET2_P")
	)
	(segment
		(start 57.470853 6.958406)
		(end 57.577101 7.064654)
		(width 0.106248)
		(layer "In3.Cu")
		(net "NFP_PCIE0_PET2_P")
	)
	(segment
		(start 58.133107 3.817061)
		(end 57.461937 3.145892)
		(width 0.106248)
		(layer "In3.Cu")
		(net "NFP_PCIE0_PET2_P")
	)
	(segment
		(start 33.710042 2.64066)
		(end 33.710042 2.524379)
		(width 0.110185)
		(layer "In3.Cu")
		(net "NFP_PCIE0_PET2_P")
	)
	(segment
		(start 16.216782 7.704785)
		(end 16.086836 7.834732)
		(width 0.110185)
		(layer "In3.Cu")
		(net "NFP_PCIE0_PET2_P")
	)
	(segment
		(start 33.45467 2.269007)
		(end 33.09333 2.269007)
		(width 0.110185)
		(layer "In3.Cu")
		(net "NFP_PCIE0_PET2_P")
	)
	(segment
		(start 38.193701 2.743098)
		(end 38.131623 2.805176)
		(width 0.110185)
		(layer "In3.Cu")
		(net "NFP_PCIE0_PET2_P")
	)
	(segment
		(start 57.577101 7.064654)
		(end 57.920382 7.064654)
		(width 0.106248)
		(layer "In3.Cu")
		(net "NFP_PCIE0_PET2_P")
	)
	(segment
		(start 26.855928 5.301234)
		(end 26.211505 4.656836)
		(width 0.110185)
		(layer "In3.Cu")
		(net "NFP_PCIE0_PET2_P")
	)
	(segment
		(start 38.193701 2.740304)
		(end 38.193701 2.743098)
		(width 0.110185)
		(layer "In3.Cu")
		(net "NFP_PCIE0_PET2_P")
	)
	(segment
		(start 16.978808 7.704785)
		(end 16.216782 7.704785)
		(width 0.110185)
		(layer "In3.Cu")
		(net "NFP_PCIE0_PET2_P")
	)
	(segment
		(start 16.41475 10.297414)
		(end 16.6624 10.049764)
		(width 0.110185)
		(layer "In3.Cu")
		(net "NFP_PCIE0_PET2_P")
	)
	(segment
		(start 57.736994 6.541999)
		(end 57.470853 6.80814)
		(width 0.106248)
		(layer "In3.Cu")
		(net "NFP_PCIE0_PET2_P")
	)
	(segment
		(start 38.131623 2.805176)
		(end 38.131623 2.805201)
		(width 0.110185)
		(layer "In3.Cu")
		(net "NFP_PCIE0_PET2_P")
	)
	(segment
		(start 16.086836 7.834732)
		(end 16.086836 10.177018)
		(width 0.110185)
		(layer "In3.Cu")
		(net "NFP_PCIE0_PET2_P")
	)
	(segment
		(start 28.477845 5.301234)
		(end 26.855928 5.301234)
		(width 0.110185)
		(layer "In3.Cu")
		(net "NFP_PCIE0_PET2_P")
	)
	(segment
		(start 32.231508 3.130829)
		(end 30.823764 3.130829)
		(width 0.110185)
		(layer "In3.Cu")
		(net "NFP_PCIE0_PET2_P")
	)
	(segment
		(start 45.901051 2.14597)
		(end 38.788035 2.14597)
		(width 0.106248)
		(layer "In3.Cu")
		(net "NFP_PCIE0_PET2_P")
	)
	(segment
		(start 37.80089 3.135935)
		(end 34.205316 3.135935)
		(width 0.110185)
		(layer "In3.Cu")
		(net "NFP_PCIE0_PET2_P")
	)
	(segment
		(start 30.823764 3.130829)
		(end 28.653308 5.301285)
		(width 0.110185)
		(layer "In3.Cu")
		(net "NFP_PCIE0_PET2_P")
	)
	(segment
		(start 33.710042 2.524379)
		(end 33.45467 2.269007)
		(width 0.110185)
		(layer "In3.Cu")
		(net "NFP_PCIE0_PET2_P")
	)
	(segment
		(start 46.133106 2.378024)
		(end 45.901051 2.14597)
		(width 0.106248)
		(layer "In3.Cu")
		(net "NFP_PCIE0_PET2_P")
	)
	(segment
		(start 57.920382 7.064654)
		(end 58.133107 6.851929)
		(width 0.106248)
		(layer "In3.Cu")
		(net "NFP_PCIE0_PET2_P")
	)
	(segment
		(start 17.483836 7.199757)
		(end 16.978808 7.704785)
		(width 0.110185)
		(layer "In3.Cu")
		(net "NFP_PCIE0_PET2_P")
	)
	(segment
		(start 46.486826 3.145892)
		(end 46.133106 2.792171)
		(width 0.106248)
		(layer "In3.Cu")
		(net "NFP_PCIE0_PET2_P")
	)
	(segment
		(start 34.205316 3.135935)
		(end 33.710042 2.64066)
		(width 0.110185)
		(layer "In3.Cu")
		(net "NFP_PCIE0_PET2_P")
	)
	(segment
		(start 33.09333 2.269007)
		(end 32.231508 3.130829)
		(width 0.110185)
		(layer "In3.Cu")
		(net "NFP_PCIE0_PET2_P")
	)
	(segment
		(start 16.207232 10.297414)
		(end 16.41475 10.297414)
		(width 0.110185)
		(layer "In3.Cu")
		(net "NFP_PCIE0_PET2_P")
	)
	(segment
		(start 16.6624 10.049764)
		(end 16.6624 9.4869)
		(width 0.110185)
		(layer "In3.Cu")
		(net "NFP_PCIE0_PET2_P")
	)
	(segment
		(start 16.086836 10.177018)
		(end 16.207232 10.297414)
		(width 0.110185)
		(layer "In3.Cu")
		(net "NFP_PCIE0_PET2_P")
	)
	(segment
		(start 18.375757 4.656836)
		(end 17.483836 5.548757)
		(width 0.110185)
		(layer "In3.Cu")
		(net "NFP_PCIE0_PET2_P")
	)
	(segment
		(start 57.736994 7.541997)
		(end 57.236995 8.041996)
		(width 0.138633)
		(layer "F.Cu")
		(net "NFP_PCIE0_PET2_N")
	)
	(via
		(at 57.736994 7.541997)
		(size 0.4826)
		(drill 0.20574)
		(layers "F.Cu" "B.Cu")
		(net "NFP_PCIE0_PET2_N")
	)
	(via
		(at 16.6624 10.7569)
		(size 0.762)
		(drill 0.2667)
		(layers "F.Cu" "B.Cu")
		(net "NFP_PCIE0_PET2_N")
	)
	(segment
		(start 17.2974 11.3919)
		(end 16.6624 10.7569)
		(width 0.138633)
		(layer "B.Cu")
		(net "NFP_PCIE0_PET2_N")
	)
	(segment
		(start 16.119475 10.50925)
		(end 16.41475 10.50925)
		(width 0.110185)
		(layer "In3.Cu")
		(net "NFP_PCIE0_PET2_N")
	)
	(segment
		(start 17.272 5.461)
		(end 17.272 7.112)
		(width 0.110185)
		(layer "In3.Cu")
		(net "NFP_PCIE0_PET2_N")
	)
	(segment
		(start 38.874929 1.93609)
		(end 38.78801 1.936115)
		(width 0.106248)
		(layer "In3.Cu")
		(net "NFP_PCIE0_PET2_N")
	)
	(segment
		(start 33.921878 2.436622)
		(end 33.542427 2.057171)
		(width 0.110185)
		(layer "In3.Cu")
		(net "NFP_PCIE0_PET2_N")
	)
	(segment
		(start 33.542427 2.057171)
		(end 33.005573 2.057171)
		(width 0.110185)
		(layer "In3.Cu")
		(net "NFP_PCIE0_PET2_N")
	)
	(segment
		(start 30.736007 2.918993)
		(end 28.565602 5.089398)
		(width 0.110185)
		(layer "In3.Cu")
		(net "NFP_PCIE0_PET2_N")
	)
	(segment
		(start 37.919787 2.717444)
		(end 37.713133 2.924099)
		(width 0.110185)
		(layer "In3.Cu")
		(net "NFP_PCIE0_PET2_N")
	)
	(segment
		(start 26.299262 4.445)
		(end 18.288 4.445)
		(width 0.110185)
		(layer "In3.Cu")
		(net "NFP_PCIE0_PET2_N")
	)
	(segment
		(start 58.340955 6.938035)
		(end 58.340955 3.730955)
		(width 0.106248)
		(layer "In3.Cu")
		(net "NFP_PCIE0_PET2_N")
	)
	(segment
		(start 34.293073 2.924099)
		(end 33.921878 2.552903)
		(width 0.110185)
		(layer "In3.Cu")
		(net "NFP_PCIE0_PET2_N")
	)
	(segment
		(start 16.2338 7.492924)
		(end 16.129025 7.492949)
		(width 0.110185)
		(layer "In3.Cu")
		(net "NFP_PCIE0_PET2_N")
	)
	(segment
		(start 18.288 4.445)
		(end 17.272 5.461)
		(width 0.110185)
		(layer "In3.Cu")
		(net "NFP_PCIE0_PET2_N")
	)
	(segment
		(start 38.658444 1.978812)
		(end 38.6556 1.978812)
		(width 0.106248)
		(layer "In3.Cu")
		(net "NFP_PCIE0_PET2_N")
	)
	(segment
		(start 46.340954 2.291918)
		(end 45.987157 1.938122)
		(width 0.106248)
		(layer "In3.Cu")
		(net "NFP_PCIE0_PET2_N")
	)
	(segment
		(start 38.78801 1.936115)
		(end 38.701116 1.936115)
		(width 0.106248)
		(layer "In3.Cu")
		(net "NFP_PCIE0_PET2_N")
	)
	(segment
		(start 17.272 7.112)
		(end 16.891076 7.492924)
		(width 0.110185)
		(layer "In3.Cu")
		(net "NFP_PCIE0_PET2_N")
	)
	(segment
		(start 32.143751 2.918993)
		(end 30.736007 2.918993)
		(width 0.110185)
		(layer "In3.Cu")
		(net "NFP_PCIE0_PET2_N")
	)
	(segment
		(start 58.340955 3.730955)
		(end 57.548043 2.938043)
		(width 0.106248)
		(layer "In3.Cu")
		(net "NFP_PCIE0_PET2_N")
	)
	(segment
		(start 37.981865 2.655341)
		(end 37.919787 2.717419)
		(width 0.110185)
		(layer "In3.Cu")
		(net "NFP_PCIE0_PET2_N")
	)
	(segment
		(start 28.565602 5.089398)
		(end 26.943685 5.089398)
		(width 0.110185)
		(layer "In3.Cu")
		(net "NFP_PCIE0_PET2_N")
	)
	(segment
		(start 45.987157 1.938122)
		(end 38.876961 1.938122)
		(width 0.106248)
		(layer "In3.Cu")
		(net "NFP_PCIE0_PET2_N")
	)
	(segment
		(start 57.548043 2.938043)
		(end 46.572932 2.938043)
		(width 0.106248)
		(layer "In3.Cu")
		(net "NFP_PCIE0_PET2_N")
	)
	(segment
		(start 46.572932 2.938043)
		(end 46.340954 2.706065)
		(width 0.106248)
		(layer "In3.Cu")
		(net "NFP_PCIE0_PET2_N")
	)
	(segment
		(start 38.876961 1.938122)
		(end 38.874929 1.93609)
		(width 0.106248)
		(layer "In3.Cu")
		(net "NFP_PCIE0_PET2_N")
	)
	(segment
		(start 16.129025 7.492949)
		(end 15.875 7.746975)
		(width 0.110185)
		(layer "In3.Cu")
		(net "NFP_PCIE0_PET2_N")
	)
	(segment
		(start 16.41475 10.50925)
		(end 16.6624 10.7569)
		(width 0.110185)
		(layer "In3.Cu")
		(net "NFP_PCIE0_PET2_N")
	)
	(segment
		(start 15.875 10.264775)
		(end 16.119475 10.50925)
		(width 0.110185)
		(layer "In3.Cu")
		(net "NFP_PCIE0_PET2_N")
	)
	(segment
		(start 37.981865 2.652547)
		(end 37.981865 2.655341)
		(width 0.110185)
		(layer "In3.Cu")
		(net "NFP_PCIE0_PET2_N")
	)
	(segment
		(start 26.943685 5.089398)
		(end 26.299262 4.445)
		(width 0.110185)
		(layer "In3.Cu")
		(net "NFP_PCIE0_PET2_N")
	)
	(segment
		(start 37.919787 2.717419)
		(end 37.919787 2.717444)
		(width 0.110185)
		(layer "In3.Cu")
		(net "NFP_PCIE0_PET2_N")
	)
	(segment
		(start 38.701116 1.936115)
		(end 38.658444 1.978812)
		(width 0.106248)
		(layer "In3.Cu")
		(net "NFP_PCIE0_PET2_N")
	)
	(segment
		(start 37.713133 2.924099)
		(end 34.293073 2.924099)
		(width 0.110185)
		(layer "In3.Cu")
		(net "NFP_PCIE0_PET2_N")
	)
	(segment
		(start 15.875 7.746975)
		(end 15.875 10.264775)
		(width 0.110185)
		(layer "In3.Cu")
		(net "NFP_PCIE0_PET2_N")
	)
	(segment
		(start 16.891076 7.492924)
		(end 16.2338 7.492924)
		(width 0.110185)
		(layer "In3.Cu")
		(net "NFP_PCIE0_PET2_N")
	)
	(segment
		(start 33.005573 2.057171)
		(end 32.143751 2.918993)
		(width 0.110185)
		(layer "In3.Cu")
		(net "NFP_PCIE0_PET2_N")
	)
	(segment
		(start 46.340954 2.706065)
		(end 46.340954 2.291918)
		(width 0.106248)
		(layer "In3.Cu")
		(net "NFP_PCIE0_PET2_N")
	)
	(segment
		(start 57.736994 7.541997)
		(end 58.340955 6.938035)
		(width 0.106248)
		(layer "In3.Cu")
		(net "NFP_PCIE0_PET2_N")
	)
	(segment
		(start 33.921878 2.552903)
		(end 33.921878 2.436622)
		(width 0.110185)
		(layer "In3.Cu")
		(net "NFP_PCIE0_PET2_N")
	)
	(segment
		(start 38.638226 1.996186)
		(end 37.981865 2.652547)
		(width 0.110185)
		(layer "In3.Cu")
		(net "NFP_PCIE0_PET2_N")
	)
	(segment
		(start 38.6556 1.978812)
		(end 38.638226 1.996186)
		(width 0.106248)
		(layer "In3.Cu")
		(net "NFP_PCIE0_PET2_N")
	)
	(segment
		(start 58.736992 5.542001)
		(end 58.236993 6.042)
		(width 0.138633)
		(layer "F.Cu")
		(net "NFP_PCIE0_PET1_P")
	)
	(via
		(at 58.736992 5.542001)
		(size 0.4826)
		(drill 0.20574)
		(layers "F.Cu" "B.Cu")
		(net "NFP_PCIE0_PET1_P")
	)
	(via
		(at 15.3924 6.9469)
		(size 0.762)
		(drill 0.254)
		(layers "F.Cu" "B.Cu")
		(net "NFP_PCIE0_PET1_P")
	)
	(segment
		(start 16.0274 7.5819)
		(end 15.3924 6.9469)
		(width 0.138633)
		(layer "B.Cu")
		(net "NFP_PCIE0_PET1_P")
	)
	(segment
		(start 58.340955 5.735752)
		(end 58.447203 5.842)
		(width 0.106248)
		(layer "In2.Cu")
		(net "NFP_PCIE0_PET1_P")
	)
	(segment
		(start 25.206706 5.696966)
		(end 25.56637 6.05663)
		(width 0.110185)
		(layer "In2.Cu")
		(net "NFP_PCIE0_PET1_P")
	)
	(segment
		(start 17.582134 7.436866)
		(end 19.322034 5.696966)
		(width 0.110185)
		(layer "In2.Cu")
		(net "NFP_PCIE0_PET1_P")
	)
	(segment
		(start 43.400878 1.938122)
		(end 47.023122 1.938122)
		(width 0.106248)
		(layer "In2.Cu")
		(net "NFP_PCIE0_PET1_P")
	)
	(segment
		(start 31.39534 3.649345)
		(end 33.04634 3.649345)
		(width 0.110185)
		(layer "In2.Cu")
		(net "NFP_PCIE0_PET1_P")
	)
	(segment
		(start 33.04634 3.649345)
		(end 33.759648 2.936037)
		(width 0.110185)
		(layer "In2.Cu")
		(net "NFP_PCIE0_PET1_P")
	)
	(segment
		(start 47.023122 1.938122)
		(end 48.023043 2.938043)
		(width 0.106248)
		(layer "In2.Cu")
		(net "NFP_PCIE0_PET1_P")
	)
	(segment
		(start 15.882366 7.436866)
		(end 17.582134 7.436866)
		(width 0.110185)
		(layer "In2.Cu")
		(net "NFP_PCIE0_PET1_P")
	)
	(segment
		(start 58.056094 2.938043)
		(end 58.340955 3.222904)
		(width 0.106248)
		(layer "In2.Cu")
		(net "NFP_PCIE0_PET1_P")
	)
	(segment
		(start 58.630744 5.842)
		(end 58.736992 5.735752)
		(width 0.106248)
		(layer "In2.Cu")
		(net "NFP_PCIE0_PET1_P")
	)
	(segment
		(start 38.354 2.936037)
		(end 38.380543 2.936037)
		(width 0.106248)
		(layer "In2.Cu")
		(net "NFP_PCIE0_PET1_P")
	)
	(segment
		(start 25.56637 6.05663)
		(end 28.988055 6.05663)
		(width 0.110185)
		(layer "In2.Cu")
		(net "NFP_PCIE0_PET1_P")
	)
	(segment
		(start 42.901057 2.938043)
		(end 43.133112 2.705989)
		(width 0.106248)
		(layer "In2.Cu")
		(net "NFP_PCIE0_PET1_P")
	)
	(segment
		(start 19.322034 5.696966)
		(end 25.206706 5.696966)
		(width 0.110185)
		(layer "In2.Cu")
		(net "NFP_PCIE0_PET1_P")
	)
	(segment
		(start 15.3924 6.9469)
		(end 15.882366 7.436866)
		(width 0.110185)
		(layer "In2.Cu")
		(net "NFP_PCIE0_PET1_P")
	)
	(segment
		(start 33.759648 2.936037)
		(end 38.354 2.936037)
		(width 0.110185)
		(layer "In2.Cu")
		(net "NFP_PCIE0_PET1_P")
	)
	(segment
		(start 28.988055 6.05663)
		(end 31.39534 3.649345)
		(width 0.110185)
		(layer "In2.Cu")
		(net "NFP_PCIE0_PET1_P")
	)
	(segment
		(start 58.736992 5.735752)
		(end 58.736992 5.542001)
		(width 0.106248)
		(layer "In2.Cu")
		(net "NFP_PCIE0_PET1_P")
	)
	(segment
		(start 43.133112 2.205888)
		(end 43.400878 1.938122)
		(width 0.106248)
		(layer "In2.Cu")
		(net "NFP_PCIE0_PET1_P")
	)
	(segment
		(start 38.843991 2.938043)
		(end 42.901057 2.938043)
		(width 0.106248)
		(layer "In2.Cu")
		(net "NFP_PCIE0_PET1_P")
	)
	(segment
		(start 48.023043 2.938043)
		(end 58.056094 2.938043)
		(width 0.106248)
		(layer "In2.Cu")
		(net "NFP_PCIE0_PET1_P")
	)
	(segment
		(start 38.380543 2.936037)
		(end 38.382524 2.938018)
		(width 0.106248)
		(layer "In2.Cu")
		(net "NFP_PCIE0_PET1_P")
	)
	(segment
		(start 38.382524 2.938018)
		(end 38.843991 2.938043)
		(width 0.106248)
		(layer "In2.Cu")
		(net "NFP_PCIE0_PET1_P")
	)
	(segment
		(start 58.340955 3.222904)
		(end 58.340955 5.735752)
		(width 0.106248)
		(layer "In2.Cu")
		(net "NFP_PCIE0_PET1_P")
	)
	(segment
		(start 58.447203 5.842)
		(end 58.630744 5.842)
		(width 0.106248)
		(layer "In2.Cu")
		(net "NFP_PCIE0_PET1_P")
	)
	(segment
		(start 43.133112 2.705989)
		(end 43.133112 2.205888)
		(width 0.106248)
		(layer "In2.Cu")
		(net "NFP_PCIE0_PET1_P")
	)
	(segment
		(start 58.736992 6.541999)
		(end 58.236993 7.041998)
		(width 0.138633)
		(layer "F.Cu")
		(net "NFP_PCIE0_PET1_N")
	)
	(via
		(at 15.3924 8.2169)
		(size 0.762)
		(drill 0.2667)
		(layers "F.Cu" "B.Cu")
		(net "NFP_PCIE0_PET1_N")
	)
	(via
		(at 58.736992 6.541999)
		(size 0.4826)
		(drill 0.20574)
		(layers "F.Cu" "B.Cu")
		(net "NFP_PCIE0_PET1_N")
	)
	(segment
		(start 16.0274 8.8519)
		(end 15.3924 8.2169)
		(width 0.138633)
		(layer "B.Cu")
		(net "NFP_PCIE0_PET1_N")
	)
	(segment
		(start 31.483097 3.861181)
		(end 33.134097 3.861181)
		(width 0.110185)
		(layer "In2.Cu")
		(net "NFP_PCIE0_PET1_N")
	)
	(segment
		(start 25.478613 6.268466)
		(end 29.075812 6.268466)
		(width 0.110185)
		(layer "In2.Cu")
		(net "NFP_PCIE0_PET1_N")
	)
	(segment
		(start 29.075812 6.268466)
		(end 31.483097 3.861181)
		(width 0.110185)
		(layer "In2.Cu")
		(net "NFP_PCIE0_PET1_N")
	)
	(segment
		(start 33.134097 3.861181)
		(end 33.847405 3.147873)
		(width 0.110185)
		(layer "In2.Cu")
		(net "NFP_PCIE0_PET1_N")
	)
	(segment
		(start 57.969937 3.145892)
		(end 58.133107 3.309061)
		(width 0.106248)
		(layer "In2.Cu")
		(net "NFP_PCIE0_PET1_N")
	)
	(segment
		(start 46.937016 2.14597)
		(end 47.54151 2.75049)
		(width 0.106248)
		(layer "In2.Cu")
		(net "NFP_PCIE0_PET1_N")
	)
	(segment
		(start 43.34096 2.792095)
		(end 43.34096 2.291994)
		(width 0.106248)
		(layer "In2.Cu")
		(net "NFP_PCIE0_PET1_N")
	)
	(segment
		(start 38.354 3.147873)
		(end 38.380543 3.147873)
		(width 0.106248)
		(layer "In2.Cu")
		(net "NFP_PCIE0_PET1_N")
	)
	(segment
		(start 47.54151 2.75049)
		(end 47.936912 3.145892)
		(width 0.106248)
		(layer "In2.Cu")
		(net "NFP_PCIE0_PET1_N")
	)
	(segment
		(start 33.847405 3.147873)
		(end 38.354 3.147873)
		(width 0.110185)
		(layer "In2.Cu")
		(net "NFP_PCIE0_PET1_N")
	)
	(segment
		(start 38.380543 3.147873)
		(end 38.382524 3.145892)
		(width 0.106248)
		(layer "In2.Cu")
		(net "NFP_PCIE0_PET1_N")
	)
	(segment
		(start 58.133107 3.309061)
		(end 58.133107 5.938114)
		(width 0.106248)
		(layer "In2.Cu")
		(net "NFP_PCIE0_PET1_N")
	)
	(segment
		(start 38.382524 3.145892)
		(end 42.987163 3.145892)
		(width 0.106248)
		(layer "In2.Cu")
		(net "NFP_PCIE0_PET1_N")
	)
	(segment
		(start 17.669891 7.648702)
		(end 19.409791 5.908802)
		(width 0.110185)
		(layer "In2.Cu")
		(net "NFP_PCIE0_PET1_N")
	)
	(segment
		(start 47.936912 3.145892)
		(end 57.969937 3.145892)
		(width 0.106248)
		(layer "In2.Cu")
		(net "NFP_PCIE0_PET1_N")
	)
	(segment
		(start 19.409791 5.908802)
		(end 25.118949 5.908802)
		(width 0.110185)
		(layer "In2.Cu")
		(net "NFP_PCIE0_PET1_N")
	)
	(segment
		(start 43.486984 2.14597)
		(end 46.937016 2.14597)
		(width 0.106248)
		(layer "In2.Cu")
		(net "NFP_PCIE0_PET1_N")
	)
	(segment
		(start 58.133107 5.938114)
		(end 58.736992 6.541999)
		(width 0.106248)
		(layer "In2.Cu")
		(net "NFP_PCIE0_PET1_N")
	)
	(segment
		(start 15.3924 8.2169)
		(end 15.960598 7.648702)
		(width 0.110185)
		(layer "In2.Cu")
		(net "NFP_PCIE0_PET1_N")
	)
	(segment
		(start 43.34096 2.291994)
		(end 43.486984 2.14597)
		(width 0.106248)
		(layer "In2.Cu")
		(net "NFP_PCIE0_PET1_N")
	)
	(segment
		(start 15.960598 7.648702)
		(end 17.669891 7.648702)
		(width 0.110185)
		(layer "In2.Cu")
		(net "NFP_PCIE0_PET1_N")
	)
	(segment
		(start 25.118949 5.908802)
		(end 25.478613 6.268466)
		(width 0.110185)
		(layer "In2.Cu")
		(net "NFP_PCIE0_PET1_N")
	)
	(segment
		(start 42.987163 3.145892)
		(end 43.34096 2.792095)
		(width 0.106248)
		(layer "In2.Cu")
		(net "NFP_PCIE0_PET1_N")
	)
	(segment
		(start 59.73699 6.541999)
		(end 59.236991 7.041998)
		(width 0.138633)
		(layer "F.Cu")
		(net "NFP_PCIE0_PET0_P")
	)
	(via
		(at 16.6624 4.4069)
		(size 0.762)
		(drill 0.254)
		(layers "F.Cu" "B.Cu")
		(net "NFP_PCIE0_PET0_P")
	)
	(via
		(at 59.73699 6.541999)
		(size 0.4826)
		(drill 0.20574)
		(layers "F.Cu" "B.Cu")
		(net "NFP_PCIE0_PET0_P")
	)
	(segment
		(start 17.2974 5.0419)
		(end 16.6624 4.4069)
		(width 0.138633)
		(layer "B.Cu")
		(net "NFP_PCIE0_PET0_P")
	)
	(segment
		(start 51.411251 2.216658)
		(end 51.121666 1.927073)
		(width 0.110185)
		(layer "In2.Cu")
		(net "NFP_PCIE0_PET0_P")
	)
	(segment
		(start 52.139342 2.216658)
		(end 51.411251 2.216658)
		(width 0.110185)
		(layer "In2.Cu")
		(net "NFP_PCIE0_PET0_P")
	)
	(segment
		(start 32.948093 2.114652)
		(end 32.919111 2.114652)
		(width 0.110185)
		(layer "In2.Cu")
		(net "NFP_PCIE0_PET0_P")
	)
	(segment
		(start 59.73699 6.751752)
		(end 59.630742 6.858)
		(width 0.106248)
		(layer "In2.Cu")
		(net "NFP_PCIE0_PET0_P")
	)
	(segment
		(start 47.740418 1.336294)
		(end 47.254262 1.336294)
		(width 0.110185)
		(layer "In2.Cu")
		(net "NFP_PCIE0_PET0_P")
	)
	(segment
		(start 59.447201 6.858)
		(end 59.340953 6.751752)
		(width 0.106248)
		(layer "In2.Cu")
		(net "NFP_PCIE0_PET0_P")
	)
	(segment
		(start 59.340953 6.751752)
		(end 59.340953 2.464791)
		(width 0.106248)
		(layer "In2.Cu")
		(net "NFP_PCIE0_PET0_P")
	)
	(segment
		(start 33.782051 1.650949)
		(end 33.375829 2.057171)
		(width 0.110185)
		(layer "In2.Cu")
		(net "NFP_PCIE0_PET0_P")
	)
	(segment
		(start 41.783 1.651)
		(end 33.957514 1.651)
		(width 0.110185)
		(layer "In2.Cu")
		(net "NFP_PCIE0_PET0_P")
	)
	(segment
		(start 49.109757 1.927073)
		(end 48.331196 1.927073)
		(width 0.110185)
		(layer "In2.Cu")
		(net "NFP_PCIE0_PET0_P")
	)
	(segment
		(start 54.081147 2.328164)
		(end 53.427757 2.328164)
		(width 0.110185)
		(layer "In2.Cu")
		(net "NFP_PCIE0_PET0_P")
	)
	(segment
		(start 53.427757 2.328164)
		(end 53.026666 1.927073)
		(width 0.110185)
		(layer "In2.Cu")
		(net "NFP_PCIE0_PET0_P")
	)
	(segment
		(start 59.297214 2.421052)
		(end 59.297138 2.415388)
		(width 0.106248)
		(layer "In2.Cu")
		(net "NFP_PCIE0_PET0_P")
	)
	(segment
		(start 50.000179 2.289581)
		(end 49.472266 2.289581)
		(width 0.110185)
		(layer "In2.Cu")
		(net "NFP_PCIE0_PET0_P")
	)
	(segment
		(start 18.415 4.445)
		(end 17.924018 4.935982)
		(width 0.110185)
		(layer "In2.Cu")
		(net "NFP_PCIE0_PET0_P")
	)
	(segment
		(start 26.035 4.445)
		(end 18.415 4.445)
		(width 0.110185)
		(layer "In2.Cu")
		(net "NFP_PCIE0_PET0_P")
	)
	(segment
		(start 26.806398 5.216398)
		(end 26.035 4.445)
		(width 0.110185)
		(layer "In2.Cu")
		(net "NFP_PCIE0_PET0_P")
	)
	(segment
		(start 50.362688 1.927073)
		(end 50.000179 2.289581)
		(width 0.110185)
		(layer "In2.Cu")
		(net "NFP_PCIE0_PET0_P")
	)
	(segment
		(start 31.099887 2.936113)
		(end 28.819602 5.216398)
		(width 0.110185)
		(layer "In2.Cu")
		(net "NFP_PCIE0_PET0_P")
	)
	(segment
		(start 58.801813 1.927073)
		(end 54.482238 1.927073)
		(width 0.110185)
		(layer "In2.Cu")
		(net "NFP_PCIE0_PET0_P")
	)
	(segment
		(start 28.819602 5.216398)
		(end 26.806398 5.216398)
		(width 0.110185)
		(layer "In2.Cu")
		(net "NFP_PCIE0_PET0_P")
	)
	(segment
		(start 49.472266 2.289581)
		(end 49.109757 1.927073)
		(width 0.110185)
		(layer "In2.Cu")
		(net "NFP_PCIE0_PET0_P")
	)
	(segment
		(start 33.005573 2.057171)
		(end 32.948093 2.114652)
		(width 0.110185)
		(layer "In2.Cu")
		(net "NFP_PCIE0_PET0_P")
	)
	(segment
		(start 53.026666 1.927073)
		(end 52.428927 1.927073)
		(width 0.110185)
		(layer "In2.Cu")
		(net "NFP_PCIE0_PET0_P")
	)
	(segment
		(start 33.957463 1.650949)
		(end 33.782051 1.650949)
		(width 0.110185)
		(layer "In2.Cu")
		(net "NFP_PCIE0_PET0_P")
	)
	(segment
		(start 54.482238 1.927073)
		(end 54.081147 2.328164)
		(width 0.110185)
		(layer "In2.Cu")
		(net "NFP_PCIE0_PET0_P")
	)
	(segment
		(start 33.375829 2.057171)
		(end 33.005573 2.057171)
		(width 0.110185)
		(layer "In2.Cu")
		(net "NFP_PCIE0_PET0_P")
	)
	(segment
		(start 17.191482 4.935982)
		(end 16.6624 4.4069)
		(width 0.110185)
		(layer "In2.Cu")
		(net "NFP_PCIE0_PET0_P")
	)
	(segment
		(start 42.291 1.143)
		(end 41.783 1.651)
		(width 0.110185)
		(layer "In2.Cu")
		(net "NFP_PCIE0_PET0_P")
	)
	(segment
		(start 48.331196 1.927073)
		(end 47.740418 1.336294)
		(width 0.110185)
		(layer "In2.Cu")
		(net "NFP_PCIE0_PET0_P")
	)
	(segment
		(start 59.283702 2.402281)
		(end 58.801813 1.927073)
		(width 0.110185)
		(layer "In2.Cu")
		(net "NFP_PCIE0_PET0_P")
	)
	(segment
		(start 59.340953 2.464791)
		(end 59.297214 2.421052)
		(width 0.106248)
		(layer "In2.Cu")
		(net "NFP_PCIE0_PET0_P")
	)
	(segment
		(start 51.121666 1.927073)
		(end 50.362688 1.927073)
		(width 0.110185)
		(layer "In2.Cu")
		(net "NFP_PCIE0_PET0_P")
	)
	(segment
		(start 47.060968 1.143)
		(end 42.291 1.143)
		(width 0.110185)
		(layer "In2.Cu")
		(net "NFP_PCIE0_PET0_P")
	)
	(segment
		(start 59.73699 6.541999)
		(end 59.73699 6.751752)
		(width 0.106248)
		(layer "In2.Cu")
		(net "NFP_PCIE0_PET0_P")
	)
	(segment
		(start 32.09765 2.936113)
		(end 31.099887 2.936113)
		(width 0.110185)
		(layer "In2.Cu")
		(net "NFP_PCIE0_PET0_P")
	)
	(segment
		(start 33.957514 1.651)
		(end 33.957463 1.650949)
		(width 0.110185)
		(layer "In2.Cu")
		(net "NFP_PCIE0_PET0_P")
	)
	(segment
		(start 52.428927 1.927073)
		(end 52.139342 2.216658)
		(width 0.110185)
		(layer "In2.Cu")
		(net "NFP_PCIE0_PET0_P")
	)
	(segment
		(start 59.297138 2.415388)
		(end 59.283702 2.402281)
		(width 0.106248)
		(layer "In2.Cu")
		(net "NFP_PCIE0_PET0_P")
	)
	(segment
		(start 47.254262 1.336294)
		(end 47.060968 1.143)
		(width 0.110185)
		(layer "In2.Cu")
		(net "NFP_PCIE0_PET0_P")
	)
	(segment
		(start 32.919111 2.114652)
		(end 32.09765 2.936113)
		(width 0.110185)
		(layer "In2.Cu")
		(net "NFP_PCIE0_PET0_P")
	)
	(segment
		(start 59.630742 6.858)
		(end 59.447201 6.858)
		(width 0.106248)
		(layer "In2.Cu")
		(net "NFP_PCIE0_PET0_P")
	)
	(segment
		(start 17.924018 4.935982)
		(end 17.191482 4.935982)
		(width 0.110185)
		(layer "In2.Cu")
		(net "NFP_PCIE0_PET0_P")
	)
	(segment
		(start 59.73699 7.541997)
		(end 59.236991 8.041996)
		(width 0.138633)
		(layer "F.Cu")
		(net "NFP_PCIE0_PET0_N")
	)
	(via
		(at 59.73699 7.541997)
		(size 0.4826)
		(drill 0.20574)
		(layers "F.Cu" "B.Cu")
		(net "NFP_PCIE0_PET0_N")
	)
	(via
		(at 16.6624 5.6769)
		(size 0.762)
		(drill 0.2667)
		(layers "F.Cu" "B.Cu")
		(net "NFP_PCIE0_PET0_N")
	)
	(segment
		(start 17.2974 6.3119)
		(end 16.6624 5.6769)
		(width 0.138633)
		(layer "B.Cu")
		(net "NFP_PCIE0_PET0_N")
	)
	(segment
		(start 48.243439 2.138909)
		(end 47.652661 1.54813)
		(width 0.110185)
		(layer "In2.Cu")
		(net "NFP_PCIE0_PET0_N")
	)
	(segment
		(start 58.714564 2.138909)
		(end 54.569995 2.138909)
		(width 0.110185)
		(layer "In2.Cu")
		(net "NFP_PCIE0_PET0_N")
	)
	(segment
		(start 46.973211 1.354836)
		(end 42.378757 1.354836)
		(width 0.110185)
		(layer "In2.Cu")
		(net "NFP_PCIE0_PET0_N")
	)
	(segment
		(start 33.463586 2.269007)
		(end 33.09333 2.269007)
		(width 0.110185)
		(layer "In2.Cu")
		(net "NFP_PCIE0_PET0_N")
	)
	(segment
		(start 18.502757 4.656836)
		(end 18.011775 5.147818)
		(width 0.110185)
		(layer "In2.Cu")
		(net "NFP_PCIE0_PET0_N")
	)
	(segment
		(start 52.938909 2.138909)
		(end 52.516684 2.138909)
		(width 0.110185)
		(layer "In2.Cu")
		(net "NFP_PCIE0_PET0_N")
	)
	(segment
		(start 53.34 2.54)
		(end 52.938909 2.138909)
		(width 0.110185)
		(layer "In2.Cu")
		(net "NFP_PCIE0_PET0_N")
	)
	(segment
		(start 41.870757 1.862836)
		(end 33.869757 1.862836)
		(width 0.110185)
		(layer "In2.Cu")
		(net "NFP_PCIE0_PET0_N")
	)
	(segment
		(start 49.384509 2.501417)
		(end 49.022 2.138909)
		(width 0.110185)
		(layer "In2.Cu")
		(net "NFP_PCIE0_PET0_N")
	)
	(segment
		(start 59.73699 7.541997)
		(end 59.133105 6.938112)
		(width 0.106248)
		(layer "In2.Cu")
		(net "NFP_PCIE0_PET0_N")
	)
	(segment
		(start 32.968794 2.364562)
		(end 32.185407 3.147949)
		(width 0.110185)
		(layer "In2.Cu")
		(net "NFP_PCIE0_PET0_N")
	)
	(segment
		(start 28.907359 5.428234)
		(end 26.718641 5.428234)
		(width 0.110185)
		(layer "In2.Cu")
		(net "NFP_PCIE0_PET0_N")
	)
	(segment
		(start 25.947243 4.656836)
		(end 18.502757 4.656836)
		(width 0.110185)
		(layer "In2.Cu")
		(net "NFP_PCIE0_PET0_N")
	)
	(segment
		(start 52.227099 2.428494)
		(end 51.323494 2.428494)
		(width 0.110185)
		(layer "In2.Cu")
		(net "NFP_PCIE0_PET0_N")
	)
	(segment
		(start 59.133105 6.938112)
		(end 59.133105 2.555621)
		(width 0.106248)
		(layer "In2.Cu")
		(net "NFP_PCIE0_PET0_N")
	)
	(segment
		(start 52.516684 2.138909)
		(end 52.227099 2.428494)
		(width 0.110185)
		(layer "In2.Cu")
		(net "NFP_PCIE0_PET0_N")
	)
	(segment
		(start 47.166505 1.54813)
		(end 46.973211 1.354836)
		(width 0.110185)
		(layer "In2.Cu")
		(net "NFP_PCIE0_PET0_N")
	)
	(segment
		(start 49.022 2.138909)
		(end 48.243439 2.138909)
		(width 0.110185)
		(layer "In2.Cu")
		(net "NFP_PCIE0_PET0_N")
	)
	(segment
		(start 51.033909 2.138909)
		(end 50.450445 2.138909)
		(width 0.110185)
		(layer "In2.Cu")
		(net "NFP_PCIE0_PET0_N")
	)
	(segment
		(start 31.187644 3.147949)
		(end 28.907359 5.428234)
		(width 0.110185)
		(layer "In2.Cu")
		(net "NFP_PCIE0_PET0_N")
	)
	(segment
		(start 51.323494 2.428494)
		(end 51.033909 2.138909)
		(width 0.110185)
		(layer "In2.Cu")
		(net "NFP_PCIE0_PET0_N")
	)
	(segment
		(start 32.185407 3.147949)
		(end 31.187644 3.147949)
		(width 0.110185)
		(layer "In2.Cu")
		(net "NFP_PCIE0_PET0_N")
	)
	(segment
		(start 17.191482 5.147818)
		(end 16.6624 5.6769)
		(width 0.110185)
		(layer "In2.Cu")
		(net "NFP_PCIE0_PET0_N")
	)
	(segment
		(start 54.168904 2.54)
		(end 53.34 2.54)
		(width 0.110185)
		(layer "In2.Cu")
		(net "NFP_PCIE0_PET0_N")
	)
	(segment
		(start 50.450445 2.138909)
		(end 50.087936 2.501417)
		(width 0.110185)
		(layer "In2.Cu")
		(net "NFP_PCIE0_PET0_N")
	)
	(segment
		(start 54.569995 2.138909)
		(end 54.168904 2.54)
		(width 0.110185)
		(layer "In2.Cu")
		(net "NFP_PCIE0_PET0_N")
	)
	(segment
		(start 32.997775 2.364562)
		(end 32.968794 2.364562)
		(width 0.110185)
		(layer "In2.Cu")
		(net "NFP_PCIE0_PET0_N")
	)
	(segment
		(start 33.869757 1.862836)
		(end 33.463586 2.269007)
		(width 0.110185)
		(layer "In2.Cu")
		(net "NFP_PCIE0_PET0_N")
	)
	(segment
		(start 33.09333 2.269007)
		(end 32.997775 2.364562)
		(width 0.110185)
		(layer "In2.Cu")
		(net "NFP_PCIE0_PET0_N")
	)
	(segment
		(start 47.652661 1.54813)
		(end 47.166505 1.54813)
		(width 0.110185)
		(layer "In2.Cu")
		(net "NFP_PCIE0_PET0_N")
	)
	(segment
		(start 18.011775 5.147818)
		(end 17.191482 5.147818)
		(width 0.110185)
		(layer "In2.Cu")
		(net "NFP_PCIE0_PET0_N")
	)
	(segment
		(start 42.378757 1.354836)
		(end 41.870757 1.862836)
		(width 0.110185)
		(layer "In2.Cu")
		(net "NFP_PCIE0_PET0_N")
	)
	(segment
		(start 26.718641 5.428234)
		(end 25.947243 4.656836)
		(width 0.110185)
		(layer "In2.Cu")
		(net "NFP_PCIE0_PET0_N")
	)
	(segment
		(start 59.133105 2.555621)
		(end 58.714564 2.138909)
		(width 0.110185)
		(layer "In2.Cu")
		(net "NFP_PCIE0_PET0_N")
	)
	(segment
		(start 50.087936 2.501417)
		(end 49.384509 2.501417)
		(width 0.110185)
		(layer "In2.Cu")
		(net "NFP_PCIE0_PET0_N")
	)
	(via
		(at 49.403 0.3429)
		(size 0.508)
		(drill 0.25654)
		(layers "F.Cu" "B.Cu")
		(net "NFP_PCIE0_PER7_P")
	)
	(via
		(at 14.1224 4.4069)
		(size 0.762)
		(drill 0.254)
		(layers "F.Cu" "B.Cu")
		(net "NFP_PCIE0_PER7_P")
	)
	(segment
		(start 14.7574 5.0419)
		(end 14.1224 4.4069)
		(width 0.138633)
		(layer "B.Cu")
		(net "NFP_PCIE0_PER7_P")
	)
	(segment
		(start 14.369796 4.868164)
		(end 15.748 4.868164)
		(width 0.110185)
		(layer "In2.Cu")
		(net "NFP_PCIE0_PER7_P")
	)
	(segment
		(start 10.033 3.81)
		(end 9.652 3.429)
		(width 0.110185)
		(layer "In2.Cu")
		(net "NFP_PCIE0_PER7_P")
	)
	(segment
		(start 10.023602 2.422398)
		(end 10.610342 2.422398)
		(width 0.110185)
		(layer "In2.Cu")
		(net "NFP_PCIE0_PER7_P")
	)
	(segment
		(start 11.655806 2.302002)
		(end 11.776202 2.422398)
		(width 0.110185)
		(layer "In2.Cu")
		(net "NFP_PCIE0_PER7_P")
	)
	(segment
		(start 25.442164 2.611755)
		(end 25.442164 2.351151)
		(width 0.110185)
		(layer "In2.Cu")
		(net "NFP_PCIE0_PER7_P")
	)
	(segment
		(start 19.070955 0.181737)
		(end 19.31543 0.426212)
		(width 0.110185)
		(layer "In2.Cu")
		(net "NFP_PCIE0_PER7_P")
	)
	(segment
		(start 9.525 1.397)
		(end 9.525 1.016)
		(width 0.110185)
		(layer "In2.Cu")
		(net "NFP_PCIE0_PER7_P")
	)
	(segment
		(start 15.729966 2.2352)
		(end 15.729966 2.032)
		(width 0.110185)
		(layer "In2.Cu")
		(net "NFP_PCIE0_PER7_P")
	)
	(segment
		(start 15.729966 2.032)
		(end 15.602966 1.905)
		(width 0.110185)
		(layer "In2.Cu")
		(net "NFP_PCIE0_PER7_P")
	)
	(segment
		(start 20.061301 0.181737)
		(end 46.635721 0.181737)
		(width 0.110185)
		(layer "In2.Cu")
		(net "NFP_PCIE0_PER7_P")
	)
	(segment
		(start 17.38757 2.455164)
		(end 17.648174 2.455164)
		(width 0.110185)
		(layer "In2.Cu")
		(net "NFP_PCIE0_PER7_P")
	)
	(segment
		(start 9.652 2.794)
		(end 10.023602 2.422398)
		(width 0.110185)
		(layer "In2.Cu")
		(net "NFP_PCIE0_PER7_P")
	)
	(segment
		(start 19.69643 3.725164)
		(end 19.816826 3.604768)
		(width 0.110185)
		(layer "In2.Cu")
		(net "NFP_PCIE0_PER7_P")
	)
	(segment
		(start 19.31543 3.604768)
		(end 19.435826 3.725164)
		(width 0.110185)
		(layer "In2.Cu")
		(net "NFP_PCIE0_PER7_P")
	)
	(segment
		(start 17.267174 2.334768)
		(end 17.38757 2.455164)
		(width 0.110185)
		(layer "In2.Cu")
		(net "NFP_PCIE0_PER7_P")
	)
	(segment
		(start 19.435826 3.725164)
		(end 19.69643 3.725164)
		(width 0.110185)
		(layer "In2.Cu")
		(net "NFP_PCIE0_PER7_P")
	)
	(segment
		(start 14.097 1.016)
		(end 14.312671 0.800329)
		(width 0.110185)
		(layer "In2.Cu")
		(net "NFP_PCIE0_PER7_P")
	)
	(segment
		(start 17.022699 0.181737)
		(end 17.267174 0.426212)
		(width 0.110185)
		(layer "In2.Cu")
		(net "NFP_PCIE0_PER7_P")
	)
	(segment
		(start 11.655806 1.006475)
		(end 11.655806 2.302002)
		(width 0.110185)
		(layer "In2.Cu")
		(net "NFP_PCIE0_PER7_P")
	)
	(segment
		(start 20.061301 2.230755)
		(end 19.816826 1.98628)
		(width 0.110185)
		(layer "In2.Cu")
		(net "NFP_PCIE0_PER7_P")
	)
	(segment
		(start 48.721264 -0.338836)
		(end 49.403 0.3429)
		(width 0.110185)
		(layer "In2.Cu")
		(net "NFP_PCIE0_PER7_P")
	)
	(segment
		(start 20.061301 2.732151)
		(end 25.321768 2.732151)
		(width 0.110185)
		(layer "In2.Cu")
		(net "NFP_PCIE0_PER7_P")
	)
	(segment
		(start 10.610342 2.422398)
		(end 10.730738 2.302002)
		(width 0.110185)
		(layer "In2.Cu")
		(net "NFP_PCIE0_PER7_P")
	)
	(segment
		(start 14.312671 0.800329)
		(end 15.659405 0.800329)
		(width 0.110185)
		(layer "In2.Cu")
		(net "NFP_PCIE0_PER7_P")
	)
	(segment
		(start 9.652 3.429)
		(end 9.652 2.794)
		(width 0.110185)
		(layer "In2.Cu")
		(net "NFP_PCIE0_PER7_P")
	)
	(segment
		(start 47.156294 -0.338836)
		(end 48.721264 -0.338836)
		(width 0.110185)
		(layer "In2.Cu")
		(net "NFP_PCIE0_PER7_P")
	)
	(segment
		(start 19.816826 1.98628)
		(end 19.816826 0.426212)
		(width 0.110185)
		(layer "In2.Cu")
		(net "NFP_PCIE0_PER7_P")
	)
	(segment
		(start 10.730738 1.905)
		(end 10.476738 1.651)
		(width 0.110185)
		(layer "In2.Cu")
		(net "NFP_PCIE0_PER7_P")
	)
	(segment
		(start 15.542768 2.422398)
		(end 15.729966 2.2352)
		(width 0.110185)
		(layer "In2.Cu")
		(net "NFP_PCIE0_PER7_P")
	)
	(segment
		(start 15.917164 3.897757)
		(end 15.829407 3.81)
		(width 0.110185)
		(layer "In2.Cu")
		(net "NFP_PCIE0_PER7_P")
	)
	(segment
		(start 15.729966 0.729767)
		(end 15.729966 0.64201)
		(width 0.110185)
		(layer "In2.Cu")
		(net "NFP_PCIE0_PER7_P")
	)
	(segment
		(start 18.013045 0.181737)
		(end 19.070955 0.181737)
		(width 0.110185)
		(layer "In2.Cu")
		(net "NFP_PCIE0_PER7_P")
	)
	(segment
		(start 11.411331 0.762)
		(end 11.655806 1.006475)
		(width 0.110185)
		(layer "In2.Cu")
		(net "NFP_PCIE0_PER7_P")
	)
	(segment
		(start 17.648174 2.455164)
		(end 17.76857 2.334768)
		(width 0.110185)
		(layer "In2.Cu")
		(net "NFP_PCIE0_PER7_P")
	)
	(segment
		(start 15.729966 0.64201)
		(end 16.190239 0.181737)
		(width 0.110185)
		(layer "In2.Cu")
		(net "NFP_PCIE0_PER7_P")
	)
	(segment
		(start 46.635721 0.181737)
		(end 47.156294 -0.338836)
		(width 0.110185)
		(layer "In2.Cu")
		(net "NFP_PCIE0_PER7_P")
	)
	(segment
		(start 17.267174 0.426212)
		(end 17.267174 2.334768)
		(width 0.110185)
		(layer "In2.Cu")
		(net "NFP_PCIE0_PER7_P")
	)
	(segment
		(start 15.748 4.868164)
		(end 15.917164 4.699)
		(width 0.110185)
		(layer "In2.Cu")
		(net "NFP_PCIE0_PER7_P")
	)
	(segment
		(start 25.442164 2.351151)
		(end 25.321768 2.230755)
		(width 0.110185)
		(layer "In2.Cu")
		(net "NFP_PCIE0_PER7_P")
	)
	(segment
		(start 19.31543 0.426212)
		(end 19.31543 3.604768)
		(width 0.110185)
		(layer "In2.Cu")
		(net "NFP_PCIE0_PER7_P")
	)
	(segment
		(start 25.321768 2.732151)
		(end 25.442164 2.611755)
		(width 0.110185)
		(layer "In2.Cu")
		(net "NFP_PCIE0_PER7_P")
	)
	(segment
		(start 14.351 1.905)
		(end 14.097 1.651)
		(width 0.110185)
		(layer "In2.Cu")
		(net "NFP_PCIE0_PER7_P")
	)
	(segment
		(start 10.476738 1.651)
		(end 9.779 1.651)
		(width 0.110185)
		(layer "In2.Cu")
		(net "NFP_PCIE0_PER7_P")
	)
	(segment
		(start 9.525 1.016)
		(end 9.779 0.762)
		(width 0.110185)
		(layer "In2.Cu")
		(net "NFP_PCIE0_PER7_P")
	)
	(segment
		(start 15.829407 3.81)
		(end 10.033 3.81)
		(width 0.110185)
		(layer "In2.Cu")
		(net "NFP_PCIE0_PER7_P")
	)
	(segment
		(start 9.779 1.651)
		(end 9.525 1.397)
		(width 0.110185)
		(layer "In2.Cu")
		(net "NFP_PCIE0_PER7_P")
	)
	(segment
		(start 9.779 0.762)
		(end 11.411331 0.762)
		(width 0.110185)
		(layer "In2.Cu")
		(net "NFP_PCIE0_PER7_P")
	)
	(segment
		(start 14.097 1.651)
		(end 14.097 1.016)
		(width 0.110185)
		(layer "In2.Cu")
		(net "NFP_PCIE0_PER7_P")
	)
	(segment
		(start 15.602966 1.905)
		(end 14.351 1.905)
		(width 0.110185)
		(layer "In2.Cu")
		(net "NFP_PCIE0_PER7_P")
	)
	(segment
		(start 19.816826 2.976626)
		(end 20.061301 2.732151)
		(width 0.110185)
		(layer "In2.Cu")
		(net "NFP_PCIE0_PER7_P")
	)
	(segment
		(start 19.816826 0.426212)
		(end 20.061301 0.181737)
		(width 0.110185)
		(layer "In2.Cu")
		(net "NFP_PCIE0_PER7_P")
	)
	(segment
		(start 14.1224 4.620768)
		(end 14.369796 4.868164)
		(width 0.110185)
		(layer "In2.Cu")
		(net "NFP_PCIE0_PER7_P")
	)
	(segment
		(start 17.76857 2.334768)
		(end 17.76857 0.426212)
		(width 0.110185)
		(layer "In2.Cu")
		(net "NFP_PCIE0_PER7_P")
	)
	(segment
		(start 15.917164 4.699)
		(end 15.917164 3.897757)
		(width 0.110185)
		(layer "In2.Cu")
		(net "NFP_PCIE0_PER7_P")
	)
	(segment
		(start 25.321768 2.230755)
		(end 20.061301 2.230755)
		(width 0.110185)
		(layer "In2.Cu")
		(net "NFP_PCIE0_PER7_P")
	)
	(segment
		(start 14.1224 4.4069)
		(end 14.1224 4.620768)
		(width 0.110185)
		(layer "In2.Cu")
		(net "NFP_PCIE0_PER7_P")
	)
	(segment
		(start 15.659405 0.800329)
		(end 15.729966 0.729767)
		(width 0.110185)
		(layer "In2.Cu")
		(net "NFP_PCIE0_PER7_P")
	)
	(segment
		(start 11.776202 2.422398)
		(end 15.542768 2.422398)
		(width 0.110185)
		(layer "In2.Cu")
		(net "NFP_PCIE0_PER7_P")
	)
	(segment
		(start 19.816826 3.604768)
		(end 19.816826 2.976626)
		(width 0.110185)
		(layer "In2.Cu")
		(net "NFP_PCIE0_PER7_P")
	)
	(segment
		(start 10.730738 2.302002)
		(end 10.730738 1.905)
		(width 0.110185)
		(layer "In2.Cu")
		(net "NFP_PCIE0_PER7_P")
	)
	(segment
		(start 16.190239 0.181737)
		(end 17.022699 0.181737)
		(width 0.110185)
		(layer "In2.Cu")
		(net "NFP_PCIE0_PER7_P")
	)
	(segment
		(start 17.76857 0.426212)
		(end 18.013045 0.181737)
		(width 0.110185)
		(layer "In2.Cu")
		(net "NFP_PCIE0_PER7_P")
	)
	(via
		(at 14.1224 5.6769)
		(size 0.762)
		(drill 0.2667)
		(layers "F.Cu" "B.Cu")
		(net "NFP_PCIE0_PER7_N")
	)
	(via
		(at 48.26 0.3429)
		(size 0.508)
		(drill 0.25654)
		(layers "F.Cu" "B.Cu")
		(net "NFP_PCIE0_PER7_N")
	)
	(segment
		(start 14.7574 6.3119)
		(end 14.1224 5.6769)
		(width 0.138633)
		(layer "B.Cu")
		(net "NFP_PCIE0_PER7_N")
	)
	(segment
		(start 14.438757 1.693164)
		(end 14.308836 1.563243)
		(width 0.110185)
		(layer "In2.Cu")
		(net "NFP_PCIE0_PER7_N")
	)
	(segment
		(start 46.723478 0.393573)
		(end 47.244051 -0.127)
		(width 0.110185)
		(layer "In2.Cu")
		(net "NFP_PCIE0_PER7_N")
	)
	(segment
		(start 10.111359 2.634234)
		(end 10.698099 2.634234)
		(width 0.110185)
		(layer "In2.Cu")
		(net "NFP_PCIE0_PER7_N")
	)
	(segment
		(start 18.983198 0.393573)
		(end 19.103594 0.513969)
		(width 0.110185)
		(layer "In2.Cu")
		(net "NFP_PCIE0_PER7_N")
	)
	(segment
		(start 14.1224 5.3086)
		(end 14.351 5.08)
		(width 0.110185)
		(layer "In2.Cu")
		(net "NFP_PCIE0_PER7_N")
	)
	(segment
		(start 10.942574 2.389759)
		(end 10.942574 1.817243)
		(width 0.110185)
		(layer "In2.Cu")
		(net "NFP_PCIE0_PER7_N")
	)
	(segment
		(start 15.630525 2.634234)
		(end 15.941802 2.322957)
		(width 0.110185)
		(layer "In2.Cu")
		(net "NFP_PCIE0_PER7_N")
	)
	(segment
		(start 9.866757 0.973836)
		(end 11.323574 0.973836)
		(width 0.110185)
		(layer "In2.Cu")
		(net "NFP_PCIE0_PER7_N")
	)
	(segment
		(start 11.323574 0.973836)
		(end 11.44397 1.094232)
		(width 0.110185)
		(layer "In2.Cu")
		(net "NFP_PCIE0_PER7_N")
	)
	(segment
		(start 25.409525 2.943987)
		(end 25.654 2.699512)
		(width 0.110185)
		(layer "In2.Cu")
		(net "NFP_PCIE0_PER7_N")
	)
	(segment
		(start 15.941802 1.944243)
		(end 15.690723 1.693164)
		(width 0.110185)
		(layer "In2.Cu")
		(net "NFP_PCIE0_PER7_N")
	)
	(segment
		(start 16.277996 0.393573)
		(end 16.934942 0.393573)
		(width 0.110185)
		(layer "In2.Cu")
		(net "NFP_PCIE0_PER7_N")
	)
	(segment
		(start 17.735931 2.667)
		(end 17.980406 2.422525)
		(width 0.110185)
		(layer "In2.Cu")
		(net "NFP_PCIE0_PER7_N")
	)
	(segment
		(start 14.400428 1.012165)
		(end 15.747162 1.012165)
		(width 0.110185)
		(layer "In2.Cu")
		(net "NFP_PCIE0_PER7_N")
	)
	(segment
		(start 14.308836 1.563243)
		(end 14.308836 1.103757)
		(width 0.110185)
		(layer "In2.Cu")
		(net "NFP_PCIE0_PER7_N")
	)
	(segment
		(start 20.028662 3.692525)
		(end 20.028662 3.064383)
		(width 0.110185)
		(layer "In2.Cu")
		(net "NFP_PCIE0_PER7_N")
	)
	(segment
		(start 20.028662 0.513969)
		(end 20.149058 0.393573)
		(width 0.110185)
		(layer "In2.Cu")
		(net "NFP_PCIE0_PER7_N")
	)
	(segment
		(start 9.736836 1.103757)
		(end 9.866757 0.973836)
		(width 0.110185)
		(layer "In2.Cu")
		(net "NFP_PCIE0_PER7_N")
	)
	(segment
		(start 17.055338 2.422525)
		(end 17.299813 2.667)
		(width 0.110185)
		(layer "In2.Cu")
		(net "NFP_PCIE0_PER7_N")
	)
	(segment
		(start 10.942574 1.817243)
		(end 10.564495 1.439164)
		(width 0.110185)
		(layer "In2.Cu")
		(net "NFP_PCIE0_PER7_N")
	)
	(segment
		(start 16.129 3.81)
		(end 15.917164 3.598164)
		(width 0.110185)
		(layer "In2.Cu")
		(net "NFP_PCIE0_PER7_N")
	)
	(segment
		(start 10.698099 2.634234)
		(end 10.942574 2.389759)
		(width 0.110185)
		(layer "In2.Cu")
		(net "NFP_PCIE0_PER7_N")
	)
	(segment
		(start 19.348069 3.937)
		(end 19.784187 3.937)
		(width 0.110185)
		(layer "In2.Cu")
		(net "NFP_PCIE0_PER7_N")
	)
	(segment
		(start 15.690723 1.693164)
		(end 14.438757 1.693164)
		(width 0.110185)
		(layer "In2.Cu")
		(net "NFP_PCIE0_PER7_N")
	)
	(segment
		(start 48.5521 0.3429)
		(end 48.26 0.3429)
		(width 0.110185)
		(layer "In2.Cu")
		(net "NFP_PCIE0_PER7_N")
	)
	(segment
		(start 19.103594 3.692525)
		(end 19.348069 3.937)
		(width 0.110185)
		(layer "In2.Cu")
		(net "NFP_PCIE0_PER7_N")
	)
	(segment
		(start 20.149058 2.018919)
		(end 20.028662 1.898523)
		(width 0.110185)
		(layer "In2.Cu")
		(net "NFP_PCIE0_PER7_N")
	)
	(segment
		(start 17.980406 0.513969)
		(end 18.100802 0.393573)
		(width 0.110185)
		(layer "In2.Cu")
		(net "NFP_PCIE0_PER7_N")
	)
	(segment
		(start 19.103594 0.513969)
		(end 19.103594 3.692525)
		(width 0.110185)
		(layer "In2.Cu")
		(net "NFP_PCIE0_PER7_N")
	)
	(segment
		(start 20.028662 1.898523)
		(end 20.028662 0.513969)
		(width 0.110185)
		(layer "In2.Cu")
		(net "NFP_PCIE0_PER7_N")
	)
	(segment
		(start 9.736836 1.309243)
		(end 9.736836 1.103757)
		(width 0.110185)
		(layer "In2.Cu")
		(net "NFP_PCIE0_PER7_N")
	)
	(segment
		(start 11.44397 1.094232)
		(end 11.44397 2.389759)
		(width 0.110185)
		(layer "In2.Cu")
		(net "NFP_PCIE0_PER7_N")
	)
	(segment
		(start 20.149058 2.943987)
		(end 25.409525 2.943987)
		(width 0.110185)
		(layer "In2.Cu")
		(net "NFP_PCIE0_PER7_N")
	)
	(segment
		(start 16.129 4.786757)
		(end 16.129 3.81)
		(width 0.110185)
		(layer "In2.Cu")
		(net "NFP_PCIE0_PER7_N")
	)
	(segment
		(start 15.747162 1.012165)
		(end 15.941802 0.817524)
		(width 0.110185)
		(layer "In2.Cu")
		(net "NFP_PCIE0_PER7_N")
	)
	(segment
		(start 14.351 5.08)
		(end 15.835757 5.08)
		(width 0.110185)
		(layer "In2.Cu")
		(net "NFP_PCIE0_PER7_N")
	)
	(segment
		(start 20.028662 3.064383)
		(end 20.149058 2.943987)
		(width 0.110185)
		(layer "In2.Cu")
		(net "NFP_PCIE0_PER7_N")
	)
	(segment
		(start 25.654 2.699512)
		(end 25.654 2.263394)
		(width 0.110185)
		(layer "In2.Cu")
		(net "NFP_PCIE0_PER7_N")
	)
	(segment
		(start 11.688445 2.634234)
		(end 15.630525 2.634234)
		(width 0.110185)
		(layer "In2.Cu")
		(net "NFP_PCIE0_PER7_N")
	)
	(segment
		(start 15.941802 0.729767)
		(end 16.277996 0.393573)
		(width 0.110185)
		(layer "In2.Cu")
		(net "NFP_PCIE0_PER7_N")
	)
	(segment
		(start 48.633507 -0.127)
		(end 48.718648 -0.041859)
		(width 0.110185)
		(layer "In2.Cu")
		(net "NFP_PCIE0_PER7_N")
	)
	(segment
		(start 15.835757 5.08)
		(end 16.129 4.786757)
		(width 0.110185)
		(layer "In2.Cu")
		(net "NFP_PCIE0_PER7_N")
	)
	(segment
		(start 15.941802 2.322957)
		(end 15.941802 1.944243)
		(width 0.110185)
		(layer "In2.Cu")
		(net "NFP_PCIE0_PER7_N")
	)
	(segment
		(start 9.863836 2.881757)
		(end 10.111359 2.634234)
		(width 0.110185)
		(layer "In2.Cu")
		(net "NFP_PCIE0_PER7_N")
	)
	(segment
		(start 9.863836 3.341243)
		(end 9.863836 2.881757)
		(width 0.110185)
		(layer "In2.Cu")
		(net "NFP_PCIE0_PER7_N")
	)
	(segment
		(start 47.244051 -0.127)
		(end 48.633507 -0.127)
		(width 0.110185)
		(layer "In2.Cu")
		(net "NFP_PCIE0_PER7_N")
	)
	(segment
		(start 11.44397 2.389759)
		(end 11.688445 2.634234)
		(width 0.110185)
		(layer "In2.Cu")
		(net "NFP_PCIE0_PER7_N")
	)
	(segment
		(start 10.564495 1.439164)
		(end 9.866757 1.439164)
		(width 0.110185)
		(layer "In2.Cu")
		(net "NFP_PCIE0_PER7_N")
	)
	(segment
		(start 15.941802 0.817524)
		(end 15.941802 0.729767)
		(width 0.110185)
		(layer "In2.Cu")
		(net "NFP_PCIE0_PER7_N")
	)
	(segment
		(start 25.654 2.263394)
		(end 25.409525 2.018919)
		(width 0.110185)
		(layer "In2.Cu")
		(net "NFP_PCIE0_PER7_N")
	)
	(segment
		(start 16.934942 0.393573)
		(end 17.055338 0.513969)
		(width 0.110185)
		(layer "In2.Cu")
		(net "NFP_PCIE0_PER7_N")
	)
	(segment
		(start 17.980406 2.422525)
		(end 17.980406 0.513969)
		(width 0.110185)
		(layer "In2.Cu")
		(net "NFP_PCIE0_PER7_N")
	)
	(segment
		(start 18.100802 0.393573)
		(end 18.983198 0.393573)
		(width 0.110185)
		(layer "In2.Cu")
		(net "NFP_PCIE0_PER7_N")
	)
	(segment
		(start 25.409525 2.018919)
		(end 20.149058 2.018919)
		(width 0.110185)
		(layer "In2.Cu")
		(net "NFP_PCIE0_PER7_N")
	)
	(segment
		(start 19.784187 3.937)
		(end 20.028662 3.692525)
		(width 0.110185)
		(layer "In2.Cu")
		(net "NFP_PCIE0_PER7_N")
	)
	(segment
		(start 15.917164 3.598164)
		(end 10.120757 3.598164)
		(width 0.110185)
		(layer "In2.Cu")
		(net "NFP_PCIE0_PER7_N")
	)
	(segment
		(start 9.866757 1.439164)
		(end 9.736836 1.309243)
		(width 0.110185)
		(layer "In2.Cu")
		(net "NFP_PCIE0_PER7_N")
	)
	(segment
		(start 48.718648 -0.041859)
		(end 48.718648 0.176352)
		(width 0.110185)
		(layer "In2.Cu")
		(net "NFP_PCIE0_PER7_N")
	)
	(segment
		(start 17.299813 2.667)
		(end 17.735931 2.667)
		(width 0.110185)
		(layer "In2.Cu")
		(net "NFP_PCIE0_PER7_N")
	)
	(segment
		(start 14.308836 1.103757)
		(end 14.400428 1.012165)
		(width 0.110185)
		(layer "In2.Cu")
		(net "NFP_PCIE0_PER7_N")
	)
	(segment
		(start 48.718648 0.176352)
		(end 48.5521 0.3429)
		(width 0.110185)
		(layer "In2.Cu")
		(net "NFP_PCIE0_PER7_N")
	)
	(segment
		(start 20.149058 0.393573)
		(end 46.723478 0.393573)
		(width 0.110185)
		(layer "In2.Cu")
		(net "NFP_PCIE0_PER7_N")
	)
	(segment
		(start 17.055338 0.513969)
		(end 17.055338 2.422525)
		(width 0.110185)
		(layer "In2.Cu")
		(net "NFP_PCIE0_PER7_N")
	)
	(segment
		(start 14.1224 5.6769)
		(end 14.1224 5.3086)
		(width 0.110185)
		(layer "In2.Cu")
		(net "NFP_PCIE0_PER7_N")
	)
	(segment
		(start 10.120757 3.598164)
		(end 9.863836 3.341243)
		(width 0.110185)
		(layer "In2.Cu")
		(net "NFP_PCIE0_PER7_N")
	)
	(via
		(at 51.469036 0.3429)
		(size 0.508)
		(drill 0.25654)
		(layers "F.Cu" "B.Cu")
		(net "NFP_PCIE0_PER6_P")
	)
	(via
		(at 12.8524 6.9469)
		(size 0.762)
		(drill 0.254)
		(layers "F.Cu" "B.Cu")
		(net "NFP_PCIE0_PER6_P")
	)
	(segment
		(start 13.4874 7.5819)
		(end 12.8524 6.9469)
		(width 0.138633)
		(layer "B.Cu")
		(net "NFP_PCIE0_PER6_P")
	)
	(segment
		(start 46.637321 -0.962914)
		(end 50.517679 -0.962914)
		(width 0.110185)
		(layer "In2.Cu")
		(net "NFP_PCIE0_PER6_P")
	)
	(segment
		(start 12.8524 6.9469)
		(end 12.8524 7.228586)
		(width 0.110185)
		(layer "In2.Cu")
		(net "NFP_PCIE0_PER6_P")
	)
	(segment
		(start 6.906768 4.345711)
		(end 6.731 4.345711)
		(width 0.110185)
		(layer "In2.Cu")
		(net "NFP_PCIE0_PER6_P")
	)
	(segment
		(start 46.205902 -0.531495)
		(end 46.637321 -0.962914)
		(width 0.110185)
		(layer "In2.Cu")
		(net "NFP_PCIE0_PER6_P")
	)
	(segment
		(start 12.443841 6.35)
		(end 12.199366 6.105525)
		(width 0.110185)
		(layer "In2.Cu")
		(net "NFP_PCIE0_PER6_P")
	)
	(segment
		(start 8.821979 2.520213)
		(end 8.932164 2.410028)
		(width 0.110185)
		(layer "In2.Cu")
		(net "NFP_PCIE0_PER6_P")
	)
	(segment
		(start 7.027164 3.300247)
		(end 7.027164 2.754478)
		(width 0.110185)
		(layer "In2.Cu")
		(net "NFP_PCIE0_PER6_P")
	)
	(segment
		(start 50.517679 -0.962914)
		(end 51.078968 -0.401625)
		(width 0.110185)
		(layer "In2.Cu")
		(net "NFP_PCIE0_PER6_P")
	)
	(segment
		(start 11.999341 5.059934)
		(end 11.368659 5.059934)
		(width 0.110185)
		(layer "In2.Cu")
		(net "NFP_PCIE0_PER6_P")
	)
	(segment
		(start 12.199366 5.259959)
		(end 11.999341 5.059934)
		(width 0.110185)
		(layer "In2.Cu")
		(net "NFP_PCIE0_PER6_P")
	)
	(segment
		(start 7.261428 2.520213)
		(end 8.821979 2.520213)
		(width 0.110185)
		(layer "In2.Cu")
		(net "NFP_PCIE0_PER6_P")
	)
	(segment
		(start 14.478025 6.35)
		(end 12.443841 6.35)
		(width 0.110185)
		(layer "In2.Cu")
		(net "NFP_PCIE0_PER6_P")
	)
	(segment
		(start 9.659366 5.259959)
		(end 9.459341 5.059934)
		(width 0.110185)
		(layer "In2.Cu")
		(net "NFP_PCIE0_PER6_P")
	)
	(segment
		(start 6.223 3.166643)
		(end 6.477 3.420643)
		(width 0.110185)
		(layer "In2.Cu")
		(net "NFP_PCIE0_PER6_P")
	)
	(segment
		(start 14.739366 6.611341)
		(end 14.478025 6.35)
		(width 0.110185)
		(layer "In2.Cu")
		(net "NFP_PCIE0_PER6_P")
	)
	(segment
		(start 9.002497 -0.655066)
		(end 13.681481 -0.655066)
		(width 0.110185)
		(layer "In2.Cu")
		(net "NFP_PCIE0_PER6_P")
	)
	(segment
		(start 13.939622 7.388098)
		(end 14.582927 7.388098)
		(width 0.110185)
		(layer "In2.Cu")
		(net "NFP_PCIE0_PER6_P")
	)
	(segment
		(start 6.477 7.366)
		(end 6.223 7.62)
		(width 0.110185)
		(layer "In2.Cu")
		(net "NFP_PCIE0_PER6_P")
	)
	(segment
		(start 7.027164 0.924357)
		(end 7.261428 0.690093)
		(width 0.110185)
		(layer "In2.Cu")
		(net "NFP_PCIE0_PER6_P")
	)
	(segment
		(start 9.659366 6.034024)
		(end 9.659366 5.259959)
		(width 0.110185)
		(layer "In2.Cu")
		(net "NFP_PCIE0_PER6_P")
	)
	(segment
		(start 10.213213 7.366)
		(end 9.968738 7.121525)
		(width 0.110185)
		(layer "In2.Cu")
		(net "NFP_PCIE0_PER6_P")
	)
	(segment
		(start 9.968738 7.121525)
		(end 9.968738 6.343396)
		(width 0.110185)
		(layer "In2.Cu")
		(net "NFP_PCIE0_PER6_P")
	)
	(segment
		(start 14.582927 7.388098)
		(end 14.739366 7.231659)
		(width 0.110185)
		(layer "In2.Cu")
		(net "NFP_PCIE0_PER6_P")
	)
	(segment
		(start 6.477 4.599711)
		(end 6.477 7.366)
		(width 0.110185)
		(layer "In2.Cu")
		(net "NFP_PCIE0_PER6_P")
	)
	(segment
		(start 11.020806 6.994525)
		(end 10.649331 7.366)
		(width 0.110185)
		(layer "In2.Cu")
		(net "NFP_PCIE0_PER6_P")
	)
	(segment
		(start 10.649331 7.366)
		(end 10.213213 7.366)
		(width 0.110185)
		(layer "In2.Cu")
		(net "NFP_PCIE0_PER6_P")
	)
	(segment
		(start 8.821979 2.029028)
		(end 7.261428 2.029028)
		(width 0.110185)
		(layer "In2.Cu")
		(net "NFP_PCIE0_PER6_P")
	)
	(segment
		(start 9.459341 5.059934)
		(end 7.427341 5.059934)
		(width 0.110185)
		(layer "In2.Cu")
		(net "NFP_PCIE0_PER6_P")
	)
	(segment
		(start 13.681481 -0.655066)
		(end 13.805052 -0.531495)
		(width 0.110185)
		(layer "In2.Cu")
		(net "NFP_PCIE0_PER6_P")
	)
	(segment
		(start 6.223 2.794)
		(end 6.223 3.166643)
		(width 0.110185)
		(layer "In2.Cu")
		(net "NFP_PCIE0_PER6_P")
	)
	(segment
		(start 14.739366 7.231659)
		(end 14.739366 6.611341)
		(width 0.110185)
		(layer "In2.Cu")
		(net "NFP_PCIE0_PER6_P")
	)
	(segment
		(start 7.027164 1.794764)
		(end 7.027164 0.924357)
		(width 0.110185)
		(layer "In2.Cu")
		(net "NFP_PCIE0_PER6_P")
	)
	(segment
		(start 8.05467 0.690093)
		(end 8.310093 0.43467)
		(width 0.110185)
		(layer "In2.Cu")
		(net "NFP_PCIE0_PER6_P")
	)
	(segment
		(start 8.932164 2.139213)
		(end 8.821979 2.029028)
		(width 0.110185)
		(layer "In2.Cu")
		(net "NFP_PCIE0_PER6_P")
	)
	(segment
		(start 7.027164 4.466107)
		(end 6.906768 4.345711)
		(width 0.110185)
		(layer "In2.Cu")
		(net "NFP_PCIE0_PER6_P")
	)
	(segment
		(start 6.731 4.345711)
		(end 6.477 4.599711)
		(width 0.110185)
		(layer "In2.Cu")
		(net "NFP_PCIE0_PER6_P")
	)
	(segment
		(start 8.310093 0.43467)
		(end 8.310093 0.153314)
		(width 0.110185)
		(layer "In2.Cu")
		(net "NFP_PCIE0_PER6_P")
	)
	(segment
		(start 13.900506 7.348982)
		(end 13.939622 7.388098)
		(width 0.110185)
		(layer "In2.Cu")
		(net "NFP_PCIE0_PER6_P")
	)
	(segment
		(start 7.261428 2.029028)
		(end 7.027164 1.794764)
		(width 0.110185)
		(layer "In2.Cu")
		(net "NFP_PCIE0_PER6_P")
	)
	(segment
		(start 7.261428 0.690093)
		(end 8.05467 0.690093)
		(width 0.110185)
		(layer "In2.Cu")
		(net "NFP_PCIE0_PER6_P")
	)
	(segment
		(start 11.368659 5.059934)
		(end 11.020806 5.407787)
		(width 0.110185)
		(layer "In2.Cu")
		(net "NFP_PCIE0_PER6_P")
	)
	(segment
		(start 7.027164 4.659757)
		(end 7.027164 4.466107)
		(width 0.110185)
		(layer "In2.Cu")
		(net "NFP_PCIE0_PER6_P")
	)
	(segment
		(start 6.477 3.420643)
		(end 6.906768 3.420643)
		(width 0.110185)
		(layer "In2.Cu")
		(net "NFP_PCIE0_PER6_P")
	)
	(segment
		(start 5.461 2.54)
		(end 5.969 2.54)
		(width 0.110185)
		(layer "In2.Cu")
		(net "NFP_PCIE0_PER6_P")
	)
	(segment
		(start 12.199366 6.105525)
		(end 12.199366 5.259959)
		(width 0.110185)
		(layer "In2.Cu")
		(net "NFP_PCIE0_PER6_P")
	)
	(segment
		(start 6.906768 3.420643)
		(end 7.027164 3.300247)
		(width 0.110185)
		(layer "In2.Cu")
		(net "NFP_PCIE0_PER6_P")
	)
	(segment
		(start 8.315198 0.148209)
		(end 8.315198 0.032233)
		(width 0.110185)
		(layer "In2.Cu")
		(net "NFP_PCIE0_PER6_P")
	)
	(segment
		(start 5.461 7.62)
		(end 5.207 7.366)
		(width 0.110185)
		(layer "In2.Cu")
		(net "NFP_PCIE0_PER6_P")
	)
	(segment
		(start 7.427341 5.059934)
		(end 7.027164 4.659757)
		(width 0.110185)
		(layer "In2.Cu")
		(net "NFP_PCIE0_PER6_P")
	)
	(segment
		(start 11.020806 5.407787)
		(end 11.020806 6.994525)
		(width 0.110185)
		(layer "In2.Cu")
		(net "NFP_PCIE0_PER6_P")
	)
	(segment
		(start 8.310093 0.153314)
		(end 8.315198 0.148209)
		(width 0.110185)
		(layer "In2.Cu")
		(net "NFP_PCIE0_PER6_P")
	)
	(segment
		(start 5.969 2.54)
		(end 6.223 2.794)
		(width 0.110185)
		(layer "In2.Cu")
		(net "NFP_PCIE0_PER6_P")
	)
	(segment
		(start 7.027164 2.754478)
		(end 7.261428 2.520213)
		(width 0.110185)
		(layer "In2.Cu")
		(net "NFP_PCIE0_PER6_P")
	)
	(segment
		(start 5.207 7.366)
		(end 5.207 2.794)
		(width 0.110185)
		(layer "In2.Cu")
		(net "NFP_PCIE0_PER6_P")
	)
	(segment
		(start 8.315198 0.032233)
		(end 9.002497 -0.655066)
		(width 0.110185)
		(layer "In2.Cu")
		(net "NFP_PCIE0_PER6_P")
	)
	(segment
		(start 13.805052 -0.531495)
		(end 46.205902 -0.531495)
		(width 0.110185)
		(layer "In2.Cu")
		(net "NFP_PCIE0_PER6_P")
	)
	(segment
		(start 51.078968 -0.401625)
		(end 51.078968 -0.047168)
		(width 0.110185)
		(layer "In2.Cu")
		(net "NFP_PCIE0_PER6_P")
	)
	(segment
		(start 5.207 2.794)
		(end 5.461 2.54)
		(width 0.110185)
		(layer "In2.Cu")
		(net "NFP_PCIE0_PER6_P")
	)
	(segment
		(start 6.223 7.62)
		(end 5.461 7.62)
		(width 0.110185)
		(layer "In2.Cu")
		(net "NFP_PCIE0_PER6_P")
	)
	(segment
		(start 12.8524 7.228586)
		(end 12.972796 7.348982)
		(width 0.110185)
		(layer "In2.Cu")
		(net "NFP_PCIE0_PER6_P")
	)
	(segment
		(start 9.968738 6.343396)
		(end 9.659366 6.034024)
		(width 0.110185)
		(layer "In2.Cu")
		(net "NFP_PCIE0_PER6_P")
	)
	(segment
		(start 8.932164 2.410028)
		(end 8.932164 2.139213)
		(width 0.110185)
		(layer "In2.Cu")
		(net "NFP_PCIE0_PER6_P")
	)
	(segment
		(start 12.972796 7.348982)
		(end 13.900506 7.348982)
		(width 0.110185)
		(layer "In2.Cu")
		(net "NFP_PCIE0_PER6_P")
	)
	(segment
		(start 51.078968 -0.047168)
		(end 51.469036 0.3429)
		(width 0.110185)
		(layer "In2.Cu")
		(net "NFP_PCIE0_PER6_P")
	)
	(via
		(at 12.8524 8.2169)
		(size 0.762)
		(drill 0.2667)
		(layers "F.Cu" "B.Cu")
		(net "NFP_PCIE0_PER6_N")
	)
	(via
		(at 50.477039 0.3429)
		(size 0.508)
		(drill 0.25654)
		(layers "F.Cu" "B.Cu")
		(net "NFP_PCIE0_PER6_N")
	)
	(segment
		(start 13.4874 8.8519)
		(end 12.8524 8.2169)
		(width 0.138633)
		(layer "B.Cu")
		(net "NFP_PCIE0_PER6_N")
	)
	(segment
		(start 12.531598 6.138164)
		(end 12.411202 6.017768)
		(width 0.110185)
		(layer "In2.Cu")
		(net "NFP_PCIE0_PER6_N")
	)
	(segment
		(start 7.239 4.37835)
		(end 6.994525 4.133875)
		(width 0.110185)
		(layer "In2.Cu")
		(net "NFP_PCIE0_PER6_N")
	)
	(segment
		(start 13.717295 -0.319659)
		(end 46.293659 -0.319659)
		(width 0.110185)
		(layer "In2.Cu")
		(net "NFP_PCIE0_PER6_N")
	)
	(segment
		(start 8.909736 1.817192)
		(end 7.349185 1.817192)
		(width 0.110185)
		(layer "In2.Cu")
		(net "NFP_PCIE0_PER6_N")
	)
	(segment
		(start 5.548757 7.408164)
		(end 5.418836 7.278243)
		(width 0.110185)
		(layer "In2.Cu")
		(net "NFP_PCIE0_PER6_N")
	)
	(segment
		(start 10.180574 6.255639)
		(end 9.871202 5.946267)
		(width 0.110185)
		(layer "In2.Cu")
		(net "NFP_PCIE0_PER6_N")
	)
	(segment
		(start 8.527034 0.235966)
		(end 8.527034 0.11999)
		(width 0.110185)
		(layer "In2.Cu")
		(net "NFP_PCIE0_PER6_N")
	)
	(segment
		(start 6.643243 4.133875)
		(end 6.265164 4.511954)
		(width 0.110185)
		(layer "In2.Cu")
		(net "NFP_PCIE0_PER6_N")
	)
	(segment
		(start 10.80897 6.906768)
		(end 10.561574 7.154164)
		(width 0.110185)
		(layer "In2.Cu")
		(net "NFP_PCIE0_PER6_N")
	)
	(segment
		(start 7.349185 1.817192)
		(end 7.239 1.707007)
		(width 0.110185)
		(layer "In2.Cu")
		(net "NFP_PCIE0_PER6_N")
	)
	(segment
		(start 7.239 4.572)
		(end 7.239 4.37835)
		(width 0.110185)
		(layer "In2.Cu")
		(net "NFP_PCIE0_PER6_N")
	)
	(segment
		(start 6.994525 3.632479)
		(end 7.239 3.388004)
		(width 0.110185)
		(layer "In2.Cu")
		(net "NFP_PCIE0_PER6_N")
	)
	(segment
		(start 14.732 7.599934)
		(end 14.951202 7.380732)
		(width 0.110185)
		(layer "In2.Cu")
		(net "NFP_PCIE0_PER6_N")
	)
	(segment
		(start 10.561574 7.154164)
		(end 10.30097 7.154164)
		(width 0.110185)
		(layer "In2.Cu")
		(net "NFP_PCIE0_PER6_N")
	)
	(segment
		(start 50.429922 -0.751078)
		(end 50.867132 -0.313868)
		(width 0.110185)
		(layer "In2.Cu")
		(net "NFP_PCIE0_PER6_N")
	)
	(segment
		(start 9.871202 5.172202)
		(end 9.547098 4.848098)
		(width 0.110185)
		(layer "In2.Cu")
		(net "NFP_PCIE0_PER6_N")
	)
	(segment
		(start 7.349185 2.732049)
		(end 8.909736 2.732049)
		(width 0.110185)
		(layer "In2.Cu")
		(net "NFP_PCIE0_PER6_N")
	)
	(segment
		(start 6.265164 7.278243)
		(end 6.135243 7.408164)
		(width 0.110185)
		(layer "In2.Cu")
		(net "NFP_PCIE0_PER6_N")
	)
	(segment
		(start 7.515098 4.848098)
		(end 7.239 4.572)
		(width 0.110185)
		(layer "In2.Cu")
		(net "NFP_PCIE0_PER6_N")
	)
	(segment
		(start 10.80897 5.32003)
		(end 10.80897 6.906768)
		(width 0.110185)
		(layer "In2.Cu")
		(net "NFP_PCIE0_PER6_N")
	)
	(segment
		(start 12.411202 5.172202)
		(end 12.087098 4.848098)
		(width 0.110185)
		(layer "In2.Cu")
		(net "NFP_PCIE0_PER6_N")
	)
	(segment
		(start 13.851865 7.599934)
		(end 14.732 7.599934)
		(width 0.110185)
		(layer "In2.Cu")
		(net "NFP_PCIE0_PER6_N")
	)
	(segment
		(start 6.011164 2.881757)
		(end 6.011164 3.2544)
		(width 0.110185)
		(layer "In2.Cu")
		(net "NFP_PCIE0_PER6_N")
	)
	(segment
		(start 12.8524 8.2169)
		(end 12.8524 7.681214)
		(width 0.110185)
		(layer "In2.Cu")
		(net "NFP_PCIE0_PER6_N")
	)
	(segment
		(start 10.180574 7.033768)
		(end 10.180574 6.255639)
		(width 0.110185)
		(layer "In2.Cu")
		(net "NFP_PCIE0_PER6_N")
	)
	(segment
		(start 7.349185 0.901929)
		(end 8.142427 0.901929)
		(width 0.110185)
		(layer "In2.Cu")
		(net "NFP_PCIE0_PER6_N")
	)
	(segment
		(start 5.548757 2.751836)
		(end 5.881243 2.751836)
		(width 0.110185)
		(layer "In2.Cu")
		(net "NFP_PCIE0_PER6_N")
	)
	(segment
		(start 50.867132 -0.313868)
		(end 50.867132 -0.047193)
		(width 0.110185)
		(layer "In2.Cu")
		(net "NFP_PCIE0_PER6_N")
	)
	(segment
		(start 12.972796 7.560818)
		(end 13.812749 7.560818)
		(width 0.110185)
		(layer "In2.Cu")
		(net "NFP_PCIE0_PER6_N")
	)
	(segment
		(start 10.30097 7.154164)
		(end 10.180574 7.033768)
		(width 0.110185)
		(layer "In2.Cu")
		(net "NFP_PCIE0_PER6_N")
	)
	(segment
		(start 46.725078 -0.751078)
		(end 50.429922 -0.751078)
		(width 0.110185)
		(layer "In2.Cu")
		(net "NFP_PCIE0_PER6_N")
	)
	(segment
		(start 7.239 3.388004)
		(end 7.239 2.842235)
		(width 0.110185)
		(layer "In2.Cu")
		(net "NFP_PCIE0_PER6_N")
	)
	(segment
		(start 12.8524 7.681214)
		(end 12.972796 7.560818)
		(width 0.110185)
		(layer "In2.Cu")
		(net "NFP_PCIE0_PER6_N")
	)
	(segment
		(start 9.144 2.051456)
		(end 8.909736 1.817192)
		(width 0.110185)
		(layer "In2.Cu")
		(net "NFP_PCIE0_PER6_N")
	)
	(segment
		(start 8.142427 0.901929)
		(end 8.521929 0.522427)
		(width 0.110185)
		(layer "In2.Cu")
		(net "NFP_PCIE0_PER6_N")
	)
	(segment
		(start 14.951202 6.523584)
		(end 14.565782 6.138164)
		(width 0.110185)
		(layer "In2.Cu")
		(net "NFP_PCIE0_PER6_N")
	)
	(segment
		(start 7.239 1.707007)
		(end 7.239 1.012114)
		(width 0.110185)
		(layer "In2.Cu")
		(net "NFP_PCIE0_PER6_N")
	)
	(segment
		(start 13.593724 -0.44323)
		(end 13.717295 -0.319659)
		(width 0.110185)
		(layer "In2.Cu")
		(net "NFP_PCIE0_PER6_N")
	)
	(segment
		(start 46.293659 -0.319659)
		(end 46.725078 -0.751078)
		(width 0.110185)
		(layer "In2.Cu")
		(net "NFP_PCIE0_PER6_N")
	)
	(segment
		(start 5.418836 2.881757)
		(end 5.548757 2.751836)
		(width 0.110185)
		(layer "In2.Cu")
		(net "NFP_PCIE0_PER6_N")
	)
	(segment
		(start 5.881243 2.751836)
		(end 6.011164 2.881757)
		(width 0.110185)
		(layer "In2.Cu")
		(net "NFP_PCIE0_PER6_N")
	)
	(segment
		(start 9.547098 4.848098)
		(end 7.515098 4.848098)
		(width 0.110185)
		(layer "In2.Cu")
		(net "NFP_PCIE0_PER6_N")
	)
	(segment
		(start 13.812749 7.560818)
		(end 13.851865 7.599934)
		(width 0.110185)
		(layer "In2.Cu")
		(net "NFP_PCIE0_PER6_N")
	)
	(segment
		(start 6.135243 7.408164)
		(end 5.548757 7.408164)
		(width 0.110185)
		(layer "In2.Cu")
		(net "NFP_PCIE0_PER6_N")
	)
	(segment
		(start 9.090254 -0.44323)
		(end 13.593724 -0.44323)
		(width 0.110185)
		(layer "In2.Cu")
		(net "NFP_PCIE0_PER6_N")
	)
	(segment
		(start 50.867132 -0.047193)
		(end 50.477039 0.3429)
		(width 0.110185)
		(layer "In2.Cu")
		(net "NFP_PCIE0_PER6_N")
	)
	(segment
		(start 7.239 2.842235)
		(end 7.349185 2.732049)
		(width 0.110185)
		(layer "In2.Cu")
		(net "NFP_PCIE0_PER6_N")
	)
	(segment
		(start 9.871202 5.946267)
		(end 9.871202 5.172202)
		(width 0.110185)
		(layer "In2.Cu")
		(net "NFP_PCIE0_PER6_N")
	)
	(segment
		(start 5.418836 7.278243)
		(end 5.418836 2.881757)
		(width 0.110185)
		(layer "In2.Cu")
		(net "NFP_PCIE0_PER6_N")
	)
	(segment
		(start 7.239 1.012114)
		(end 7.349185 0.901929)
		(width 0.110185)
		(layer "In2.Cu")
		(net "NFP_PCIE0_PER6_N")
	)
	(segment
		(start 14.565782 6.138164)
		(end 12.531598 6.138164)
		(width 0.110185)
		(layer "In2.Cu")
		(net "NFP_PCIE0_PER6_N")
	)
	(segment
		(start 6.265164 4.511954)
		(end 6.265164 7.278243)
		(width 0.110185)
		(layer "In2.Cu")
		(net "NFP_PCIE0_PER6_N")
	)
	(segment
		(start 6.389243 3.632479)
		(end 6.994525 3.632479)
		(width 0.110185)
		(layer "In2.Cu")
		(net "NFP_PCIE0_PER6_N")
	)
	(segment
		(start 12.411202 6.017768)
		(end 12.411202 5.172202)
		(width 0.110185)
		(layer "In2.Cu")
		(net "NFP_PCIE0_PER6_N")
	)
	(segment
		(start 14.951202 7.380732)
		(end 14.951202 6.523584)
		(width 0.110185)
		(layer "In2.Cu")
		(net "NFP_PCIE0_PER6_N")
	)
	(segment
		(start 8.909736 2.732049)
		(end 9.144 2.497785)
		(width 0.110185)
		(layer "In2.Cu")
		(net "NFP_PCIE0_PER6_N")
	)
	(segment
		(start 8.521929 0.522427)
		(end 8.521929 0.241071)
		(width 0.110185)
		(layer "In2.Cu")
		(net "NFP_PCIE0_PER6_N")
	)
	(segment
		(start 8.527034 0.11999)
		(end 9.090254 -0.44323)
		(width 0.110185)
		(layer "In2.Cu")
		(net "NFP_PCIE0_PER6_N")
	)
	(segment
		(start 11.280902 4.848098)
		(end 10.80897 5.32003)
		(width 0.110185)
		(layer "In2.Cu")
		(net "NFP_PCIE0_PER6_N")
	)
	(segment
		(start 8.521929 0.241071)
		(end 8.527034 0.235966)
		(width 0.110185)
		(layer "In2.Cu")
		(net "NFP_PCIE0_PER6_N")
	)
	(segment
		(start 9.144 2.497785)
		(end 9.144 2.051456)
		(width 0.110185)
		(layer "In2.Cu")
		(net "NFP_PCIE0_PER6_N")
	)
	(segment
		(start 6.994525 4.133875)
		(end 6.643243 4.133875)
		(width 0.110185)
		(layer "In2.Cu")
		(net "NFP_PCIE0_PER6_N")
	)
	(segment
		(start 12.087098 4.848098)
		(end 11.280902 4.848098)
		(width 0.110185)
		(layer "In2.Cu")
		(net "NFP_PCIE0_PER6_N")
	)
	(segment
		(start 6.011164 3.2544)
		(end 6.389243 3.632479)
		(width 0.110185)
		(layer "In2.Cu")
		(net "NFP_PCIE0_PER6_N")
	)
	(via
		(at 14.1224 9.4869)
		(size 0.762)
		(drill 0.254)
		(layers "F.Cu" "B.Cu")
		(net "NFP_PCIE0_PER5_P")
	)
	(via
		(at 53.467 0.3429)
		(size 0.508)
		(drill 0.25654)
		(layers "F.Cu" "B.Cu")
		(net "NFP_PCIE0_PER5_P")
	)
	(segment
		(start 14.7574 10.1219)
		(end 14.1224 9.4869)
		(width 0.138633)
		(layer "B.Cu")
		(net "NFP_PCIE0_PER5_P")
	)
	(segment
		(start 8.876767 7.704836)
		(end 9.483598 7.704836)
		(width 0.110185)
		(layer "In2.Cu")
		(net "NFP_PCIE0_PER5_P")
	)
	(segment
		(start 10.753598 8.974836)
		(end 11.203915 8.974836)
		(width 0.110185)
		(layer "In2.Cu")
		(net "NFP_PCIE0_PER5_P")
	)
	(segment
		(start 11.548364 9.431807)
		(end 11.994693 9.431807)
		(width 0.110185)
		(layer "In2.Cu")
		(net "NFP_PCIE0_PER5_P")
	)
	(segment
		(start 5.549621 -0.30447)
		(end 5.549621 -0.134239)
		(width 0.110185)
		(layer "In2.Cu")
		(net "NFP_PCIE0_PER5_P")
	)
	(segment
		(start 13.976934 -1.368298)
		(end 5.37939 -1.368298)
		(width 0.110185)
		(layer "In2.Cu")
		(net "NFP_PCIE0_PER5_P")
	)
	(segment
		(start 11.3141 9.085021)
		(end 11.3141 9.197543)
		(width 0.110185)
		(layer "In2.Cu")
		(net "NFP_PCIE0_PER5_P")
	)
	(segment
		(start 14.1224 9.768586)
		(end 14.1224 9.4869)
		(width 0.110185)
		(layer "In2.Cu")
		(net "NFP_PCIE0_PER5_P")
	)
	(segment
		(start 7.239 8.001)
		(end 7.239 6.524092)
		(width 0.110185)
		(layer "In2.Cu")
		(net "NFP_PCIE0_PER5_P")
	)
	(segment
		(start 45.776134 -1.244727)
		(end 14.100505 -1.244727)
		(width 0.110185)
		(layer "In2.Cu")
		(net "NFP_PCIE0_PER5_P")
	)
	(segment
		(start 7.433158 6.329934)
		(end 8.189341 6.329934)
		(width 0.110185)
		(layer "In2.Cu")
		(net "NFP_PCIE0_PER5_P")
	)
	(segment
		(start 14.517243 8.974836)
		(end 14.739366 9.196959)
		(width 0.110185)
		(layer "In2.Cu")
		(net "NFP_PCIE0_PER5_P")
	)
	(segment
		(start 14.739366 9.726041)
		(end 14.576425 9.888982)
		(width 0.110185)
		(layer "In2.Cu")
		(net "NFP_PCIE0_PER5_P")
	)
	(segment
		(start 14.739366 9.196959)
		(end 14.739366 9.726041)
		(width 0.110185)
		(layer "In2.Cu")
		(net "NFP_PCIE0_PER5_P")
	)
	(segment
		(start 12.228957 9.085021)
		(end 12.339142 8.974836)
		(width 0.110185)
		(layer "In2.Cu")
		(net "NFP_PCIE0_PER5_P")
	)
	(segment
		(start 5.376164 1.519174)
		(end 5.255768 1.63957)
		(width 0.110185)
		(layer "In2.Cu")
		(net "NFP_PCIE0_PER5_P")
	)
	(segment
		(start 4.051148 1.138174)
		(end 5.255768 1.138174)
		(width 0.110185)
		(layer "In2.Cu")
		(net "NFP_PCIE0_PER5_P")
	)
	(segment
		(start 8.389366 6.529959)
		(end 8.389366 7.217435)
		(width 0.110185)
		(layer "In2.Cu")
		(net "NFP_PCIE0_PER5_P")
	)
	(segment
		(start 11.994693 9.431807)
		(end 12.228957 9.197543)
		(width 0.110185)
		(layer "In2.Cu")
		(net "NFP_PCIE0_PER5_P")
	)
	(segment
		(start 14.576425 9.888982)
		(end 14.242796 9.888982)
		(width 0.110185)
		(layer "In2.Cu")
		(net "NFP_PCIE0_PER5_P")
	)
	(segment
		(start 52.210132 -1.549146)
		(end 46.080553 -1.549146)
		(width 0.110185)
		(layer "In2.Cu")
		(net "NFP_PCIE0_PER5_P")
	)
	(segment
		(start 5.376164 1.25857)
		(end 5.376164 1.519174)
		(width 0.110185)
		(layer "In2.Cu")
		(net "NFP_PCIE0_PER5_P")
	)
	(segment
		(start 5.255768 1.138174)
		(end 5.376164 1.25857)
		(width 0.110185)
		(layer "In2.Cu")
		(net "NFP_PCIE0_PER5_P")
	)
	(segment
		(start 4.750892 -0.394081)
		(end 4.405173 -0.394081)
		(width 0.110185)
		(layer "In2.Cu")
		(net "NFP_PCIE0_PER5_P")
	)
	(segment
		(start 3.806673 0.893699)
		(end 4.051148 1.138174)
		(width 0.110185)
		(layer "In2.Cu")
		(net "NFP_PCIE0_PER5_P")
	)
	(segment
		(start 7.239 6.524092)
		(end 7.433158 6.329934)
		(width 0.110185)
		(layer "In2.Cu")
		(net "NFP_PCIE0_PER5_P")
	)
	(segment
		(start 4.051148 1.63957)
		(end 3.806673 1.884045)
		(width 0.110185)
		(layer "In2.Cu")
		(net "NFP_PCIE0_PER5_P")
	)
	(segment
		(start 5.105425 -1.094334)
		(end 5.105425 -0.74864)
		(width 0.110185)
		(layer "In2.Cu")
		(net "NFP_PCIE0_PER5_P")
	)
	(segment
		(start 14.100505 -1.244727)
		(end 13.976934 -1.368298)
		(width 0.110185)
		(layer "In2.Cu")
		(net "NFP_PCIE0_PER5_P")
	)
	(segment
		(start 4.378198 4.677766)
		(end 4.378198 8.061198)
		(width 0.110185)
		(layer "In2.Cu")
		(net "NFP_PCIE0_PER5_P")
	)
	(segment
		(start 12.228957 9.197543)
		(end 12.228957 9.085021)
		(width 0.110185)
		(layer "In2.Cu")
		(net "NFP_PCIE0_PER5_P")
	)
	(segment
		(start 3.806673 4.10624)
		(end 4.378198 4.677766)
		(width 0.110185)
		(layer "In2.Cu")
		(net "NFP_PCIE0_PER5_P")
	)
	(segment
		(start 3.806673 1.884045)
		(end 3.806673 4.10624)
		(width 0.110185)
		(layer "In2.Cu")
		(net "NFP_PCIE0_PER5_P")
	)
	(segment
		(start 5.365293 0.050089)
		(end 5.195062 0.050089)
		(width 0.110185)
		(layer "In2.Cu")
		(net "NFP_PCIE0_PER5_P")
	)
	(segment
		(start 14.242796 9.888982)
		(end 14.1224 9.768586)
		(width 0.110185)
		(layer "In2.Cu")
		(net "NFP_PCIE0_PER5_P")
	)
	(segment
		(start 5.195062 0.050089)
		(end 4.750892 -0.394081)
		(width 0.110185)
		(layer "In2.Cu")
		(net "NFP_PCIE0_PER5_P")
	)
	(segment
		(start 6.731 8.509)
		(end 7.239 8.001)
		(width 0.110185)
		(layer "In2.Cu")
		(net "NFP_PCIE0_PER5_P")
	)
	(segment
		(start 9.483598 7.704836)
		(end 10.753598 8.974836)
		(width 0.110185)
		(layer "In2.Cu")
		(net "NFP_PCIE0_PER5_P")
	)
	(segment
		(start 5.255768 1.63957)
		(end 4.051148 1.63957)
		(width 0.110185)
		(layer "In2.Cu")
		(net "NFP_PCIE0_PER5_P")
	)
	(segment
		(start 4.405173 -0.394081)
		(end 3.806673 0.204419)
		(width 0.110185)
		(layer "In2.Cu")
		(net "NFP_PCIE0_PER5_P")
	)
	(segment
		(start 53.128418 -0.63086)
		(end 52.210132 -1.549146)
		(width 0.110185)
		(layer "In2.Cu")
		(net "NFP_PCIE0_PER5_P")
	)
	(segment
		(start 8.389366 7.217435)
		(end 8.876767 7.704836)
		(width 0.110185)
		(layer "In2.Cu")
		(net "NFP_PCIE0_PER5_P")
	)
	(segment
		(start 53.128418 0.004318)
		(end 53.128418 -0.63086)
		(width 0.110185)
		(layer "In2.Cu")
		(net "NFP_PCIE0_PER5_P")
	)
	(segment
		(start 53.467 0.3429)
		(end 53.128418 0.004318)
		(width 0.110185)
		(layer "In2.Cu")
		(net "NFP_PCIE0_PER5_P")
	)
	(segment
		(start 5.549621 -0.134239)
		(end 5.365293 0.050089)
		(width 0.110185)
		(layer "In2.Cu")
		(net "NFP_PCIE0_PER5_P")
	)
	(segment
		(start 8.189341 6.329934)
		(end 8.389366 6.529959)
		(width 0.110185)
		(layer "In2.Cu")
		(net "NFP_PCIE0_PER5_P")
	)
	(segment
		(start 11.203915 8.974836)
		(end 11.3141 9.085021)
		(width 0.110185)
		(layer "In2.Cu")
		(net "NFP_PCIE0_PER5_P")
	)
	(segment
		(start 11.3141 9.197543)
		(end 11.548364 9.431807)
		(width 0.110185)
		(layer "In2.Cu")
		(net "NFP_PCIE0_PER5_P")
	)
	(segment
		(start 46.080553 -1.549146)
		(end 45.776134 -1.244727)
		(width 0.110185)
		(layer "In2.Cu")
		(net "NFP_PCIE0_PER5_P")
	)
	(segment
		(start 5.105425 -0.74864)
		(end 5.549621 -0.30447)
		(width 0.110185)
		(layer "In2.Cu")
		(net "NFP_PCIE0_PER5_P")
	)
	(segment
		(start 4.826 8.509)
		(end 6.731 8.509)
		(width 0.110185)
		(layer "In2.Cu")
		(net "NFP_PCIE0_PER5_P")
	)
	(segment
		(start 4.378198 8.061198)
		(end 4.826 8.509)
		(width 0.110185)
		(layer "In2.Cu")
		(net "NFP_PCIE0_PER5_P")
	)
	(segment
		(start 5.37939 -1.368298)
		(end 5.105425 -1.094334)
		(width 0.110185)
		(layer "In2.Cu")
		(net "NFP_PCIE0_PER5_P")
	)
	(segment
		(start 12.339142 8.974836)
		(end 14.517243 8.974836)
		(width 0.110185)
		(layer "In2.Cu")
		(net "NFP_PCIE0_PER5_P")
	)
	(segment
		(start 3.806673 0.204419)
		(end 3.806673 0.893699)
		(width 0.110185)
		(layer "In2.Cu")
		(net "NFP_PCIE0_PER5_P")
	)
	(via
		(at 14.1224 10.7569)
		(size 0.762)
		(drill 0.2667)
		(layers "F.Cu" "B.Cu")
		(net "NFP_PCIE0_PER5_N")
	)
	(via
		(at 52.48656 0.3429)
		(size 0.508)
		(drill 0.25654)
		(layers "F.Cu" "B.Cu")
		(net "NFP_PCIE0_PER5_N")
	)
	(segment
		(start 14.7574 11.3919)
		(end 14.1224 10.7569)
		(width 0.138633)
		(layer "B.Cu")
		(net "NFP_PCIE0_PER5_N")
	)
	(segment
		(start 6.643243 8.297164)
		(end 7.027164 7.913243)
		(width 0.110185)
		(layer "In2.Cu")
		(net "NFP_PCIE0_PER5_N")
	)
	(segment
		(start 14.664182 10.100818)
		(end 14.242796 10.100818)
		(width 0.110185)
		(layer "In2.Cu")
		(net "NFP_PCIE0_PER5_N")
	)
	(segment
		(start 4.49293 -0.182245)
		(end 4.018509 0.292176)
		(width 0.110185)
		(layer "In2.Cu")
		(net "NFP_PCIE0_PER5_N")
	)
	(segment
		(start 13.889177 -1.156462)
		(end 5.467147 -1.156462)
		(width 0.110185)
		(layer "In2.Cu")
		(net "NFP_PCIE0_PER5_N")
	)
	(segment
		(start 5.588 1.606931)
		(end 5.343525 1.851406)
		(width 0.110185)
		(layer "In2.Cu")
		(net "NFP_PCIE0_PER5_N")
	)
	(segment
		(start 52.48656 0.3429)
		(end 52.916582 0.004318)
		(width 0.110185)
		(layer "In2.Cu")
		(net "NFP_PCIE0_PER5_N")
	)
	(segment
		(start 11.906936 9.219971)
		(end 12.017121 9.109786)
		(width 0.110185)
		(layer "In2.Cu")
		(net "NFP_PCIE0_PER5_N")
	)
	(segment
		(start 11.636121 9.219971)
		(end 11.906936 9.219971)
		(width 0.110185)
		(layer "In2.Cu")
		(net "NFP_PCIE0_PER5_N")
	)
	(segment
		(start 5.343525 1.851406)
		(end 4.138905 1.851406)
		(width 0.110185)
		(layer "In2.Cu")
		(net "NFP_PCIE0_PER5_N")
	)
	(segment
		(start 14.1224 10.221214)
		(end 14.1224 10.7569)
		(width 0.110185)
		(layer "In2.Cu")
		(net "NFP_PCIE0_PER5_N")
	)
	(segment
		(start 4.663135 -0.182245)
		(end 4.49293 -0.182245)
		(width 0.110185)
		(layer "In2.Cu")
		(net "NFP_PCIE0_PER5_N")
	)
	(segment
		(start 52.916582 0.004318)
		(end 52.916582 -0.543103)
		(width 0.110185)
		(layer "In2.Cu")
		(net "NFP_PCIE0_PER5_N")
	)
	(segment
		(start 5.761457 -0.046482)
		(end 5.45305 0.261925)
		(width 0.110185)
		(layer "In2.Cu")
		(net "NFP_PCIE0_PER5_N")
	)
	(segment
		(start 11.291672 8.763)
		(end 11.525936 8.997264)
		(width 0.110185)
		(layer "In2.Cu")
		(net "NFP_PCIE0_PER5_N")
	)
	(segment
		(start 12.017121 8.997264)
		(end 12.251385 8.763)
		(width 0.110185)
		(layer "In2.Cu")
		(net "NFP_PCIE0_PER5_N")
	)
	(segment
		(start 4.138905 0.926338)
		(end 5.343525 0.926338)
		(width 0.110185)
		(layer "In2.Cu")
		(net "NFP_PCIE0_PER5_N")
	)
	(segment
		(start 4.018509 1.971802)
		(end 4.018509 4.018483)
		(width 0.110185)
		(layer "In2.Cu")
		(net "NFP_PCIE0_PER5_N")
	)
	(segment
		(start 14.605 8.763)
		(end 14.951202 9.109202)
		(width 0.110185)
		(layer "In2.Cu")
		(net "NFP_PCIE0_PER5_N")
	)
	(segment
		(start 8.277098 6.118098)
		(end 8.601202 6.442202)
		(width 0.110185)
		(layer "In2.Cu")
		(net "NFP_PCIE0_PER5_N")
	)
	(segment
		(start 14.951202 9.813798)
		(end 14.664182 10.100818)
		(width 0.110185)
		(layer "In2.Cu")
		(net "NFP_PCIE0_PER5_N")
	)
	(segment
		(start 52.122375 -1.33731)
		(end 46.16831 -1.33731)
		(width 0.110185)
		(layer "In2.Cu")
		(net "NFP_PCIE0_PER5_N")
	)
	(segment
		(start 5.761457 -0.392227)
		(end 5.761457 -0.046482)
		(width 0.110185)
		(layer "In2.Cu")
		(net "NFP_PCIE0_PER5_N")
	)
	(segment
		(start 4.590034 4.590009)
		(end 4.590034 7.973441)
		(width 0.110185)
		(layer "In2.Cu")
		(net "NFP_PCIE0_PER5_N")
	)
	(segment
		(start 5.588 1.170813)
		(end 5.588 1.606931)
		(width 0.110185)
		(layer "In2.Cu")
		(net "NFP_PCIE0_PER5_N")
	)
	(segment
		(start 10.841355 8.763)
		(end 11.291672 8.763)
		(width 0.110185)
		(layer "In2.Cu")
		(net "NFP_PCIE0_PER5_N")
	)
	(segment
		(start 4.018509 0.805942)
		(end 4.138905 0.926338)
		(width 0.110185)
		(layer "In2.Cu")
		(net "NFP_PCIE0_PER5_N")
	)
	(segment
		(start 7.027164 6.436335)
		(end 7.345401 6.118098)
		(width 0.110185)
		(layer "In2.Cu")
		(net "NFP_PCIE0_PER5_N")
	)
	(segment
		(start 11.525936 8.997264)
		(end 11.525936 9.109786)
		(width 0.110185)
		(layer "In2.Cu")
		(net "NFP_PCIE0_PER5_N")
	)
	(segment
		(start 9.571355 7.493)
		(end 10.841355 8.763)
		(width 0.110185)
		(layer "In2.Cu")
		(net "NFP_PCIE0_PER5_N")
	)
	(segment
		(start 4.590034 7.973441)
		(end 4.913757 8.297164)
		(width 0.110185)
		(layer "In2.Cu")
		(net "NFP_PCIE0_PER5_N")
	)
	(segment
		(start 4.913757 8.297164)
		(end 6.643243 8.297164)
		(width 0.110185)
		(layer "In2.Cu")
		(net "NFP_PCIE0_PER5_N")
	)
	(segment
		(start 5.317261 -0.836397)
		(end 5.761457 -0.392227)
		(width 0.110185)
		(layer "In2.Cu")
		(net "NFP_PCIE0_PER5_N")
	)
	(segment
		(start 5.45305 0.261925)
		(end 5.107305 0.261925)
		(width 0.110185)
		(layer "In2.Cu")
		(net "NFP_PCIE0_PER5_N")
	)
	(segment
		(start 8.601202 6.442202)
		(end 8.601202 7.129678)
		(width 0.110185)
		(layer "In2.Cu")
		(net "NFP_PCIE0_PER5_N")
	)
	(segment
		(start 8.964524 7.493)
		(end 9.571355 7.493)
		(width 0.110185)
		(layer "In2.Cu")
		(net "NFP_PCIE0_PER5_N")
	)
	(segment
		(start 14.951202 9.109202)
		(end 14.951202 9.813798)
		(width 0.110185)
		(layer "In2.Cu")
		(net "NFP_PCIE0_PER5_N")
	)
	(segment
		(start 5.343525 0.926338)
		(end 5.588 1.170813)
		(width 0.110185)
		(layer "In2.Cu")
		(net "NFP_PCIE0_PER5_N")
	)
	(segment
		(start 14.012748 -1.032891)
		(end 13.889177 -1.156462)
		(width 0.110185)
		(layer "In2.Cu")
		(net "NFP_PCIE0_PER5_N")
	)
	(segment
		(start 12.017121 9.109786)
		(end 12.017121 8.997264)
		(width 0.110185)
		(layer "In2.Cu")
		(net "NFP_PCIE0_PER5_N")
	)
	(segment
		(start 5.317261 -1.006577)
		(end 5.317261 -0.836397)
		(width 0.110185)
		(layer "In2.Cu")
		(net "NFP_PCIE0_PER5_N")
	)
	(segment
		(start 5.467147 -1.156462)
		(end 5.317261 -1.006577)
		(width 0.110185)
		(layer "In2.Cu")
		(net "NFP_PCIE0_PER5_N")
	)
	(segment
		(start 45.863891 -1.032891)
		(end 14.012748 -1.032891)
		(width 0.110185)
		(layer "In2.Cu")
		(net "NFP_PCIE0_PER5_N")
	)
	(segment
		(start 12.251385 8.763)
		(end 14.605 8.763)
		(width 0.110185)
		(layer "In2.Cu")
		(net "NFP_PCIE0_PER5_N")
	)
	(segment
		(start 4.138905 1.851406)
		(end 4.018509 1.971802)
		(width 0.110185)
		(layer "In2.Cu")
		(net "NFP_PCIE0_PER5_N")
	)
	(segment
		(start 4.018509 4.018483)
		(end 4.590034 4.590009)
		(width 0.110185)
		(layer "In2.Cu")
		(net "NFP_PCIE0_PER5_N")
	)
	(segment
		(start 8.601202 7.129678)
		(end 8.964524 7.493)
		(width 0.110185)
		(layer "In2.Cu")
		(net "NFP_PCIE0_PER5_N")
	)
	(segment
		(start 7.027164 7.913243)
		(end 7.027164 6.436335)
		(width 0.110185)
		(layer "In2.Cu")
		(net "NFP_PCIE0_PER5_N")
	)
	(segment
		(start 5.107305 0.261925)
		(end 4.663135 -0.182245)
		(width 0.110185)
		(layer "In2.Cu")
		(net "NFP_PCIE0_PER5_N")
	)
	(segment
		(start 7.345401 6.118098)
		(end 8.277098 6.118098)
		(width 0.110185)
		(layer "In2.Cu")
		(net "NFP_PCIE0_PER5_N")
	)
	(segment
		(start 52.916582 -0.543103)
		(end 52.122375 -1.33731)
		(width 0.110185)
		(layer "In2.Cu")
		(net "NFP_PCIE0_PER5_N")
	)
	(segment
		(start 11.525936 9.109786)
		(end 11.636121 9.219971)
		(width 0.110185)
		(layer "In2.Cu")
		(net "NFP_PCIE0_PER5_N")
	)
	(segment
		(start 14.242796 10.100818)
		(end 14.1224 10.221214)
		(width 0.110185)
		(layer "In2.Cu")
		(net "NFP_PCIE0_PER5_N")
	)
	(segment
		(start 46.16831 -1.33731)
		(end 45.863891 -1.032891)
		(width 0.110185)
		(layer "In2.Cu")
		(net "NFP_PCIE0_PER5_N")
	)
	(segment
		(start 4.018509 0.292176)
		(end 4.018509 0.805942)
		(width 0.110185)
		(layer "In2.Cu")
		(net "NFP_PCIE0_PER5_N")
	)
	(via
		(at 12.8524 12.0269)
		(size 0.762)
		(drill 0.254)
		(layers "F.Cu" "B.Cu")
		(net "NFP_PCIE0_PER4_P")
	)
	(via
		(at 54.483 0.3429)
		(size 0.508)
		(drill 0.25654)
		(layers "F.Cu" "B.Cu")
		(net "NFP_PCIE0_PER4_P")
	)
	(segment
		(start 13.4874 12.6619)
		(end 12.8524 12.0269)
		(width 0.138633)
		(layer "B.Cu")
		(net "NFP_PCIE0_PER4_P")
	)
	(segment
		(start 14.18463 -1.869694)
		(end 14.308201 -1.746123)
		(width 0.110185)
		(layer "In2.Cu")
		(net "NFP_PCIE0_PER4_P")
	)
	(segment
		(start 3.048 7.292772)
		(end 3.048 6.856654)
		(width 0.110185)
		(layer "In2.Cu")
		(net "NFP_PCIE0_PER4_P")
	)
	(segment
		(start 3.048 6.856654)
		(end 2.803525 6.612179)
		(width 0.110185)
		(layer "In2.Cu")
		(net "NFP_PCIE0_PER4_P")
	)
	(segment
		(start 1.989836 5.065319)
		(end 1.989836 4.804715)
		(width 0.110185)
		(layer "In2.Cu")
		(net "NFP_PCIE0_PER4_P")
	)
	(segment
		(start 2.803525 8.038643)
		(end 2.110232 8.038643)
		(width 0.110185)
		(layer "In2.Cu")
		(net "NFP_PCIE0_PER4_P")
	)
	(segment
		(start 2.110232 6.110783)
		(end 2.803525 6.110783)
		(width 0.110185)
		(layer "In2.Cu")
		(net "NFP_PCIE0_PER4_P")
	)
	(segment
		(start 5.102098 11.198098)
		(end 3.048 9.144)
		(width 0.110185)
		(layer "In2.Cu")
		(net "NFP_PCIE0_PER4_P")
	)
	(segment
		(start 3.048 8.283118)
		(end 2.803525 8.038643)
		(width 0.110185)
		(layer "In2.Cu")
		(net "NFP_PCIE0_PER4_P")
	)
	(segment
		(start 2.110232 5.185715)
		(end 1.989836 5.065319)
		(width 0.110185)
		(layer "In2.Cu")
		(net "NFP_PCIE0_PER4_P")
	)
	(segment
		(start 3.048 5.43019)
		(end 2.803525 5.185715)
		(width 0.110185)
		(layer "In2.Cu")
		(net "NFP_PCIE0_PER4_P")
	)
	(segment
		(start 2.803525 4.684319)
		(end 3.048 4.439844)
		(width 0.110185)
		(layer "In2.Cu")
		(net "NFP_PCIE0_PER4_P")
	)
	(segment
		(start 2.803525 5.185715)
		(end 2.110232 5.185715)
		(width 0.110185)
		(layer "In2.Cu")
		(net "NFP_PCIE0_PER4_P")
	)
	(segment
		(start 3.048 9.144)
		(end 3.048 8.283118)
		(width 0.110185)
		(layer "In2.Cu")
		(net "NFP_PCIE0_PER4_P")
	)
	(segment
		(start 9.871202 11.522202)
		(end 9.547098 11.198098)
		(width 0.110185)
		(layer "In2.Cu")
		(net "NFP_PCIE0_PER4_P")
	)
	(segment
		(start 13.022402 12.435561)
		(end 12.901981 12.555982)
		(width 0.110185)
		(layer "In2.Cu")
		(net "NFP_PCIE0_PER4_P")
	)
	(segment
		(start 3.048 5.866308)
		(end 3.048 5.43019)
		(width 0.110185)
		(layer "In2.Cu")
		(net "NFP_PCIE0_PER4_P")
	)
	(segment
		(start 2.110232 8.038643)
		(end 1.989836 7.918247)
		(width 0.110185)
		(layer "In2.Cu")
		(net "NFP_PCIE0_PER4_P")
	)
	(segment
		(start 12.8524 12.0269)
		(end 13.022402 12.196902)
		(width 0.110185)
		(layer "In2.Cu")
		(net "NFP_PCIE0_PER4_P")
	)
	(segment
		(start 14.308201 -1.746123)
		(end 45.561148 -1.746123)
		(width 0.110185)
		(layer "In2.Cu")
		(net "NFP_PCIE0_PER4_P")
	)
	(segment
		(start 54.358032 -1.902968)
		(end 55.225188 -1.035812)
		(width 0.110185)
		(layer "In2.Cu")
		(net "NFP_PCIE0_PER4_P")
	)
	(segment
		(start 2.110232 4.684319)
		(end 2.803525 4.684319)
		(width 0.110185)
		(layer "In2.Cu")
		(net "NFP_PCIE0_PER4_P")
	)
	(segment
		(start 3.048 0.254)
		(end 5.171694 -1.869694)
		(width 0.110185)
		(layer "In2.Cu")
		(net "NFP_PCIE0_PER4_P")
	)
	(segment
		(start 5.171694 -1.869694)
		(end 14.18463 -1.869694)
		(width 0.110185)
		(layer "In2.Cu")
		(net "NFP_PCIE0_PER4_P")
	)
	(segment
		(start 2.803525 6.110783)
		(end 3.048 5.866308)
		(width 0.110185)
		(layer "In2.Cu")
		(net "NFP_PCIE0_PER4_P")
	)
	(segment
		(start 54.775125 0.3429)
		(end 54.483 0.3429)
		(width 0.110185)
		(layer "In2.Cu")
		(net "NFP_PCIE0_PER4_P")
	)
	(segment
		(start 3.048 4.439844)
		(end 3.048 0.254)
		(width 0.110185)
		(layer "In2.Cu")
		(net "NFP_PCIE0_PER4_P")
	)
	(segment
		(start 9.547098 11.198098)
		(end 5.102098 11.198098)
		(width 0.110185)
		(layer "In2.Cu")
		(net "NFP_PCIE0_PER4_P")
	)
	(segment
		(start 2.803525 6.612179)
		(end 2.110232 6.612179)
		(width 0.110185)
		(layer "In2.Cu")
		(net "NFP_PCIE0_PER4_P")
	)
	(segment
		(start 1.989836 6.231179)
		(end 2.110232 6.110783)
		(width 0.110185)
		(layer "In2.Cu")
		(net "NFP_PCIE0_PER4_P")
	)
	(segment
		(start 2.110232 6.612179)
		(end 1.989836 6.491783)
		(width 0.110185)
		(layer "In2.Cu")
		(net "NFP_PCIE0_PER4_P")
	)
	(segment
		(start 10.217506 12.555982)
		(end 9.871202 12.209678)
		(width 0.110185)
		(layer "In2.Cu")
		(net "NFP_PCIE0_PER4_P")
	)
	(segment
		(start 55.225188 -0.107163)
		(end 54.775125 0.3429)
		(width 0.110185)
		(layer "In2.Cu")
		(net "NFP_PCIE0_PER4_P")
	)
	(segment
		(start 2.110232 7.537247)
		(end 2.803525 7.537247)
		(width 0.110185)
		(layer "In2.Cu")
		(net "NFP_PCIE0_PER4_P")
	)
	(segment
		(start 13.022402 12.196902)
		(end 13.022402 12.435561)
		(width 0.110185)
		(layer "In2.Cu")
		(net "NFP_PCIE0_PER4_P")
	)
	(segment
		(start 55.225188 -1.035812)
		(end 55.225188 -0.107163)
		(width 0.110185)
		(layer "In2.Cu")
		(net "NFP_PCIE0_PER4_P")
	)
	(segment
		(start 12.901981 12.555982)
		(end 10.217506 12.555982)
		(width 0.110185)
		(layer "In2.Cu")
		(net "NFP_PCIE0_PER4_P")
	)
	(segment
		(start 45.717968 -1.902968)
		(end 54.358032 -1.902968)
		(width 0.110185)
		(layer "In2.Cu")
		(net "NFP_PCIE0_PER4_P")
	)
	(segment
		(start 1.989836 7.657643)
		(end 2.110232 7.537247)
		(width 0.110185)
		(layer "In2.Cu")
		(net "NFP_PCIE0_PER4_P")
	)
	(segment
		(start 9.871202 12.209678)
		(end 9.871202 11.522202)
		(width 0.110185)
		(layer "In2.Cu")
		(net "NFP_PCIE0_PER4_P")
	)
	(segment
		(start 1.989836 7.918247)
		(end 1.989836 7.657643)
		(width 0.110185)
		(layer "In2.Cu")
		(net "NFP_PCIE0_PER4_P")
	)
	(segment
		(start 2.803525 7.537247)
		(end 3.048 7.292772)
		(width 0.110185)
		(layer "In2.Cu")
		(net "NFP_PCIE0_PER4_P")
	)
	(segment
		(start 1.989836 4.804715)
		(end 2.110232 4.684319)
		(width 0.110185)
		(layer "In2.Cu")
		(net "NFP_PCIE0_PER4_P")
	)
	(segment
		(start 45.561148 -1.746123)
		(end 45.717968 -1.902968)
		(width 0.110185)
		(layer "In2.Cu")
		(net "NFP_PCIE0_PER4_P")
	)
	(segment
		(start 1.989836 6.491783)
		(end 1.989836 6.231179)
		(width 0.110185)
		(layer "In2.Cu")
		(net "NFP_PCIE0_PER4_P")
	)
	(via
		(at 55.437024 0.3429)
		(size 0.508)
		(drill 0.25654)
		(layers "F.Cu" "B.Cu")
		(net "NFP_PCIE0_PER4_N")
	)
	(via
		(at 12.8524 13.2969)
		(size 0.762)
		(drill 0.2667)
		(layers "F.Cu" "B.Cu")
		(net "NFP_PCIE0_PER4_N")
	)
	(segment
		(start 13.4874 13.9319)
		(end 12.8524 13.2969)
		(width 0.138633)
		(layer "B.Cu")
		(net "NFP_PCIE0_PER4_N")
	)
	(segment
		(start 14.272387 -2.08153)
		(end 14.395958 -1.957959)
		(width 0.110185)
		(layer "In2.Cu")
		(net "NFP_PCIE0_PER4_N")
	)
	(segment
		(start 2.715768 6.824015)
		(end 2.022475 6.824015)
		(width 0.110185)
		(layer "In2.Cu")
		(net "NFP_PCIE0_PER4_N")
	)
	(segment
		(start 9.459341 11.409934)
		(end 5.014341 11.409934)
		(width 0.110185)
		(layer "In2.Cu")
		(net "NFP_PCIE0_PER4_N")
	)
	(segment
		(start 9.659366 11.609959)
		(end 9.459341 11.409934)
		(width 0.110185)
		(layer "In2.Cu")
		(net "NFP_PCIE0_PER4_N")
	)
	(segment
		(start 55.437024 -1.123569)
		(end 55.437024 0.3429)
		(width 0.110185)
		(layer "In2.Cu")
		(net "NFP_PCIE0_PER4_N")
	)
	(segment
		(start 2.022475 5.397551)
		(end 1.778 5.153076)
		(width 0.110185)
		(layer "In2.Cu")
		(net "NFP_PCIE0_PER4_N")
	)
	(segment
		(start 10.129749 12.767818)
		(end 9.659366 12.297435)
		(width 0.110185)
		(layer "In2.Cu")
		(net "NFP_PCIE0_PER4_N")
	)
	(segment
		(start 2.836164 4.352087)
		(end 2.836164 0.166243)
		(width 0.110185)
		(layer "In2.Cu")
		(net "NFP_PCIE0_PER4_N")
	)
	(segment
		(start 2.836164 7.205015)
		(end 2.836164 6.944411)
		(width 0.110185)
		(layer "In2.Cu")
		(net "NFP_PCIE0_PER4_N")
	)
	(segment
		(start 2.836164 5.517947)
		(end 2.715768 5.397551)
		(width 0.110185)
		(layer "In2.Cu")
		(net "NFP_PCIE0_PER4_N")
	)
	(segment
		(start 2.022475 7.325411)
		(end 2.715768 7.325411)
		(width 0.110185)
		(layer "In2.Cu")
		(net "NFP_PCIE0_PER4_N")
	)
	(segment
		(start 2.715768 4.472483)
		(end 2.836164 4.352087)
		(width 0.110185)
		(layer "In2.Cu")
		(net "NFP_PCIE0_PER4_N")
	)
	(segment
		(start 2.836164 5.778551)
		(end 2.836164 5.517947)
		(width 0.110185)
		(layer "In2.Cu")
		(net "NFP_PCIE0_PER4_N")
	)
	(segment
		(start 5.014341 11.409934)
		(end 2.836164 9.231757)
		(width 0.110185)
		(layer "In2.Cu")
		(net "NFP_PCIE0_PER4_N")
	)
	(segment
		(start 45.630211 -2.114804)
		(end 54.445789 -2.114804)
		(width 0.110185)
		(layer "In2.Cu")
		(net "NFP_PCIE0_PER4_N")
	)
	(segment
		(start 2.836164 0.166243)
		(end 5.083937 -2.08153)
		(width 0.110185)
		(layer "In2.Cu")
		(net "NFP_PCIE0_PER4_N")
	)
	(segment
		(start 5.083937 -2.08153)
		(end 14.272387 -2.08153)
		(width 0.110185)
		(layer "In2.Cu")
		(net "NFP_PCIE0_PER4_N")
	)
	(segment
		(start 2.715768 7.325411)
		(end 2.836164 7.205015)
		(width 0.110185)
		(layer "In2.Cu")
		(net "NFP_PCIE0_PER4_N")
	)
	(segment
		(start 2.836164 6.944411)
		(end 2.715768 6.824015)
		(width 0.110185)
		(layer "In2.Cu")
		(net "NFP_PCIE0_PER4_N")
	)
	(segment
		(start 2.022475 4.472483)
		(end 2.715768 4.472483)
		(width 0.110185)
		(layer "In2.Cu")
		(net "NFP_PCIE0_PER4_N")
	)
	(segment
		(start 1.778 8.006004)
		(end 1.778 7.569886)
		(width 0.110185)
		(layer "In2.Cu")
		(net "NFP_PCIE0_PER4_N")
	)
	(segment
		(start 2.022475 5.898947)
		(end 2.715768 5.898947)
		(width 0.110185)
		(layer "In2.Cu")
		(net "NFP_PCIE0_PER4_N")
	)
	(segment
		(start 2.836164 9.231757)
		(end 2.836164 8.370875)
		(width 0.110185)
		(layer "In2.Cu")
		(net "NFP_PCIE0_PER4_N")
	)
	(segment
		(start 2.715768 8.250479)
		(end 2.022475 8.250479)
		(width 0.110185)
		(layer "In2.Cu")
		(net "NFP_PCIE0_PER4_N")
	)
	(segment
		(start 1.778 5.153076)
		(end 1.778 4.716958)
		(width 0.110185)
		(layer "In2.Cu")
		(net "NFP_PCIE0_PER4_N")
	)
	(segment
		(start 1.778 4.716958)
		(end 2.022475 4.472483)
		(width 0.110185)
		(layer "In2.Cu")
		(net "NFP_PCIE0_PER4_N")
	)
	(segment
		(start 9.659366 12.297435)
		(end 9.659366 11.609959)
		(width 0.110185)
		(layer "In2.Cu")
		(net "NFP_PCIE0_PER4_N")
	)
	(segment
		(start 2.836164 8.370875)
		(end 2.715768 8.250479)
		(width 0.110185)
		(layer "In2.Cu")
		(net "NFP_PCIE0_PER4_N")
	)
	(segment
		(start 2.715768 5.397551)
		(end 2.022475 5.397551)
		(width 0.110185)
		(layer "In2.Cu")
		(net "NFP_PCIE0_PER4_N")
	)
	(segment
		(start 12.8524 13.2969)
		(end 12.323318 12.767818)
		(width 0.110185)
		(layer "In2.Cu")
		(net "NFP_PCIE0_PER4_N")
	)
	(segment
		(start 2.022475 6.824015)
		(end 1.778 6.57954)
		(width 0.110185)
		(layer "In2.Cu")
		(net "NFP_PCIE0_PER4_N")
	)
	(segment
		(start 12.323318 12.767818)
		(end 10.129749 12.767818)
		(width 0.110185)
		(layer "In2.Cu")
		(net "NFP_PCIE0_PER4_N")
	)
	(segment
		(start 2.715768 5.898947)
		(end 2.836164 5.778551)
		(width 0.110185)
		(layer "In2.Cu")
		(net "NFP_PCIE0_PER4_N")
	)
	(segment
		(start 1.778 6.143422)
		(end 2.022475 5.898947)
		(width 0.110185)
		(layer "In2.Cu")
		(net "NFP_PCIE0_PER4_N")
	)
	(segment
		(start 14.395958 -1.957959)
		(end 45.473391 -1.957959)
		(width 0.110185)
		(layer "In2.Cu")
		(net "NFP_PCIE0_PER4_N")
	)
	(segment
		(start 1.778 6.57954)
		(end 1.778 6.143422)
		(width 0.110185)
		(layer "In2.Cu")
		(net "NFP_PCIE0_PER4_N")
	)
	(segment
		(start 45.473391 -1.957959)
		(end 45.630211 -2.114804)
		(width 0.110185)
		(layer "In2.Cu")
		(net "NFP_PCIE0_PER4_N")
	)
	(segment
		(start 1.778 7.569886)
		(end 2.022475 7.325411)
		(width 0.110185)
		(layer "In2.Cu")
		(net "NFP_PCIE0_PER4_N")
	)
	(segment
		(start 2.022475 8.250479)
		(end 1.778 8.006004)
		(width 0.110185)
		(layer "In2.Cu")
		(net "NFP_PCIE0_PER4_N")
	)
	(segment
		(start 54.445789 -2.114804)
		(end 55.437024 -1.123569)
		(width 0.110185)
		(layer "In2.Cu")
		(net "NFP_PCIE0_PER4_N")
	)
	(via
		(at 12.8524 22.1869)
		(size 0.762)
		(drill 0.254)
		(layers "F.Cu" "B.Cu")
		(net "NFP_PCIE0_PER3_P")
	)
	(via
		(at 57.404 0.3429)
		(size 0.508)
		(drill 0.25654)
		(layers "F.Cu" "B.Cu")
		(net "NFP_PCIE0_PER3_P")
	)
	(segment
		(start 13.4874 22.8219)
		(end 12.8524 22.1869)
		(width 0.138633)
		(layer "B.Cu")
		(net "NFP_PCIE0_PER3_P")
	)
	(segment
		(start 11.296472 1.137641)
		(end 11.564366 0.812571)
		(width 0.110185)
		(layer "In3.Cu")
		(net "NFP_PCIE0_PER3_P")
	)
	(segment
		(start 15.787243 21.505164)
		(end 15.917164 21.375243)
		(width 0.110185)
		(layer "In3.Cu")
		(net "NFP_PCIE0_PER3_P")
	)
	(segment
		(start 56.811189 -0.338836)
		(end 57.001918 -0.148107)
		(width 0.110185)
		(layer "In3.Cu")
		(net "NFP_PCIE0_PER3_P")
	)
	(segment
		(start 15.917164 21.375243)
		(end 15.917164 11.771757)
		(width 0.110185)
		(layer "In3.Cu")
		(net "NFP_PCIE0_PER3_P")
	)
	(segment
		(start 57.001918 -0.059182)
		(end 57.404 0.3429)
		(width 0.110185)
		(layer "In3.Cu")
		(net "NFP_PCIE0_PER3_P")
	)
	(segment
		(start 57.001918 -0.148107)
		(end 57.001918 -0.059182)
		(width 0.110185)
		(layer "In3.Cu")
		(net "NFP_PCIE0_PER3_P")
	)
	(segment
		(start 14.368018 22.715982)
		(end 14.679066 22.404934)
		(width 0.110185)
		(layer "In3.Cu")
		(net "NFP_PCIE0_PER3_P")
	)
	(segment
		(start 7.78957 2.402078)
		(end 8.371535 2.984043)
		(width 0.110185)
		(layer "In3.Cu")
		(net "NFP_PCIE0_PER3_P")
	)
	(segment
		(start 6.985 8.300568)
		(end 6.985 2.875432)
		(width 0.110185)
		(layer "In3.Cu")
		(net "NFP_PCIE0_PER3_P")
	)
	(segment
		(start 8.136941 2.054758)
		(end 8.136941 1.723441)
		(width 0.110185)
		(layer "In3.Cu")
		(net "NFP_PCIE0_PER3_P")
	)
	(segment
		(start 25.274499 0.563626)
		(end 25.813233 0.024892)
		(width 0.110185)
		(layer "In3.Cu")
		(net "NFP_PCIE0_PER3_P")
	)
	(segment
		(start 13.641959 0.314198)
		(end 13.64201 0.314198)
		(width 0.110185)
		(layer "In3.Cu")
		(net "NFP_PCIE0_PER3_P")
	)
	(segment
		(start 6.985 2.875432)
		(end 7.458304 2.402078)
		(width 0.110185)
		(layer "In3.Cu")
		(net "NFP_PCIE0_PER3_P")
	)
	(segment
		(start 11.037138 1.396975)
		(end 11.296472 1.137641)
		(width 0.110185)
		(layer "In3.Cu")
		(net "NFP_PCIE0_PER3_P")
	)
	(segment
		(start 20.864703 0.563626)
		(end 25.274499 0.563626)
		(width 0.110185)
		(layer "In3.Cu")
		(net "NFP_PCIE0_PER3_P")
	)
	(segment
		(start 8.71888 2.636698)
		(end 8.136941 2.054758)
		(width 0.110185)
		(layer "In3.Cu")
		(net "NFP_PCIE0_PER3_P")
	)
	(segment
		(start 25.813233 0.024892)
		(end 29.660367 0.024892)
		(width 0.110185)
		(layer "In3.Cu")
		(net "NFP_PCIE0_PER3_P")
	)
	(segment
		(start 12.318771 0.058166)
		(end 13.385927 0.058166)
		(width 0.110185)
		(layer "In3.Cu")
		(net "NFP_PCIE0_PER3_P")
	)
	(segment
		(start 13.385927 0.058166)
		(end 13.641959 0.314198)
		(width 0.110185)
		(layer "In3.Cu")
		(net "NFP_PCIE0_PER3_P")
	)
	(segment
		(start 29.660367 0.024892)
		(end 30.199101 0.563626)
		(width 0.110185)
		(layer "In3.Cu")
		(net "NFP_PCIE0_PER3_P")
	)
	(segment
		(start 14.679066 22.404934)
		(end 14.679066 21.883243)
		(width 0.110185)
		(layer "In3.Cu")
		(net "NFP_PCIE0_PER3_P")
	)
	(segment
		(start 7.458304 2.402078)
		(end 7.78957 2.402078)
		(width 0.110185)
		(layer "In3.Cu")
		(net "NFP_PCIE0_PER3_P")
	)
	(segment
		(start 8.136941 1.723441)
		(end 8.463407 1.396975)
		(width 0.110185)
		(layer "In3.Cu")
		(net "NFP_PCIE0_PER3_P")
	)
	(segment
		(start 7.532294 11.514836)
		(end 7.070598 11.05314)
		(width 0.110185)
		(layer "In3.Cu")
		(net "NFP_PCIE0_PER3_P")
	)
	(segment
		(start 7.070598 8.386166)
		(end 6.985 8.300568)
		(width 0.110185)
		(layer "In3.Cu")
		(net "NFP_PCIE0_PER3_P")
	)
	(segment
		(start 15.917164 11.771757)
		(end 15.660243 11.514836)
		(width 0.110185)
		(layer "In3.Cu")
		(net "NFP_PCIE0_PER3_P")
	)
	(segment
		(start 20.677734 0.750595)
		(end 20.864703 0.563626)
		(width 0.110185)
		(layer "In3.Cu")
		(net "NFP_PCIE0_PER3_P")
	)
	(segment
		(start 12.8524 22.1869)
		(end 13.381482 22.715982)
		(width 0.110185)
		(layer "In3.Cu")
		(net "NFP_PCIE0_PER3_P")
	)
	(segment
		(start 8.527339 2.984043)
		(end 8.71888 2.792501)
		(width 0.110185)
		(layer "In3.Cu")
		(net "NFP_PCIE0_PER3_P")
	)
	(segment
		(start 8.71888 2.792501)
		(end 8.71888 2.636698)
		(width 0.110185)
		(layer "In3.Cu")
		(net "NFP_PCIE0_PER3_P")
	)
	(segment
		(start 15.660243 11.514836)
		(end 7.532294 11.514836)
		(width 0.110185)
		(layer "In3.Cu")
		(net "NFP_PCIE0_PER3_P")
	)
	(segment
		(start 46.761781 0.563626)
		(end 47.664243 -0.338836)
		(width 0.110185)
		(layer "In3.Cu")
		(net "NFP_PCIE0_PER3_P")
	)
	(segment
		(start 13.381482 22.715982)
		(end 14.368018 22.715982)
		(width 0.110185)
		(layer "In3.Cu")
		(net "NFP_PCIE0_PER3_P")
	)
	(segment
		(start 15.057145 21.505164)
		(end 15.787243 21.505164)
		(width 0.110185)
		(layer "In3.Cu")
		(net "NFP_PCIE0_PER3_P")
	)
	(segment
		(start 7.070598 11.05314)
		(end 7.070598 8.386166)
		(width 0.110185)
		(layer "In3.Cu")
		(net "NFP_PCIE0_PER3_P")
	)
	(segment
		(start 14.078407 0.750595)
		(end 20.677734 0.750595)
		(width 0.110185)
		(layer "In3.Cu")
		(net "NFP_PCIE0_PER3_P")
	)
	(segment
		(start 8.463407 1.396975)
		(end 11.037138 1.396975)
		(width 0.110185)
		(layer "In3.Cu")
		(net "NFP_PCIE0_PER3_P")
	)
	(segment
		(start 47.664243 -0.338836)
		(end 56.811189 -0.338836)
		(width 0.110185)
		(layer "In3.Cu")
		(net "NFP_PCIE0_PER3_P")
	)
	(segment
		(start 8.371535 2.984043)
		(end 8.527339 2.984043)
		(width 0.110185)
		(layer "In3.Cu")
		(net "NFP_PCIE0_PER3_P")
	)
	(segment
		(start 30.199101 0.563626)
		(end 46.761781 0.563626)
		(width 0.110185)
		(layer "In3.Cu")
		(net "NFP_PCIE0_PER3_P")
	)
	(segment
		(start 13.64201 0.314198)
		(end 14.078407 0.750595)
		(width 0.110185)
		(layer "In3.Cu")
		(net "NFP_PCIE0_PER3_P")
	)
	(segment
		(start 14.679066 21.883243)
		(end 15.057145 21.505164)
		(width 0.110185)
		(layer "In3.Cu")
		(net "NFP_PCIE0_PER3_P")
	)
	(segment
		(start 11.564366 0.812571)
		(end 12.318771 0.058166)
		(width 0.110185)
		(layer "In3.Cu")
		(net "NFP_PCIE0_PER3_P")
	)
	(via
		(at 56.388 0.3429)
		(size 0.508)
		(drill 0.25654)
		(layers "F.Cu" "B.Cu")
		(net "NFP_PCIE0_PER3_N")
	)
	(via
		(at 12.8524 23.4569)
		(size 0.762)
		(drill 0.2667)
		(layers "F.Cu" "B.Cu")
		(net "NFP_PCIE0_PER3_N")
	)
	(segment
		(start 13.4874 24.0919)
		(end 12.8524 23.4569)
		(width 0.138633)
		(layer "B.Cu")
		(net "NFP_PCIE0_PER3_N")
	)
	(segment
		(start 7.701813 2.613914)
		(end 8.283778 3.195879)
		(width 0.110185)
		(layer "In3.Cu")
		(net "NFP_PCIE0_PER3_N")
	)
	(segment
		(start 12.406528 0.270002)
		(end 13.29817 0.270002)
		(width 0.110185)
		(layer "In3.Cu")
		(net "NFP_PCIE0_PER3_N")
	)
	(segment
		(start 25.90099 0.236728)
		(end 29.57261 0.236728)
		(width 0.110185)
		(layer "In3.Cu")
		(net "NFP_PCIE0_PER3_N")
	)
	(segment
		(start 8.930716 2.548941)
		(end 8.348777 1.967001)
		(width 0.110185)
		(layer "In3.Cu")
		(net "NFP_PCIE0_PER3_N")
	)
	(segment
		(start 12.8524 23.4569)
		(end 12.8524 23.048214)
		(width 0.110185)
		(layer "In3.Cu")
		(net "NFP_PCIE0_PER3_N")
	)
	(segment
		(start 11.721363 0.955167)
		(end 12.406528 0.270002)
		(width 0.110185)
		(layer "In3.Cu")
		(net "NFP_PCIE0_PER3_N")
	)
	(segment
		(start 7.388708 2.771318)
		(end 7.546061 2.613914)
		(width 0.110185)
		(layer "In3.Cu")
		(net "NFP_PCIE0_PER3_N")
	)
	(segment
		(start 7.196836 2.963189)
		(end 7.388708 2.771318)
		(width 0.110185)
		(layer "In3.Cu")
		(net "NFP_PCIE0_PER3_N")
	)
	(segment
		(start 11.124895 1.608811)
		(end 11.45347 1.280236)
		(width 0.110185)
		(layer "In3.Cu")
		(net "NFP_PCIE0_PER3_N")
	)
	(segment
		(start 15.144902 21.717)
		(end 15.875 21.717)
		(width 0.110185)
		(layer "In3.Cu")
		(net "NFP_PCIE0_PER3_N")
	)
	(segment
		(start 29.57261 0.236728)
		(end 30.111344 0.775462)
		(width 0.110185)
		(layer "In3.Cu")
		(net "NFP_PCIE0_PER3_N")
	)
	(segment
		(start 20.765491 0.962431)
		(end 20.95246 0.775462)
		(width 0.110185)
		(layer "In3.Cu")
		(net "NFP_PCIE0_PER3_N")
	)
	(segment
		(start 7.196836 8.212811)
		(end 7.196836 2.963189)
		(width 0.110185)
		(layer "In3.Cu")
		(net "NFP_PCIE0_PER3_N")
	)
	(segment
		(start 13.29817 0.270002)
		(end 13.554202 0.526034)
		(width 0.110185)
		(layer "In3.Cu")
		(net "NFP_PCIE0_PER3_N")
	)
	(segment
		(start 13.554253 0.526034)
		(end 13.99065 0.962431)
		(width 0.110185)
		(layer "In3.Cu")
		(net "NFP_PCIE0_PER3_N")
	)
	(segment
		(start 8.615096 3.195879)
		(end 8.930716 2.880258)
		(width 0.110185)
		(layer "In3.Cu")
		(net "NFP_PCIE0_PER3_N")
	)
	(segment
		(start 7.282434 10.965383)
		(end 7.282434 8.298409)
		(width 0.110185)
		(layer "In3.Cu")
		(net "NFP_PCIE0_PER3_N")
	)
	(segment
		(start 46.849538 0.775462)
		(end 47.752 -0.127)
		(width 0.110185)
		(layer "In3.Cu")
		(net "NFP_PCIE0_PER3_N")
	)
	(segment
		(start 7.282434 8.298409)
		(end 7.196836 8.212811)
		(width 0.110185)
		(layer "In3.Cu")
		(net "NFP_PCIE0_PER3_N")
	)
	(segment
		(start 12.972796 22.927818)
		(end 14.455775 22.927818)
		(width 0.110185)
		(layer "In3.Cu")
		(net "NFP_PCIE0_PER3_N")
	)
	(segment
		(start 56.790082 0.222504)
		(end 56.669686 0.3429)
		(width 0.110185)
		(layer "In3.Cu")
		(net "NFP_PCIE0_PER3_N")
	)
	(segment
		(start 14.890902 21.971)
		(end 15.144902 21.717)
		(width 0.110185)
		(layer "In3.Cu")
		(net "NFP_PCIE0_PER3_N")
	)
	(segment
		(start 8.348777 1.967001)
		(end 8.348777 1.811198)
		(width 0.110185)
		(layer "In3.Cu")
		(net "NFP_PCIE0_PER3_N")
	)
	(segment
		(start 14.455775 22.927818)
		(end 14.890902 22.492691)
		(width 0.110185)
		(layer "In3.Cu")
		(net "NFP_PCIE0_PER3_N")
	)
	(segment
		(start 20.95246 0.775462)
		(end 25.362256 0.775462)
		(width 0.110185)
		(layer "In3.Cu")
		(net "NFP_PCIE0_PER3_N")
	)
	(segment
		(start 15.875 21.717)
		(end 16.129 21.463)
		(width 0.110185)
		(layer "In3.Cu")
		(net "NFP_PCIE0_PER3_N")
	)
	(segment
		(start 30.111344 0.775462)
		(end 46.849538 0.775462)
		(width 0.110185)
		(layer "In3.Cu")
		(net "NFP_PCIE0_PER3_N")
	)
	(segment
		(start 56.704967 -0.127)
		(end 56.790082 -0.041885)
		(width 0.110185)
		(layer "In3.Cu")
		(net "NFP_PCIE0_PER3_N")
	)
	(segment
		(start 8.348777 1.811198)
		(end 8.551164 1.608811)
		(width 0.110185)
		(layer "In3.Cu")
		(net "NFP_PCIE0_PER3_N")
	)
	(segment
		(start 8.930716 2.880258)
		(end 8.930716 2.548941)
		(width 0.110185)
		(layer "In3.Cu")
		(net "NFP_PCIE0_PER3_N")
	)
	(segment
		(start 56.790082 -0.041885)
		(end 56.790082 0.222504)
		(width 0.110185)
		(layer "In3.Cu")
		(net "NFP_PCIE0_PER3_N")
	)
	(segment
		(start 47.752 -0.127)
		(end 56.704967 -0.127)
		(width 0.110185)
		(layer "In3.Cu")
		(net "NFP_PCIE0_PER3_N")
	)
	(segment
		(start 7.546061 2.613914)
		(end 7.701813 2.613914)
		(width 0.110185)
		(layer "In3.Cu")
		(net "NFP_PCIE0_PER3_N")
	)
	(segment
		(start 13.99065 0.962431)
		(end 20.765491 0.962431)
		(width 0.110185)
		(layer "In3.Cu")
		(net "NFP_PCIE0_PER3_N")
	)
	(segment
		(start 13.554202 0.526034)
		(end 13.554253 0.526034)
		(width 0.110185)
		(layer "In3.Cu")
		(net "NFP_PCIE0_PER3_N")
	)
	(segment
		(start 8.551164 1.608811)
		(end 11.124895 1.608811)
		(width 0.110185)
		(layer "In3.Cu")
		(net "NFP_PCIE0_PER3_N")
	)
	(segment
		(start 7.620051 11.303)
		(end 7.282434 10.965383)
		(width 0.110185)
		(layer "In3.Cu")
		(net "NFP_PCIE0_PER3_N")
	)
	(segment
		(start 8.283778 3.195879)
		(end 8.615096 3.195879)
		(width 0.110185)
		(layer "In3.Cu")
		(net "NFP_PCIE0_PER3_N")
	)
	(segment
		(start 12.8524 23.048214)
		(end 12.972796 22.927818)
		(width 0.110185)
		(layer "In3.Cu")
		(net "NFP_PCIE0_PER3_N")
	)
	(segment
		(start 56.669686 0.3429)
		(end 56.388 0.3429)
		(width 0.110185)
		(layer "In3.Cu")
		(net "NFP_PCIE0_PER3_N")
	)
	(segment
		(start 14.890902 22.492691)
		(end 14.890902 21.971)
		(width 0.110185)
		(layer "In3.Cu")
		(net "NFP_PCIE0_PER3_N")
	)
	(segment
		(start 11.45347 1.280236)
		(end 11.721363 0.955167)
		(width 0.110185)
		(layer "In3.Cu")
		(net "NFP_PCIE0_PER3_N")
	)
	(segment
		(start 25.362256 0.775462)
		(end 25.90099 0.236728)
		(width 0.110185)
		(layer "In3.Cu")
		(net "NFP_PCIE0_PER3_N")
	)
	(segment
		(start 16.129 21.463)
		(end 16.129 11.684)
		(width 0.110185)
		(layer "In3.Cu")
		(net "NFP_PCIE0_PER3_N")
	)
	(segment
		(start 16.129 11.684)
		(end 15.748 11.303)
		(width 0.110185)
		(layer "In3.Cu")
		(net "NFP_PCIE0_PER3_N")
	)
	(segment
		(start 15.748 11.303)
		(end 7.620051 11.303)
		(width 0.110185)
		(layer "In3.Cu")
		(net "NFP_PCIE0_PER3_N")
	)
	(via
		(at 59.373008 0.3429)
		(size 0.508)
		(drill 0.25654)
		(layers "F.Cu" "B.Cu")
		(net "NFP_PCIE0_PER2_P")
	)
	(via
		(at 14.1224 20.9169)
		(size 0.762)
		(drill 0.254)
		(layers "F.Cu" "B.Cu")
		(net "NFP_PCIE0_PER2_P")
	)
	(segment
		(start 14.7574 20.2819)
		(end 14.1224 20.9169)
		(width 0.138633)
		(layer "B.Cu")
		(net "NFP_PCIE0_PER2_P")
	)
	(segment
		(start 14.739366 19.124041)
		(end 14.739366 14.485366)
		(width 0.110185)
		(layer "In3.Cu")
		(net "NFP_PCIE0_PER2_P")
	)
	(segment
		(start 24.979046 -0.149606)
		(end 25.51778 -0.68834)
		(width 0.110185)
		(layer "In3.Cu")
		(net "NFP_PCIE0_PER2_P")
	)
	(segment
		(start 14.351 14.097)
		(end 8.636 14.097)
		(width 0.110185)
		(layer "In3.Cu")
		(net "NFP_PCIE0_PER2_P")
	)
	(segment
		(start 14.1224 20.9169)
		(end 14.1224 19.741007)
		(width 0.110185)
		(layer "In3.Cu")
		(net "NFP_PCIE0_PER2_P")
	)
	(segment
		(start 29.95582 -0.68834)
		(end 30.4689 -0.17526)
		(width 0.110185)
		(layer "In3.Cu")
		(net "NFP_PCIE0_PER2_P")
	)
	(segment
		(start 13.68138 -0.655066)
		(end 13.937412 -0.399034)
		(width 0.110185)
		(layer "In3.Cu")
		(net "NFP_PCIE0_PER2_P")
	)
	(segment
		(start 15.764535 -0.399034)
		(end 16.013963 -0.149606)
		(width 0.110185)
		(layer "In3.Cu")
		(net "NFP_PCIE0_PER2_P")
	)
	(segment
		(start 30.4689 -0.17526)
		(end 46.484642 -0.17526)
		(width 0.110185)
		(layer "In3.Cu")
		(net "NFP_PCIE0_PER2_P")
	)
	(segment
		(start 14.1224 19.741007)
		(end 14.739366 19.124041)
		(width 0.110185)
		(layer "In3.Cu")
		(net "NFP_PCIE0_PER2_P")
	)
	(segment
		(start 7.767066 -0.655066)
		(end 13.68138 -0.655066)
		(width 0.110185)
		(layer "In3.Cu")
		(net "NFP_PCIE0_PER2_P")
	)
	(segment
		(start 58.986928 -0.621665)
		(end 58.986928 -0.04318)
		(width 0.110185)
		(layer "In3.Cu")
		(net "NFP_PCIE0_PER2_P")
	)
	(segment
		(start 6.604 1.651)
		(end 6.604 0.508)
		(width 0.110185)
		(layer "In3.Cu")
		(net "NFP_PCIE0_PER2_P")
	)
	(segment
		(start 6.604 0.508)
		(end 7.767066 -0.655066)
		(width 0.110185)
		(layer "In3.Cu")
		(net "NFP_PCIE0_PER2_P")
	)
	(segment
		(start 57.581267 -0.973836)
		(end 57.641465 -1.034034)
		(width 0.110185)
		(layer "In3.Cu")
		(net "NFP_PCIE0_PER2_P")
	)
	(segment
		(start 5.890768 2.364232)
		(end 6.604 1.651)
		(width 0.110185)
		(layer "In3.Cu")
		(net "NFP_PCIE0_PER2_P")
	)
	(segment
		(start 57.641465 -1.034034)
		(end 58.574559 -1.034034)
		(width 0.110185)
		(layer "In3.Cu")
		(net "NFP_PCIE0_PER2_P")
	)
	(segment
		(start 8.255 13.021945)
		(end 8.001 12.767945)
		(width 0.110185)
		(layer "In3.Cu")
		(net "NFP_PCIE0_PER2_P")
	)
	(segment
		(start 16.013963 -0.149606)
		(end 24.979046 -0.149606)
		(width 0.110185)
		(layer "In3.Cu")
		(net "NFP_PCIE0_PER2_P")
	)
	(segment
		(start 58.986928 -0.04318)
		(end 59.373008 0.3429)
		(width 0.110185)
		(layer "In3.Cu")
		(net "NFP_PCIE0_PER2_P")
	)
	(segment
		(start 13.937412 -0.399034)
		(end 15.764535 -0.399034)
		(width 0.110185)
		(layer "In3.Cu")
		(net "NFP_PCIE0_PER2_P")
	)
	(segment
		(start 25.51778 -0.68834)
		(end 29.95582 -0.68834)
		(width 0.110185)
		(layer "In3.Cu")
		(net "NFP_PCIE0_PER2_P")
	)
	(segment
		(start 8.255 13.716)
		(end 8.255 13.021945)
		(width 0.110185)
		(layer "In3.Cu")
		(net "NFP_PCIE0_PER2_P")
	)
	(segment
		(start 8.636 14.097)
		(end 8.255 13.716)
		(width 0.110185)
		(layer "In3.Cu")
		(net "NFP_PCIE0_PER2_P")
	)
	(segment
		(start 58.574559 -1.034034)
		(end 58.986928 -0.621665)
		(width 0.110185)
		(layer "In3.Cu")
		(net "NFP_PCIE0_PER2_P")
	)
	(segment
		(start 5.890768 10.889336)
		(end 5.890768 2.364232)
		(width 0.110185)
		(layer "In3.Cu")
		(net "NFP_PCIE0_PER2_P")
	)
	(segment
		(start 8.001 12.767945)
		(end 7.769377 12.767945)
		(width 0.110185)
		(layer "In3.Cu")
		(net "NFP_PCIE0_PER2_P")
	)
	(segment
		(start 47.283218 -0.973836)
		(end 57.581267 -0.973836)
		(width 0.110185)
		(layer "In3.Cu")
		(net "NFP_PCIE0_PER2_P")
	)
	(segment
		(start 46.484642 -0.17526)
		(end 47.283218 -0.973836)
		(width 0.110185)
		(layer "In3.Cu")
		(net "NFP_PCIE0_PER2_P")
	)
	(segment
		(start 7.769377 12.767945)
		(end 5.890768 10.889336)
		(width 0.110185)
		(layer "In3.Cu")
		(net "NFP_PCIE0_PER2_P")
	)
	(segment
		(start 14.739366 14.485366)
		(end 14.351 14.097)
		(width 0.110185)
		(layer "In3.Cu")
		(net "NFP_PCIE0_PER2_P")
	)
	(via
		(at 15.3924 20.9169)
		(size 0.762)
		(drill 0.2667)
		(layers "F.Cu" "B.Cu")
		(net "NFP_PCIE0_PER2_N")
	)
	(via
		(at 58.389012 0.3429)
		(size 0.508)
		(drill 0.25654)
		(layers "F.Cu" "B.Cu")
		(net "NFP_PCIE0_PER2_N")
	)
	(segment
		(start 14.7574 21.5519)
		(end 15.3924 20.9169)
		(width 0.138633)
		(layer "B.Cu")
		(net "NFP_PCIE0_PER2_N")
	)
	(segment
		(start 29.868063 -0.476504)
		(end 30.381143 0.036576)
		(width 0.110185)
		(layer "In3.Cu")
		(net "NFP_PCIE0_PER2_N")
	)
	(segment
		(start 15.676778 -0.187198)
		(end 15.926206 0.06223)
		(width 0.110185)
		(layer "In3.Cu")
		(net "NFP_PCIE0_PER2_N")
	)
	(segment
		(start 46.572399 0.036576)
		(end 47.370975 -0.762)
		(width 0.110185)
		(layer "In3.Cu")
		(net "NFP_PCIE0_PER2_N")
	)
	(segment
		(start 6.815836 0.595757)
		(end 7.854823 -0.44323)
		(width 0.110185)
		(layer "In3.Cu")
		(net "NFP_PCIE0_PER2_N")
	)
	(segment
		(start 47.370975 -0.762)
		(end 57.669024 -0.762)
		(width 0.110185)
		(layer "In3.Cu")
		(net "NFP_PCIE0_PER2_N")
	)
	(segment
		(start 14.438757 13.885164)
		(end 8.723757 13.885164)
		(width 0.110185)
		(layer "In3.Cu")
		(net "NFP_PCIE0_PER2_N")
	)
	(segment
		(start 6.102604 2.451989)
		(end 6.815836 1.738757)
		(width 0.110185)
		(layer "In3.Cu")
		(net "NFP_PCIE0_PER2_N")
	)
	(segment
		(start 58.775092 -0.533908)
		(end 58.775092 -0.04318)
		(width 0.110185)
		(layer "In3.Cu")
		(net "NFP_PCIE0_PER2_N")
	)
	(segment
		(start 14.951202 19.211798)
		(end 14.951202 14.397609)
		(width 0.110185)
		(layer "In3.Cu")
		(net "NFP_PCIE0_PER2_N")
	)
	(segment
		(start 58.775092 -0.04318)
		(end 58.389012 0.3429)
		(width 0.110185)
		(layer "In3.Cu")
		(net "NFP_PCIE0_PER2_N")
	)
	(segment
		(start 8.466836 13.628243)
		(end 8.466836 12.934188)
		(width 0.110185)
		(layer "In3.Cu")
		(net "NFP_PCIE0_PER2_N")
	)
	(segment
		(start 30.381143 0.036576)
		(end 46.572399 0.036576)
		(width 0.110185)
		(layer "In3.Cu")
		(net "NFP_PCIE0_PER2_N")
	)
	(segment
		(start 14.8209 20.9169)
		(end 14.334236 20.430236)
		(width 0.110185)
		(layer "In3.Cu")
		(net "NFP_PCIE0_PER2_N")
	)
	(segment
		(start 14.334236 20.430236)
		(end 14.334236 19.828764)
		(width 0.110185)
		(layer "In3.Cu")
		(net "NFP_PCIE0_PER2_N")
	)
	(segment
		(start 13.593623 -0.44323)
		(end 13.849655 -0.187198)
		(width 0.110185)
		(layer "In3.Cu")
		(net "NFP_PCIE0_PER2_N")
	)
	(segment
		(start 8.723757 13.885164)
		(end 8.466836 13.628243)
		(width 0.110185)
		(layer "In3.Cu")
		(net "NFP_PCIE0_PER2_N")
	)
	(segment
		(start 15.3924 20.9169)
		(end 14.8209 20.9169)
		(width 0.110185)
		(layer "In3.Cu")
		(net "NFP_PCIE0_PER2_N")
	)
	(segment
		(start 14.951202 14.397609)
		(end 14.438757 13.885164)
		(width 0.110185)
		(layer "In3.Cu")
		(net "NFP_PCIE0_PER2_N")
	)
	(segment
		(start 13.849655 -0.187198)
		(end 15.676778 -0.187198)
		(width 0.110185)
		(layer "In3.Cu")
		(net "NFP_PCIE0_PER2_N")
	)
	(segment
		(start 14.334236 19.828764)
		(end 14.951202 19.211798)
		(width 0.110185)
		(layer "In3.Cu")
		(net "NFP_PCIE0_PER2_N")
	)
	(segment
		(start 8.466836 12.934188)
		(end 8.088757 12.556109)
		(width 0.110185)
		(layer "In3.Cu")
		(net "NFP_PCIE0_PER2_N")
	)
	(segment
		(start 58.486802 -0.822198)
		(end 58.775092 -0.533908)
		(width 0.110185)
		(layer "In3.Cu")
		(net "NFP_PCIE0_PER2_N")
	)
	(segment
		(start 25.605537 -0.476504)
		(end 29.868063 -0.476504)
		(width 0.110185)
		(layer "In3.Cu")
		(net "NFP_PCIE0_PER2_N")
	)
	(segment
		(start 7.854823 -0.44323)
		(end 13.593623 -0.44323)
		(width 0.110185)
		(layer "In3.Cu")
		(net "NFP_PCIE0_PER2_N")
	)
	(segment
		(start 57.729222 -0.822198)
		(end 58.486802 -0.822198)
		(width 0.110185)
		(layer "In3.Cu")
		(net "NFP_PCIE0_PER2_N")
	)
	(segment
		(start 7.857134 12.556109)
		(end 6.102604 10.801579)
		(width 0.110185)
		(layer "In3.Cu")
		(net "NFP_PCIE0_PER2_N")
	)
	(segment
		(start 6.815836 1.738757)
		(end 6.815836 0.595757)
		(width 0.110185)
		(layer "In3.Cu")
		(net "NFP_PCIE0_PER2_N")
	)
	(segment
		(start 57.669024 -0.762)
		(end 57.729222 -0.822198)
		(width 0.110185)
		(layer "In3.Cu")
		(net "NFP_PCIE0_PER2_N")
	)
	(segment
		(start 25.066803 0.06223)
		(end 25.605537 -0.476504)
		(width 0.110185)
		(layer "In3.Cu")
		(net "NFP_PCIE0_PER2_N")
	)
	(segment
		(start 6.102604 10.801579)
		(end 6.102604 2.451989)
		(width 0.110185)
		(layer "In3.Cu")
		(net "NFP_PCIE0_PER2_N")
	)
	(segment
		(start 8.088757 12.556109)
		(end 7.857134 12.556109)
		(width 0.110185)
		(layer "In3.Cu")
		(net "NFP_PCIE0_PER2_N")
	)
	(segment
		(start 15.926206 0.06223)
		(end 25.066803 0.06223)
		(width 0.110185)
		(layer "In3.Cu")
		(net "NFP_PCIE0_PER2_N")
	)
	(via
		(at 60.325 0.3429)
		(size 0.508)
		(drill 0.25654)
		(layers "F.Cu" "B.Cu")
		(net "NFP_PCIE0_PER1_P")
	)
	(via
		(at 12.8524 17.1069)
		(size 0.762)
		(drill 0.254)
		(layers "F.Cu" "B.Cu")
		(net "NFP_PCIE0_PER1_P")
	)
	(segment
		(start 13.4874 17.7419)
		(end 12.8524 17.1069)
		(width 0.138633)
		(layer "B.Cu")
		(net "NFP_PCIE0_PER1_P")
	)
	(segment
		(start 25.020778 -0.90043)
		(end 25.310084 -1.189736)
		(width 0.110185)
		(layer "In3.Cu")
		(net "NFP_PCIE0_PER1_P")
	)
	(segment
		(start 12.319 16.845407)
		(end 11.898757 16.425164)
		(width 0.110185)
		(layer "In3.Cu")
		(net "NFP_PCIE0_PER1_P")
	)
	(segment
		(start 46.061757 -0.677164)
		(end 46.696757 -1.312164)
		(width 0.110185)
		(layer "In3.Cu")
		(net "NFP_PCIE0_PER1_P")
	)
	(segment
		(start 12.631395 17.973929)
		(end 12.489053 17.973929)
		(width 0.110185)
		(layer "In3.Cu")
		(net "NFP_PCIE0_PER1_P")
	)
	(segment
		(start 7.069836 15.914243)
		(end 7.069836 13.673861)
		(width 0.110185)
		(layer "In3.Cu")
		(net "NFP_PCIE0_PER1_P")
	)
	(segment
		(start 5.987034 12.099265)
		(end 5.321656 11.433886)
		(width 0.110185)
		(layer "In3.Cu")
		(net "NFP_PCIE0_PER1_P")
	)
	(segment
		(start 12.8524 17.752924)
		(end 12.631395 17.973929)
		(width 0.110185)
		(layer "In3.Cu")
		(net "NFP_PCIE0_PER1_P")
	)
	(segment
		(start 5.399583 2.160753)
		(end 5.654802 1.905533)
		(width 0.110185)
		(layer "In3.Cu")
		(net "NFP_PCIE0_PER1_P")
	)
	(segment
		(start 30.676088 -0.677164)
		(end 46.061757 -0.677164)
		(width 0.110185)
		(layer "In3.Cu")
		(net "NFP_PCIE0_PER1_P")
	)
	(segment
		(start 5.654802 1.905533)
		(end 5.654802 0.071222)
		(width 0.110185)
		(layer "In3.Cu")
		(net "NFP_PCIE0_PER1_P")
	)
	(segment
		(start 7.580757 16.425164)
		(end 7.069836 15.914243)
		(width 0.110185)
		(layer "In3.Cu")
		(net "NFP_PCIE0_PER1_P")
	)
	(segment
		(start 59.774836 -1.312164)
		(end 60.790582 -0.296418)
		(width 0.110185)
		(layer "In3.Cu")
		(net "NFP_PCIE0_PER1_P")
	)
	(segment
		(start 12.319 17.803876)
		(end 12.319 16.845407)
		(width 0.110185)
		(layer "In3.Cu")
		(net "NFP_PCIE0_PER1_P")
	)
	(segment
		(start 5.399583 2.728417)
		(end 5.399583 2.160753)
		(width 0.110185)
		(layer "In3.Cu")
		(net "NFP_PCIE0_PER1_P")
	)
	(segment
		(start 46.696757 -1.312164)
		(end 59.774836 -1.312164)
		(width 0.110185)
		(layer "In3.Cu")
		(net "NFP_PCIE0_PER1_P")
	)
	(segment
		(start 12.8524 17.1069)
		(end 12.8524 17.752924)
		(width 0.110185)
		(layer "In3.Cu")
		(net "NFP_PCIE0_PER1_P")
	)
	(segment
		(start 25.310084 -1.189736)
		(end 30.163516 -1.189736)
		(width 0.110185)
		(layer "In3.Cu")
		(net "NFP_PCIE0_PER1_P")
	)
	(segment
		(start 13.889126 -1.156462)
		(end 14.145158 -0.90043)
		(width 0.110185)
		(layer "In3.Cu")
		(net "NFP_PCIE0_PER1_P")
	)
	(segment
		(start 60.6171 0.3429)
		(end 60.325 0.3429)
		(width 0.110185)
		(layer "In3.Cu")
		(net "NFP_PCIE0_PER1_P")
	)
	(segment
		(start 60.790582 0.169418)
		(end 60.6171 0.3429)
		(width 0.110185)
		(layer "In3.Cu")
		(net "NFP_PCIE0_PER1_P")
	)
	(segment
		(start 5.654802 0.071222)
		(end 6.882486 -1.156462)
		(width 0.110185)
		(layer "In3.Cu")
		(net "NFP_PCIE0_PER1_P")
	)
	(segment
		(start 14.145158 -0.90043)
		(end 25.020778 -0.90043)
		(width 0.110185)
		(layer "In3.Cu")
		(net "NFP_PCIE0_PER1_P")
	)
	(segment
		(start 5.987034 12.591059)
		(end 5.987034 12.099265)
		(width 0.110185)
		(layer "In3.Cu")
		(net "NFP_PCIE0_PER1_P")
	)
	(segment
		(start 5.321656 11.433886)
		(end 5.321656 2.806344)
		(width 0.110185)
		(layer "In3.Cu")
		(net "NFP_PCIE0_PER1_P")
	)
	(segment
		(start 30.163516 -1.189736)
		(end 30.676088 -0.677164)
		(width 0.110185)
		(layer "In3.Cu")
		(net "NFP_PCIE0_PER1_P")
	)
	(segment
		(start 60.790582 -0.296418)
		(end 60.790582 0.169418)
		(width 0.110185)
		(layer "In3.Cu")
		(net "NFP_PCIE0_PER1_P")
	)
	(segment
		(start 12.489053 17.973929)
		(end 12.319 17.803876)
		(width 0.110185)
		(layer "In3.Cu")
		(net "NFP_PCIE0_PER1_P")
	)
	(segment
		(start 5.321656 2.806344)
		(end 5.399583 2.728417)
		(width 0.110185)
		(layer "In3.Cu")
		(net "NFP_PCIE0_PER1_P")
	)
	(segment
		(start 7.069836 13.673861)
		(end 5.987034 12.591059)
		(width 0.110185)
		(layer "In3.Cu")
		(net "NFP_PCIE0_PER1_P")
	)
	(segment
		(start 6.882486 -1.156462)
		(end 13.889126 -1.156462)
		(width 0.110185)
		(layer "In3.Cu")
		(net "NFP_PCIE0_PER1_P")
	)
	(segment
		(start 11.898757 16.425164)
		(end 7.580757 16.425164)
		(width 0.110185)
		(layer "In3.Cu")
		(net "NFP_PCIE0_PER1_P")
	)
	(via
		(at 61.214 0.3429)
		(size 0.508)
		(drill 0.25654)
		(layers "F.Cu" "B.Cu")
		(net "NFP_PCIE0_PER1_N")
	)
	(via
		(at 12.8524 18.3769)
		(size 0.762)
		(drill 0.2667)
		(layers "F.Cu" "B.Cu")
		(net "NFP_PCIE0_PER1_N")
	)
	(segment
		(start 13.4874 19.0119)
		(end 12.8524 18.3769)
		(width 0.138633)
		(layer "B.Cu")
		(net "NFP_PCIE0_PER1_N")
	)
	(segment
		(start 5.442966 -0.016535)
		(end 6.794729 -1.368298)
		(width 0.110185)
		(layer "In3.Cu")
		(net "NFP_PCIE0_PER1_N")
	)
	(segment
		(start 5.775198 12.187022)
		(end 5.10982 11.521643)
		(width 0.110185)
		(layer "In3.Cu")
		(net "NFP_PCIE0_PER1_N")
	)
	(segment
		(start 45.974 -0.889)
		(end 46.609 -1.524)
		(width 0.110185)
		(layer "In3.Cu")
		(net "NFP_PCIE0_PER1_N")
	)
	(segment
		(start 59.862593 -1.524)
		(end 61.002418 -0.384175)
		(width 0.110185)
		(layer "In3.Cu")
		(net "NFP_PCIE0_PER1_N")
	)
	(segment
		(start 5.10982 11.521643)
		(end 5.10982 2.718587)
		(width 0.110185)
		(layer "In3.Cu")
		(net "NFP_PCIE0_PER1_N")
	)
	(segment
		(start 5.10982 2.718587)
		(end 5.187747 2.64066)
		(width 0.110185)
		(layer "In3.Cu")
		(net "NFP_PCIE0_PER1_N")
	)
	(segment
		(start 61.002418 -0.384175)
		(end 61.002418 0.131318)
		(width 0.110185)
		(layer "In3.Cu")
		(net "NFP_PCIE0_PER1_N")
	)
	(segment
		(start 5.187747 2.072996)
		(end 5.442966 1.817776)
		(width 0.110185)
		(layer "In3.Cu")
		(net "NFP_PCIE0_PER1_N")
	)
	(segment
		(start 30.251273 -1.401572)
		(end 30.763845 -0.889)
		(width 0.110185)
		(layer "In3.Cu")
		(net "NFP_PCIE0_PER1_N")
	)
	(segment
		(start 5.775198 12.678816)
		(end 5.775198 12.187022)
		(width 0.110185)
		(layer "In3.Cu")
		(net "NFP_PCIE0_PER1_N")
	)
	(segment
		(start 14.232915 -1.112266)
		(end 24.933021 -1.112266)
		(width 0.110185)
		(layer "In3.Cu")
		(net "NFP_PCIE0_PER1_N")
	)
	(segment
		(start 12.401296 18.185765)
		(end 12.107164 17.891633)
		(width 0.110185)
		(layer "In3.Cu")
		(net "NFP_PCIE0_PER1_N")
	)
	(segment
		(start 25.222327 -1.401572)
		(end 30.251273 -1.401572)
		(width 0.110185)
		(layer "In3.Cu")
		(net "NFP_PCIE0_PER1_N")
	)
	(segment
		(start 12.661265 18.185765)
		(end 12.401296 18.185765)
		(width 0.110185)
		(layer "In3.Cu")
		(net "NFP_PCIE0_PER1_N")
	)
	(segment
		(start 6.858 13.761618)
		(end 5.775198 12.678816)
		(width 0.110185)
		(layer "In3.Cu")
		(net "NFP_PCIE0_PER1_N")
	)
	(segment
		(start 24.933021 -1.112266)
		(end 25.222327 -1.401572)
		(width 0.110185)
		(layer "In3.Cu")
		(net "NFP_PCIE0_PER1_N")
	)
	(segment
		(start 7.493 16.637)
		(end 6.858 16.002)
		(width 0.110185)
		(layer "In3.Cu")
		(net "NFP_PCIE0_PER1_N")
	)
	(segment
		(start 61.002418 0.131318)
		(end 61.214 0.3429)
		(width 0.110185)
		(layer "In3.Cu")
		(net "NFP_PCIE0_PER1_N")
	)
	(segment
		(start 5.442966 1.817776)
		(end 5.442966 -0.016535)
		(width 0.110185)
		(layer "In3.Cu")
		(net "NFP_PCIE0_PER1_N")
	)
	(segment
		(start 13.976883 -1.368298)
		(end 14.232915 -1.112266)
		(width 0.110185)
		(layer "In3.Cu")
		(net "NFP_PCIE0_PER1_N")
	)
	(segment
		(start 6.858 16.002)
		(end 6.858 13.761618)
		(width 0.110185)
		(layer "In3.Cu")
		(net "NFP_PCIE0_PER1_N")
	)
	(segment
		(start 12.107164 16.933164)
		(end 11.811 16.637)
		(width 0.110185)
		(layer "In3.Cu")
		(net "NFP_PCIE0_PER1_N")
	)
	(segment
		(start 30.763845 -0.889)
		(end 45.974 -0.889)
		(width 0.110185)
		(layer "In3.Cu")
		(net "NFP_PCIE0_PER1_N")
	)
	(segment
		(start 12.107164 17.891633)
		(end 12.107164 16.933164)
		(width 0.110185)
		(layer "In3.Cu")
		(net "NFP_PCIE0_PER1_N")
	)
	(segment
		(start 12.8524 18.3769)
		(end 12.661265 18.185765)
		(width 0.110185)
		(layer "In3.Cu")
		(net "NFP_PCIE0_PER1_N")
	)
	(segment
		(start 6.794729 -1.368298)
		(end 13.976883 -1.368298)
		(width 0.110185)
		(layer "In3.Cu")
		(net "NFP_PCIE0_PER1_N")
	)
	(segment
		(start 11.811 16.637)
		(end 7.493 16.637)
		(width 0.110185)
		(layer "In3.Cu")
		(net "NFP_PCIE0_PER1_N")
	)
	(segment
		(start 5.187747 2.64066)
		(end 5.187747 2.072996)
		(width 0.110185)
		(layer "In3.Cu")
		(net "NFP_PCIE0_PER1_N")
	)
	(segment
		(start 46.609 -1.524)
		(end 59.862593 -1.524)
		(width 0.110185)
		(layer "In3.Cu")
		(net "NFP_PCIE0_PER1_N")
	)
	(via
		(at 62.221999 0.3429)
		(size 0.508)
		(drill 0.25654)
		(layers "F.Cu" "B.Cu")
		(net "NFP_PCIE0_PER0_P")
	)
	(via
		(at 14.1224 14.5669)
		(size 0.762)
		(drill 0.254)
		(layers "F.Cu" "B.Cu")
		(net "NFP_PCIE0_PER0_P")
	)
	(segment
		(start 14.7574 15.2019)
		(end 14.1224 14.5669)
		(width 0.138633)
		(layer "B.Cu")
		(net "NFP_PCIE0_PER0_P")
	)
	(segment
		(start 14.393367 -1.902968)
		(end 30.458969 -1.902968)
		(width 0.110185)
		(layer "In3.Cu")
		(net "NFP_PCIE0_PER0_P")
	)
	(segment
		(start 4.064 2.559863)
		(end 4.064 0.560908)
		(width 0.110185)
		(layer "In3.Cu")
		(net "NFP_PCIE0_PER0_P")
	)
	(segment
		(start 6.061202 13.98811)
		(end 4.618634 12.545543)
		(width 0.110185)
		(layer "In3.Cu")
		(net "NFP_PCIE0_PER0_P")
	)
	(segment
		(start 13.589 15.367)
		(end 13.353796 15.602204)
		(width 0.110185)
		(layer "In3.Cu")
		(net "NFP_PCIE0_PER0_P")
	)
	(segment
		(start 13.015544 18.923)
		(end 7.492975 18.923)
		(width 0.110185)
		(layer "In3.Cu")
		(net "NFP_PCIE0_PER0_P")
	)
	(segment
		(start 6.494602 -1.869694)
		(end 14.360093 -1.869694)
		(width 0.110185)
		(layer "In3.Cu")
		(net "NFP_PCIE0_PER0_P")
	)
	(segment
		(start 14.1224 14.5669)
		(end 14.1224 15.2146)
		(width 0.110185)
		(layer "In3.Cu")
		(net "NFP_PCIE0_PER0_P")
	)
	(segment
		(start 62.907164 -0.211836)
		(end 62.907164 -0.042139)
		(width 0.110185)
		(layer "In3.Cu")
		(net "NFP_PCIE0_PER0_P")
	)
	(segment
		(start 7.492975 18.923)
		(end 6.061202 17.491227)
		(width 0.110185)
		(layer "In3.Cu")
		(net "NFP_PCIE0_PER0_P")
	)
	(segment
		(start 45.72 -1.397)
		(end 46.225968 -1.902968)
		(width 0.110185)
		(layer "In3.Cu")
		(net "NFP_PCIE0_PER0_P")
	)
	(segment
		(start 62.907164 -0.042139)
		(end 62.522125 0.3429)
		(width 0.110185)
		(layer "In3.Cu")
		(net "NFP_PCIE0_PER0_P")
	)
	(segment
		(start 46.225968 -1.902968)
		(end 61.216032 -1.902968)
		(width 0.110185)
		(layer "In3.Cu")
		(net "NFP_PCIE0_PER0_P")
	)
	(segment
		(start 13.97 15.367)
		(end 13.589 15.367)
		(width 0.110185)
		(layer "In3.Cu")
		(net "NFP_PCIE0_PER0_P")
	)
	(segment
		(start 30.458969 -1.902968)
		(end 30.964937 -1.397)
		(width 0.110185)
		(layer "In3.Cu")
		(net "NFP_PCIE0_PER0_P")
	)
	(segment
		(start 14.1224 15.2146)
		(end 13.97 15.367)
		(width 0.110185)
		(layer "In3.Cu")
		(net "NFP_PCIE0_PER0_P")
	)
	(segment
		(start 30.964937 -1.397)
		(end 45.72 -1.397)
		(width 0.110185)
		(layer "In3.Cu")
		(net "NFP_PCIE0_PER0_P")
	)
	(segment
		(start 61.216032 -1.902968)
		(end 62.907164 -0.211836)
		(width 0.110185)
		(layer "In3.Cu")
		(net "NFP_PCIE0_PER0_P")
	)
	(segment
		(start 4.618634 3.114497)
		(end 4.064 2.559863)
		(width 0.110185)
		(layer "In3.Cu")
		(net "NFP_PCIE0_PER0_P")
	)
	(segment
		(start 4.618634 12.545543)
		(end 4.618634 3.114497)
		(width 0.110185)
		(layer "In3.Cu")
		(net "NFP_PCIE0_PER0_P")
	)
	(segment
		(start 14.360093 -1.869694)
		(end 14.393367 -1.902968)
		(width 0.110185)
		(layer "In3.Cu")
		(net "NFP_PCIE0_PER0_P")
	)
	(segment
		(start 13.353796 15.602204)
		(end 13.353796 18.584748)
		(width 0.110185)
		(layer "In3.Cu")
		(net "NFP_PCIE0_PER0_P")
	)
	(segment
		(start 62.522125 0.3429)
		(end 62.221999 0.3429)
		(width 0.110185)
		(layer "In3.Cu")
		(net "NFP_PCIE0_PER0_P")
	)
	(segment
		(start 6.061202 17.491227)
		(end 6.061202 13.98811)
		(width 0.110185)
		(layer "In3.Cu")
		(net "NFP_PCIE0_PER0_P")
	)
	(segment
		(start 4.064 0.560908)
		(end 6.494602 -1.869694)
		(width 0.110185)
		(layer "In3.Cu")
		(net "NFP_PCIE0_PER0_P")
	)
	(segment
		(start 13.353796 18.584748)
		(end 13.015544 18.923)
		(width 0.110185)
		(layer "In3.Cu")
		(net "NFP_PCIE0_PER0_P")
	)
	(via
		(at 14.1224 15.8369)
		(size 0.762)
		(drill 0.2667)
		(layers "F.Cu" "B.Cu")
		(net "NFP_PCIE0_PER0_N")
	)
	(via
		(at 63.213996 0.3429)
		(size 0.508)
		(drill 0.25654)
		(layers "F.Cu" "B.Cu")
		(net "NFP_PCIE0_PER0_N")
	)
	(segment
		(start 14.7574 16.4719)
		(end 14.1224 15.8369)
		(width 0.138633)
		(layer "B.Cu")
		(net "NFP_PCIE0_PER0_N")
	)
	(segment
		(start 14.1224 15.8369)
		(end 14.1224 15.731236)
		(width 0.110185)
		(layer "In3.Cu")
		(net "NFP_PCIE0_PER0_N")
	)
	(segment
		(start 14.272336 -2.08153)
		(end 14.30561 -2.114804)
		(width 0.110185)
		(layer "In3.Cu")
		(net "NFP_PCIE0_PER0_N")
	)
	(segment
		(start 13.97 15.578836)
		(end 13.676757 15.578836)
		(width 0.110185)
		(layer "In3.Cu")
		(net "NFP_PCIE0_PER0_N")
	)
	(segment
		(start 6.406845 -2.08153)
		(end 14.272336 -2.08153)
		(width 0.110185)
		(layer "In3.Cu")
		(net "NFP_PCIE0_PER0_N")
	)
	(segment
		(start 13.565632 18.672505)
		(end 13.103301 19.134836)
		(width 0.110185)
		(layer "In3.Cu")
		(net "NFP_PCIE0_PER0_N")
	)
	(segment
		(start 4.406798 3.202254)
		(end 3.852164 2.64762)
		(width 0.110185)
		(layer "In3.Cu")
		(net "NFP_PCIE0_PER0_N")
	)
	(segment
		(start 30.546726 -2.114804)
		(end 31.052694 -1.608836)
		(width 0.110185)
		(layer "In3.Cu")
		(net "NFP_PCIE0_PER0_N")
	)
	(segment
		(start 5.849366 14.075867)
		(end 4.406798 12.6333)
		(width 0.110185)
		(layer "In3.Cu")
		(net "NFP_PCIE0_PER0_N")
	)
	(segment
		(start 31.052694 -1.608836)
		(end 45.632243 -1.608836)
		(width 0.110185)
		(layer "In3.Cu")
		(net "NFP_PCIE0_PER0_N")
	)
	(segment
		(start 61.303789 -2.114804)
		(end 63.119 -0.299593)
		(width 0.110185)
		(layer "In3.Cu")
		(net "NFP_PCIE0_PER0_N")
	)
	(segment
		(start 14.30561 -2.114804)
		(end 30.546726 -2.114804)
		(width 0.110185)
		(layer "In3.Cu")
		(net "NFP_PCIE0_PER0_N")
	)
	(segment
		(start 63.119 0.247904)
		(end 63.213996 0.3429)
		(width 0.110185)
		(layer "In3.Cu")
		(net "NFP_PCIE0_PER0_N")
	)
	(segment
		(start 13.103301 19.134836)
		(end 7.405218 19.134836)
		(width 0.110185)
		(layer "In3.Cu")
		(net "NFP_PCIE0_PER0_N")
	)
	(segment
		(start 63.119 -0.299593)
		(end 63.119 0.247904)
		(width 0.110185)
		(layer "In3.Cu")
		(net "NFP_PCIE0_PER0_N")
	)
	(segment
		(start 14.1224 15.731236)
		(end 13.97 15.578836)
		(width 0.110185)
		(layer "In3.Cu")
		(net "NFP_PCIE0_PER0_N")
	)
	(segment
		(start 7.405218 19.134836)
		(end 5.849366 17.578984)
		(width 0.110185)
		(layer "In3.Cu")
		(net "NFP_PCIE0_PER0_N")
	)
	(segment
		(start 3.852164 2.64762)
		(end 3.852164 0.473151)
		(width 0.110185)
		(layer "In3.Cu")
		(net "NFP_PCIE0_PER0_N")
	)
	(segment
		(start 45.632243 -1.608836)
		(end 46.138211 -2.114804)
		(width 0.110185)
		(layer "In3.Cu")
		(net "NFP_PCIE0_PER0_N")
	)
	(segment
		(start 13.565632 15.689961)
		(end 13.565632 18.672505)
		(width 0.110185)
		(layer "In3.Cu")
		(net "NFP_PCIE0_PER0_N")
	)
	(segment
		(start 5.849366 17.578984)
		(end 5.849366 14.075867)
		(width 0.110185)
		(layer "In3.Cu")
		(net "NFP_PCIE0_PER0_N")
	)
	(segment
		(start 4.406798 12.6333)
		(end 4.406798 3.202254)
		(width 0.110185)
		(layer "In3.Cu")
		(net "NFP_PCIE0_PER0_N")
	)
	(segment
		(start 13.676757 15.578836)
		(end 13.565632 15.689961)
		(width 0.110185)
		(layer "In3.Cu")
		(net "NFP_PCIE0_PER0_N")
	)
	(segment
		(start 46.138211 -2.114804)
		(end 61.303789 -2.114804)
		(width 0.110185)
		(layer "In3.Cu")
		(net "NFP_PCIE0_PER0_N")
	)
	(segment
		(start 3.852164 0.473151)
		(end 6.406845 -2.08153)
		(width 0.110185)
		(layer "In3.Cu")
		(net "NFP_PCIE0_PER0_N")
	)
	(segment
		(start 41.237002 8.041996)
		(end 40.737003 7.541997)
		(width 0.13208)
		(layer "F.Cu")
		(net "NFP_CORE_VID7")
	)
	(via
		(at 37.1221 33.274)
		(size 0.508)
		(drill 0.25654)
		(layers "F.Cu" "B.Cu")
		(net "NFP_CORE_VID7")
	)
	(via
		(at 40.737003 7.541997)
		(size 0.4826)
		(drill 0.20574)
		(layers "F.Cu" "B.Cu")
		(net "NFP_CORE_VID7")
	)
	(via
		(at 37.719 34.544)
		(size 0.762)
		(drill 0.381)
		(layers "F.Cu" "B.Cu")
		(net "NFP_CORE_VID7")
	)
	(segment
		(start 37.1221 33.274)
		(end 37.1221 33.9471)
		(width 0.14732)
		(layer "B.Cu")
		(net "NFP_CORE_VID7")
	)
	(segment
		(start 37.1221 33.9471)
		(end 37.719 34.544)
		(width 0.14732)
		(layer "B.Cu")
		(net "NFP_CORE_VID7")
	)
	(segment
		(start 37.910821 25.161875)
		(end 38.354 25.605054)
		(width 0.12065)
		(layer "In7.Cu")
		(net "NFP_CORE_VID7")
	)
	(segment
		(start 36.667059 24.268354)
		(end 37.56058 25.161875)
		(width 0.12065)
		(layer "In7.Cu")
		(net "NFP_CORE_VID7")
	)
	(segment
		(start 37.592 19.057036)
		(end 37.584482 19.064554)
		(width 0.12065)
		(layer "In7.Cu")
		(net "NFP_CORE_VID7")
	)
	(segment
		(start 37.56058 25.161875)
		(end 37.910821 25.161875)
		(width 0.12065)
		(layer "In7.Cu")
		(net "NFP_CORE_VID7")
	)
	(segment
		(start 38.354 25.605054)
		(end 38.354 31.877)
		(width 0.12065)
		(layer "In7.Cu")
		(net "NFP_CORE_VID7")
	)
	(segment
		(start 38.333782 10.374935)
		(end 38.333782 18.308218)
		(width 0.12065)
		(layer "In7.Cu")
		(net "NFP_CORE_VID7")
	)
	(segment
		(start 38.883234 10.138766)
		(end 38.569951 10.138766)
		(width 0.12065)
		(layer "In7.Cu")
		(net "NFP_CORE_VID7")
	)
	(segment
		(start 40.737003 7.541997)
		(end 40.737003 8.284997)
		(width 0.12065)
		(layer "In7.Cu")
		(net "NFP_CORE_VID7")
	)
	(segment
		(start 37.592 19.05)
		(end 37.592 19.057036)
		(width 0.12065)
		(layer "In7.Cu")
		(net "NFP_CORE_VID7")
	)
	(segment
		(start 36.667059 23.495)
		(end 36.667059 24.268354)
		(width 0.12065)
		(layer "In7.Cu")
		(net "NFP_CORE_VID7")
	)
	(segment
		(start 38.354 31.877)
		(end 37.846 32.385)
		(width 0.12065)
		(layer "In7.Cu")
		(net "NFP_CORE_VID7")
	)
	(segment
		(start 37.584482 19.064554)
		(end 37.584482 22.577577)
		(width 0.12065)
		(layer "In7.Cu")
		(net "NFP_CORE_VID7")
	)
	(segment
		(start 37.584482 22.577577)
		(end 36.667059 23.495)
		(width 0.12065)
		(layer "In7.Cu")
		(net "NFP_CORE_VID7")
	)
	(segment
		(start 40.737003 8.284997)
		(end 38.883234 10.138766)
		(width 0.12065)
		(layer "In7.Cu")
		(net "NFP_CORE_VID7")
	)
	(segment
		(start 37.846 32.385)
		(end 37.846 32.5501)
		(width 0.12065)
		(layer "In7.Cu")
		(net "NFP_CORE_VID7")
	)
	(segment
		(start 37.846 32.5501)
		(end 37.1221 33.274)
		(width 0.12065)
		(layer "In7.Cu")
		(net "NFP_CORE_VID7")
	)
	(segment
		(start 38.333782 18.308218)
		(end 37.592 19.05)
		(width 0.12065)
		(layer "In7.Cu")
		(net "NFP_CORE_VID7")
	)
	(segment
		(start 38.569951 10.138766)
		(end 38.333782 10.374935)
		(width 0.12065)
		(layer "In7.Cu")
		(net "NFP_CORE_VID7")
	)
	(segment
		(start 39.237006 9.041994)
		(end 38.737007 8.541995)
		(width 0.13208)
		(layer "F.Cu")
		(net "NFP_CORE_VID6")
	)
	(via
		(at 35.433 31.242)
		(size 0.508)
		(drill 0.2667)
		(layers "F.Cu" "B.Cu")
		(net "NFP_CORE_VID6")
	)
	(via
		(at 38.737007 8.541995)
		(size 0.4826)
		(drill 0.20574)
		(layers "F.Cu" "B.Cu")
		(net "NFP_CORE_VID6")
	)
	(segment
		(start 34.671 32.0929)
		(end 34.544 32.2199)
		(width 0.14732)
		(layer "B.Cu")
		(net "NFP_CORE_VID6")
	)
	(segment
		(start 34.671 32.012026)
		(end 34.671 32.0929)
		(width 0.14732)
		(layer "B.Cu")
		(net "NFP_CORE_VID6")
	)
	(segment
		(start 35.433 31.242)
		(end 34.99866 31.67634)
		(width 0.14732)
		(layer "B.Cu")
		(net "NFP_CORE_VID6")
	)
	(segment
		(start 34.99866 31.67634)
		(end 34.99866 31.684366)
		(width 0.14732)
		(layer "B.Cu")
		(net "NFP_CORE_VID6")
	)
	(segment
		(start 34.99866 31.684366)
		(end 34.671 32.012026)
		(width 0.14732)
		(layer "B.Cu")
		(net "NFP_CORE_VID6")
	)
	(segment
		(start 34.732341 23.814684)
		(end 35.052 23.495025)
		(width 0.12065)
		(layer "In7.Cu")
		(net "NFP_CORE_VID6")
	)
	(segment
		(start 35.905059 22.514941)
		(end 36.433404 22.514941)
		(width 0.12065)
		(layer "In7.Cu")
		(net "NFP_CORE_VID6")
	)
	(segment
		(start 35.433 30.734)
		(end 35.625253 30.541747)
		(width 0.12065)
		(layer "In7.Cu")
		(net "NFP_CORE_VID6")
	)
	(segment
		(start 34.732341 28.763316)
		(end 34.732341 23.814684)
		(width 0.12065)
		(layer "In7.Cu")
		(net "NFP_CORE_VID6")
	)
	(segment
		(start 35.625253 29.656227)
		(end 34.732341 28.763316)
		(width 0.12065)
		(layer "In7.Cu")
		(net "NFP_CORE_VID6")
	)
	(segment
		(start 35.052 23.495025)
		(end 35.052 23.368)
		(width 0.12065)
		(layer "In7.Cu")
		(net "NFP_CORE_VID6")
	)
	(segment
		(start 38.227 10.131476)
		(end 38.227 9.052001)
		(width 0.12065)
		(layer "In7.Cu")
		(net "NFP_CORE_VID6")
	)
	(segment
		(start 36.433404 22.514941)
		(end 36.703 22.245345)
		(width 0.12065)
		(layer "In7.Cu")
		(net "NFP_CORE_VID6")
	)
	(segment
		(start 35.052 23.368)
		(end 35.905059 22.514941)
		(width 0.12065)
		(layer "In7.Cu")
		(net "NFP_CORE_VID6")
	)
	(segment
		(start 36.703 22.245345)
		(end 36.703 18.655132)
		(width 0.12065)
		(layer "In7.Cu")
		(net "NFP_CORE_VID6")
	)
	(segment
		(start 36.703 18.655132)
		(end 38.086132 17.272)
		(width 0.12065)
		(layer "In7.Cu")
		(net "NFP_CORE_VID6")
	)
	(segment
		(start 35.625253 30.541747)
		(end 35.625253 29.656227)
		(width 0.12065)
		(layer "In7.Cu")
		(net "NFP_CORE_VID6")
	)
	(segment
		(start 38.227 9.052001)
		(end 38.737007 8.541995)
		(width 0.12065)
		(layer "In7.Cu")
		(net "NFP_CORE_VID6")
	)
	(segment
		(start 38.086132 17.272)
		(end 38.086132 10.272344)
		(width 0.12065)
		(layer "In7.Cu")
		(net "NFP_CORE_VID6")
	)
	(segment
		(start 35.433 31.242)
		(end 35.433 30.734)
		(width 0.12065)
		(layer "In7.Cu")
		(net "NFP_CORE_VID6")
	)
	(segment
		(start 38.086132 10.272344)
		(end 38.227 10.131476)
		(width 0.12065)
		(layer "In7.Cu")
		(net "NFP_CORE_VID6")
	)
	(segment
		(start 40.237004 7.041998)
		(end 39.737005 6.541999)
		(width 0.13208)
		(layer "F.Cu")
		(net "NFP_CORE_VID5")
	)
	(via
		(at 33.655 31.496)
		(size 0.508)
		(drill 0.254)
		(layers "F.Cu" "B.Cu")
		(net "NFP_CORE_VID5")
	)
	(via
		(at 39.737005 6.541999)
		(size 0.4826)
		(drill 0.25654)
		(layers "F.Cu" "B.Cu")
		(net "NFP_CORE_VID5")
	)
	(segment
		(start 33.655 32.2199)
		(end 33.655 31.496)
		(width 0.14732)
		(layer "B.Cu")
		(net "NFP_CORE_VID5")
	)
	(segment
		(start 36.901171 10.480675)
		(end 36.515675 10.866171)
		(width 0.12065)
		(layer "In7.Cu")
		(net "NFP_CORE_VID5")
	)
	(segment
		(start 37.772975 9.725025)
		(end 37.017325 10.480675)
		(width 0.12065)
		(layer "In7.Cu")
		(net "NFP_CORE_VID5")
	)
	(segment
		(start 39.33378 6.945224)
		(end 39.33378 7.52922)
		(width 0.12065)
		(layer "In7.Cu")
		(net "NFP_CORE_VID5")
	)
	(segment
		(start 33.111059 30.952059)
		(end 33.655 31.496)
		(width 0.12065)
		(layer "In7.Cu")
		(net "NFP_CORE_VID5")
	)
	(segment
		(start 37.772975 8.709025)
		(end 37.772975 9.725025)
		(width 0.12065)
		(layer "In7.Cu")
		(net "NFP_CORE_VID5")
	)
	(segment
		(start 38.862 8.001)
		(end 38.481 8.001)
		(width 0.12065)
		(layer "In7.Cu")
		(net "NFP_CORE_VID5")
	)
	(segment
		(start 34.046541 20.503286)
		(end 34.046541 22.087459)
		(width 0.12065)
		(layer "In7.Cu")
		(net "NFP_CORE_VID5")
	)
	(segment
		(start 32.755459 24.638)
		(end 33.009459 24.892)
		(width 0.12065)
		(layer "In7.Cu")
		(net "NFP_CORE_VID5")
	)
	(segment
		(start 36.515675 10.866171)
		(end 36.515675 16.443325)
		(width 0.12065)
		(layer "In7.Cu")
		(net "NFP_CORE_VID5")
	)
	(segment
		(start 34.000059 20.456804)
		(end 34.046541 20.503286)
		(width 0.12065)
		(layer "In7.Cu")
		(net "NFP_CORE_VID5")
	)
	(segment
		(start 37.017325 10.480675)
		(end 36.901171 10.480675)
		(width 0.12065)
		(layer "In7.Cu")
		(net "NFP_CORE_VID5")
	)
	(segment
		(start 39.737005 6.541999)
		(end 39.33378 6.945224)
		(width 0.12065)
		(layer "In7.Cu")
		(net "NFP_CORE_VID5")
	)
	(segment
		(start 33.655 25.146)
		(end 33.655 28.956)
		(width 0.12065)
		(layer "In7.Cu")
		(net "NFP_CORE_VID5")
	)
	(segment
		(start 33.009459 24.892)
		(end 33.401 24.892)
		(width 0.12065)
		(layer "In7.Cu")
		(net "NFP_CORE_VID5")
	)
	(segment
		(start 34.046541 22.087459)
		(end 32.755459 23.378541)
		(width 0.12065)
		(layer "In7.Cu")
		(net "NFP_CORE_VID5")
	)
	(segment
		(start 33.401 24.892)
		(end 33.655 25.146)
		(width 0.12065)
		(layer "In7.Cu")
		(net "NFP_CORE_VID5")
	)
	(segment
		(start 32.755459 23.378541)
		(end 32.755459 24.638)
		(width 0.12065)
		(layer "In7.Cu")
		(net "NFP_CORE_VID5")
	)
	(segment
		(start 34.000059 18.958941)
		(end 34.000059 20.456804)
		(width 0.12065)
		(layer "In7.Cu")
		(net "NFP_CORE_VID5")
	)
	(segment
		(start 39.33378 7.52922)
		(end 38.862 8.001)
		(width 0.12065)
		(layer "In7.Cu")
		(net "NFP_CORE_VID5")
	)
	(segment
		(start 36.515675 16.443325)
		(end 34.000059 18.958941)
		(width 0.12065)
		(layer "In7.Cu")
		(net "NFP_CORE_VID5")
	)
	(segment
		(start 33.655 28.956)
		(end 33.111059 29.499941)
		(width 0.12065)
		(layer "In7.Cu")
		(net "NFP_CORE_VID5")
	)
	(segment
		(start 38.481 8.001)
		(end 37.772975 8.709025)
		(width 0.12065)
		(layer "In7.Cu")
		(net "NFP_CORE_VID5")
	)
	(segment
		(start 33.111059 29.499941)
		(end 33.111059 30.952059)
		(width 0.12065)
		(layer "In7.Cu")
		(net "NFP_CORE_VID5")
	)
	(segment
		(start 39.237006 8.041996)
		(end 38.737007 7.541997)
		(width 0.13208)
		(layer "F.Cu")
		(net "NFP_CORE_VID4")
	)
	(via
		(at 38.737007 7.541997)
		(size 0.4826)
		(drill 0.20574)
		(layers "F.Cu" "B.Cu")
		(net "NFP_CORE_VID4")
	)
	(via
		(at 32.766 31.242)
		(size 0.762)
		(drill 0.2667)
		(layers "F.Cu" "B.Cu")
		(net "NFP_CORE_VID4")
	)
	(segment
		(start 32.766 31.242)
		(end 32.33166 31.67634)
		(width 0.14732)
		(layer "B.Cu")
		(net "NFP_CORE_VID4")
	)
	(segment
		(start 32.33166 31.67634)
		(end 32.33166 31.76524)
		(width 0.14732)
		(layer "B.Cu")
		(net "NFP_CORE_VID4")
	)
	(segment
		(start 32.33166 31.76524)
		(end 31.877 32.2199)
		(width 0.14732)
		(layer "B.Cu")
		(net "NFP_CORE_VID4")
	)
	(segment
		(start 33.419059 26.307059)
		(end 32.725741 25.613741)
		(width 0.12065)
		(layer "In7.Cu")
		(net "NFP_CORE_VID4")
	)
	(segment
		(start 37.0237 9.077325)
		(end 37.266829 9.077325)
		(width 0.12065)
		(layer "In7.Cu")
		(net "NFP_CORE_VID4")
	)
	(segment
		(start 38.431978 7.541997)
		(end 38.737007 7.541997)
		(width 0.12065)
		(layer "In7.Cu")
		(net "NFP_CORE_VID4")
	)
	(segment
		(start 33.187259 19.263741)
		(end 36.195 16.256)
		(width 0.12065)
		(layer "In7.Cu")
		(net "NFP_CORE_VID4")
	)
	(segment
		(start 32.725741 25.110796)
		(end 32.466686 24.851741)
		(width 0.12065)
		(layer "In7.Cu")
		(net "NFP_CORE_VID4")
	)
	(segment
		(start 37.525325 8.44865)
		(end 38.431978 7.541997)
		(width 0.12065)
		(layer "In7.Cu")
		(net "NFP_CORE_VID4")
	)
	(segment
		(start 36.195 16.256)
		(end 36.195 15.197099)
		(width 0.12065)
		(layer "In7.Cu")
		(net "NFP_CORE_VID4")
	)
	(segment
		(start 32.171996 24.851741)
		(end 31.912941 24.592686)
		(width 0.12065)
		(layer "In7.Cu")
		(net "NFP_CORE_VID4")
	)
	(segment
		(start 33.274 27.559)
		(end 33.419059 27.413941)
		(width 0.12065)
		(layer "In7.Cu")
		(net "NFP_CORE_VID4")
	)
	(segment
		(start 32.298259 29.905604)
		(end 32.298259 29.550741)
		(width 0.12065)
		(layer "In7.Cu")
		(net "NFP_CORE_VID4")
	)
	(segment
		(start 33.419059 27.413941)
		(end 33.419059 26.307059)
		(width 0.12065)
		(layer "In7.Cu")
		(net "NFP_CORE_VID4")
	)
	(segment
		(start 33.187259 20.456804)
		(end 33.187259 19.263741)
		(width 0.12065)
		(layer "In7.Cu")
		(net "NFP_CORE_VID4")
	)
	(segment
		(start 31.912941 24.592686)
		(end 31.912941 22.697059)
		(width 0.12065)
		(layer "In7.Cu")
		(net "NFP_CORE_VID4")
	)
	(segment
		(start 36.195 9.906025)
		(end 37.0237 9.077325)
		(width 0.12065)
		(layer "In7.Cu")
		(net "NFP_CORE_VID4")
	)
	(segment
		(start 32.766 31.242)
		(end 32.766 30.373345)
		(width 0.12065)
		(layer "In7.Cu")
		(net "NFP_CORE_VID4")
	)
	(segment
		(start 32.725741 25.613741)
		(end 32.725741 25.110796)
		(width 0.12065)
		(layer "In7.Cu")
		(net "NFP_CORE_VID4")
	)
	(segment
		(start 32.466686 24.851741)
		(end 32.171996 24.851741)
		(width 0.12065)
		(layer "In7.Cu")
		(net "NFP_CORE_VID4")
	)
	(segment
		(start 33.263459 21.346541)
		(end 33.263459 20.533004)
		(width 0.12065)
		(layer "In7.Cu")
		(net "NFP_CORE_VID4")
	)
	(segment
		(start 36.195 14.470253)
		(end 36.195 9.906025)
		(width 0.12065)
		(layer "In7.Cu")
		(net "NFP_CORE_VID4")
	)
	(segment
		(start 36.195 15.197099)
		(end 36.207344 15.135047)
		(width 0.12065)
		(layer "In7.Cu")
		(net "NFP_CORE_VID4")
	)
	(segment
		(start 37.266829 9.077325)
		(end 37.525325 8.818829)
		(width 0.12065)
		(layer "In7.Cu")
		(net "NFP_CORE_VID4")
	)
	(segment
		(start 32.298259 29.550741)
		(end 33.274 28.575)
		(width 0.12065)
		(layer "In7.Cu")
		(net "NFP_CORE_VID4")
	)
	(segment
		(start 33.263459 20.533004)
		(end 33.187259 20.456804)
		(width 0.12065)
		(layer "In7.Cu")
		(net "NFP_CORE_VID4")
	)
	(segment
		(start 37.525325 8.818829)
		(end 37.525325 8.44865)
		(width 0.12065)
		(layer "In7.Cu")
		(net "NFP_CORE_VID4")
	)
	(segment
		(start 36.207344 15.135047)
		(end 36.207344 14.532229)
		(width 0.12065)
		(layer "In7.Cu")
		(net "NFP_CORE_VID4")
	)
	(segment
		(start 33.274 28.575)
		(end 33.274 27.559)
		(width 0.12065)
		(layer "In7.Cu")
		(net "NFP_CORE_VID4")
	)
	(segment
		(start 36.207344 14.532229)
		(end 36.195 14.470253)
		(width 0.12065)
		(layer "In7.Cu")
		(net "NFP_CORE_VID4")
	)
	(segment
		(start 31.912941 22.697059)
		(end 33.263459 21.346541)
		(width 0.12065)
		(layer "In7.Cu")
		(net "NFP_CORE_VID4")
	)
	(segment
		(start 32.766 30.373345)
		(end 32.298259 29.905604)
		(width 0.12065)
		(layer "In7.Cu")
		(net "NFP_CORE_VID4")
	)
	(segment
		(start 39.237006 6.042)
		(end 38.737007 5.542001)
		(width 0.13208)
		(layer "F.Cu")
		(net "NFP_CORE_VID3")
	)
	(via
		(at 30.988 31.496)
		(size 0.508)
		(drill 0.254)
		(layers "F.Cu" "B.Cu")
		(net "NFP_CORE_VID3")
	)
	(via
		(at 38.737007 5.542001)
		(size 0.4826)
		(drill 0.25654)
		(layers "F.Cu" "B.Cu")
		(net "NFP_CORE_VID3")
	)
	(segment
		(start 30.988 32.2199)
		(end 30.988 31.496)
		(width 0.14732)
		(layer "B.Cu")
		(net "NFP_CORE_VID3")
	)
	(segment
		(start 32.374459 20.456804)
		(end 32.374459 19.928459)
		(width 0.12065)
		(layer "In7.Cu")
		(net "NFP_CORE_VID3")
	)
	(segment
		(start 29.718 17.272)
		(end 29.718 14.975154)
		(width 0.12065)
		(layer "In7.Cu")
		(net "NFP_CORE_VID3")
	)
	(segment
		(start 31.495949 24.637949)
		(end 31.495949 24.175695)
		(width 0.12065)
		(layer "In7.Cu")
		(net "NFP_CORE_VID3")
	)
	(segment
		(start 30.988 31.496)
		(end 30.648275 31.156275)
		(width 0.12065)
		(layer "In7.Cu")
		(net "NFP_CORE_VID3")
	)
	(segment
		(start 30.648275 30.383886)
		(end 30.891886 30.140275)
		(width 0.12065)
		(layer "In7.Cu")
		(net "NFP_CORE_VID3")
	)
	(segment
		(start 32.247459 25.770459)
		(end 31.912941 25.435941)
		(width 0.12065)
		(layer "In7.Cu")
		(net "NFP_CORE_VID3")
	)
	(segment
		(start 34.808846 9.144)
		(end 36.068 9.144)
		(width 0.12065)
		(layer "In7.Cu")
		(net "NFP_CORE_VID3")
	)
	(segment
		(start 31.912941 25.054941)
		(end 31.495949 24.637949)
		(width 0.12065)
		(layer "In7.Cu")
		(net "NFP_CORE_VID3")
	)
	(segment
		(start 32.635977 26.666977)
		(end 32.247459 26.278459)
		(width 0.12065)
		(layer "In7.Cu")
		(net "NFP_CORE_VID3")
	)
	(segment
		(start 32.635977 26.972743)
		(end 32.635977 26.666977)
		(width 0.12065)
		(layer "In7.Cu")
		(net "NFP_CORE_VID3")
	)
	(segment
		(start 36.913871 7.038975)
		(end 38.808025 7.038975)
		(width 0.12065)
		(layer "In7.Cu")
		(net "NFP_CORE_VID3")
	)
	(segment
		(start 39.140232 6.709054)
		(end 39.140232 6.706768)
		(width 0.12065)
		(layer "In7.Cu")
		(net "NFP_CORE_VID3")
	)
	(segment
		(start 31.485459 29.474541)
		(end 32.639 28.321)
		(width 0.12065)
		(layer "In7.Cu")
		(net "NFP_CORE_VID3")
	)
	(segment
		(start 31.22107 30.140275)
		(end 31.485459 29.875886)
		(width 0.12065)
		(layer "In7.Cu")
		(net "NFP_CORE_VID3")
	)
	(segment
		(start 29.778325 14.914829)
		(end 29.778325 13.666521)
		(width 0.12065)
		(layer "In7.Cu")
		(net "NFP_CORE_VID3")
	)
	(segment
		(start 30.891886 30.140275)
		(end 31.22107 30.140275)
		(width 0.12065)
		(layer "In7.Cu")
		(net "NFP_CORE_VID3")
	)
	(segment
		(start 39.243 6.604)
		(end 39.243 6.35)
		(width 0.12065)
		(layer "In7.Cu")
		(net "NFP_CORE_VID3")
	)
	(segment
		(start 31.495949 24.175695)
		(end 31.115 23.794745)
		(width 0.12065)
		(layer "In7.Cu")
		(net "NFP_CORE_VID3")
	)
	(segment
		(start 36.517936 7.43491)
		(end 36.913871 7.038975)
		(width 0.12065)
		(layer "In7.Cu")
		(net "NFP_CORE_VID3")
	)
	(segment
		(start 32.385 20.467345)
		(end 32.374459 20.456804)
		(width 0.12065)
		(layer "In7.Cu")
		(net "NFP_CORE_VID3")
	)
	(segment
		(start 31.115 23.794745)
		(end 31.115 22.606)
		(width 0.12065)
		(layer "In7.Cu")
		(net "NFP_CORE_VID3")
	)
	(segment
		(start 36.068 9.144)
		(end 36.517936 8.694064)
		(width 0.12065)
		(layer "In7.Cu")
		(net "NFP_CORE_VID3")
	)
	(segment
		(start 32.639 26.975765)
		(end 32.635977 26.972743)
		(width 0.12065)
		(layer "In7.Cu")
		(net "NFP_CORE_VID3")
	)
	(segment
		(start 39.243 6.35)
		(end 38.737007 5.844007)
		(width 0.12065)
		(layer "In7.Cu")
		(net "NFP_CORE_VID3")
	)
	(segment
		(start 38.808025 7.038975)
		(end 38.901776 6.945224)
		(width 0.12065)
		(layer "In7.Cu")
		(net "NFP_CORE_VID3")
	)
	(segment
		(start 30.648275 31.156275)
		(end 30.648275 30.383886)
		(width 0.12065)
		(layer "In7.Cu")
		(net "NFP_CORE_VID3")
	)
	(segment
		(start 38.737007 5.844007)
		(end 38.737007 5.542001)
		(width 0.12065)
		(layer "In7.Cu")
		(net "NFP_CORE_VID3")
	)
	(segment
		(start 33.472171 10.480675)
		(end 34.808846 9.144)
		(width 0.12065)
		(layer "In7.Cu")
		(net "NFP_CORE_VID3")
	)
	(segment
		(start 38.904062 6.945224)
		(end 39.140232 6.709054)
		(width 0.12065)
		(layer "In7.Cu")
		(net "NFP_CORE_VID3")
	)
	(segment
		(start 32.385 21.336)
		(end 32.385 20.467345)
		(width 0.12065)
		(layer "In7.Cu")
		(net "NFP_CORE_VID3")
	)
	(segment
		(start 32.964171 10.480675)
		(end 33.472171 10.480675)
		(width 0.12065)
		(layer "In7.Cu")
		(net "NFP_CORE_VID3")
	)
	(segment
		(start 32.374459 19.928459)
		(end 29.718 17.272)
		(width 0.12065)
		(layer "In7.Cu")
		(net "NFP_CORE_VID3")
	)
	(segment
		(start 38.901776 6.945224)
		(end 38.904062 6.945224)
		(width 0.12065)
		(layer "In7.Cu")
		(net "NFP_CORE_VID3")
	)
	(segment
		(start 32.639 28.321)
		(end 32.639 26.975765)
		(width 0.12065)
		(layer "In7.Cu")
		(net "NFP_CORE_VID3")
	)
	(segment
		(start 29.718 14.975154)
		(end 29.778325 14.914829)
		(width 0.12065)
		(layer "In7.Cu")
		(net "NFP_CORE_VID3")
	)
	(segment
		(start 29.778325 13.666521)
		(end 32.964171 10.480675)
		(width 0.12065)
		(layer "In7.Cu")
		(net "NFP_CORE_VID3")
	)
	(segment
		(start 31.912941 25.435941)
		(end 31.912941 25.054941)
		(width 0.12065)
		(layer "In7.Cu")
		(net "NFP_CORE_VID3")
	)
	(segment
		(start 39.140232 6.706768)
		(end 39.243 6.604)
		(width 0.12065)
		(layer "In7.Cu")
		(net "NFP_CORE_VID3")
	)
	(segment
		(start 32.247459 26.278459)
		(end 32.247459 25.770459)
		(width 0.12065)
		(layer "In7.Cu")
		(net "NFP_CORE_VID3")
	)
	(segment
		(start 36.517936 8.694064)
		(end 36.517936 7.43491)
		(width 0.12065)
		(layer "In7.Cu")
		(net "NFP_CORE_VID3")
	)
	(segment
		(start 31.115 22.606)
		(end 32.385 21.336)
		(width 0.12065)
		(layer "In7.Cu")
		(net "NFP_CORE_VID3")
	)
	(segment
		(start 31.485459 29.875886)
		(end 31.485459 29.474541)
		(width 0.12065)
		(layer "In7.Cu")
		(net "NFP_CORE_VID3")
	)
	(segment
		(start 39.237006 7.041998)
		(end 38.737007 6.541999)
		(width 0.13208)
		(layer "F.Cu")
		(net "NFP_CORE_VID2")
	)
	(via
		(at 38.737007 6.541999)
		(size 0.4826)
		(drill 0.20574)
		(layers "F.Cu" "B.Cu")
		(net "NFP_CORE_VID2")
	)
	(via
		(at 30.099 31.242)
		(size 0.762)
		(drill 0.2667)
		(layers "F.Cu" "B.Cu")
		(net "NFP_CORE_VID2")
	)
	(segment
		(start 29.66466 31.76524)
		(end 29.21 32.2199)
		(width 0.14732)
		(layer "B.Cu")
		(net "NFP_CORE_VID2")
	)
	(segment
		(start 29.66466 31.67634)
		(end 29.66466 31.76524)
		(width 0.14732)
		(layer "B.Cu")
		(net "NFP_CORE_VID2")
	)
	(segment
		(start 30.099 31.242)
		(end 29.66466 31.67634)
		(width 0.14732)
		(layer "B.Cu")
		(net "NFP_CORE_VID2")
	)
	(segment
		(start 31.582741 25.613741)
		(end 31.359196 25.613741)
		(width 0.12065)
		(layer "In7.Cu")
		(net "NFP_CORE_VID2")
	)
	(segment
		(start 31.760541 25.791541)
		(end 31.582741 25.613741)
		(width 0.12065)
		(layer "In7.Cu")
		(net "NFP_CORE_VID2")
	)
	(segment
		(start 36.769675 6.791325)
		(end 38.48768 6.791325)
		(width 0.12065)
		(layer "In7.Cu")
		(net "NFP_CORE_VID2")
	)
	(segment
		(start 31.100141 24.297996)
		(end 30.841086 24.038941)
		(width 0.12065)
		(layer "In7.Cu")
		(net "NFP_CORE_VID2")
	)
	(segment
		(start 31.561659 19.877659)
		(end 28.829 17.145)
		(width 0.12065)
		(layer "In7.Cu")
		(net "NFP_CORE_VID2")
	)
	(segment
		(start 30.099 30.48)
		(end 30.617541 29.961459)
		(width 0.12065)
		(layer "In7.Cu")
		(net "NFP_CORE_VID2")
	)
	(segment
		(start 30.617541 29.961459)
		(end 30.617541 29.453459)
		(width 0.12065)
		(layer "In7.Cu")
		(net "NFP_CORE_VID2")
	)
	(segment
		(start 30.841086 24.038941)
		(end 30.546396 24.038941)
		(width 0.12065)
		(layer "In7.Cu")
		(net "NFP_CORE_VID2")
	)
	(segment
		(start 30.546396 24.038941)
		(end 30.287341 23.779886)
		(width 0.12065)
		(layer "In7.Cu")
		(net "NFP_CORE_VID2")
	)
	(segment
		(start 31.100141 25.354686)
		(end 31.100141 24.297996)
		(width 0.12065)
		(layer "In7.Cu")
		(net "NFP_CORE_VID2")
	)
	(segment
		(start 28.829 14.097)
		(end 34.798 8.128)
		(width 0.12065)
		(layer "In7.Cu")
		(net "NFP_CORE_VID2")
	)
	(segment
		(start 30.099 31.242)
		(end 30.099 30.48)
		(width 0.12065)
		(layer "In7.Cu")
		(net "NFP_CORE_VID2")
	)
	(segment
		(start 36.068076 7.492924)
		(end 36.769675 6.791325)
		(width 0.12065)
		(layer "In7.Cu")
		(net "NFP_CORE_VID2")
	)
	(segment
		(start 30.287341 22.671659)
		(end 31.561659 21.397341)
		(width 0.12065)
		(layer "In7.Cu")
		(net "NFP_CORE_VID2")
	)
	(segment
		(start 31.561659 21.397341)
		(end 31.561659 19.877659)
		(width 0.12065)
		(layer "In7.Cu")
		(net "NFP_CORE_VID2")
	)
	(segment
		(start 31.359196 25.613741)
		(end 31.100141 25.354686)
		(width 0.12065)
		(layer "In7.Cu")
		(net "NFP_CORE_VID2")
	)
	(segment
		(start 36.068076 7.873924)
		(end 36.068076 7.492924)
		(width 0.12065)
		(layer "In7.Cu")
		(net "NFP_CORE_VID2")
	)
	(segment
		(start 30.287341 23.779886)
		(end 30.287341 22.671659)
		(width 0.12065)
		(layer "In7.Cu")
		(net "NFP_CORE_VID2")
	)
	(segment
		(start 35.814 8.128)
		(end 36.068076 7.873924)
		(width 0.12065)
		(layer "In7.Cu")
		(net "NFP_CORE_VID2")
	)
	(segment
		(start 34.798 8.128)
		(end 35.814 8.128)
		(width 0.12065)
		(layer "In7.Cu")
		(net "NFP_CORE_VID2")
	)
	(segment
		(start 38.48768 6.791325)
		(end 38.737007 6.541999)
		(width 0.12065)
		(layer "In7.Cu")
		(net "NFP_CORE_VID2")
	)
	(segment
		(start 28.829 17.145)
		(end 28.829 14.097)
		(width 0.12065)
		(layer "In7.Cu")
		(net "NFP_CORE_VID2")
	)
	(segment
		(start 31.760541 28.310459)
		(end 31.760541 25.791541)
		(width 0.12065)
		(layer "In7.Cu")
		(net "NFP_CORE_VID2")
	)
	(segment
		(start 30.617541 29.453459)
		(end 31.760541 28.310459)
		(width 0.12065)
		(layer "In7.Cu")
		(net "NFP_CORE_VID2")
	)
	(segment
		(start 40.237004 8.041996)
		(end 39.737005 7.541997)
		(width 0.13208)
		(layer "F.Cu")
		(net "NFP_CORE_VID1")
	)
	(via
		(at 28.321 31.496)
		(size 0.508)
		(drill 0.254)
		(layers "F.Cu" "B.Cu")
		(net "NFP_CORE_VID1")
	)
	(via
		(at 39.737005 7.541997)
		(size 0.4826)
		(drill 0.25654)
		(layers "F.Cu" "B.Cu")
		(net "NFP_CORE_VID1")
	)
	(segment
		(start 28.321 32.2199)
		(end 28.321 31.496)
		(width 0.14732)
		(layer "B.Cu")
		(net "NFP_CORE_VID1")
	)
	(segment
		(start 22.479 16.256)
		(end 22.479 17.018)
		(width 0.12065)
		(layer "In7.Cu")
		(net "NFP_CORE_VID1")
	)
	(segment
		(start 22.341078 8.762924)
		(end 21.971076 8.762924)
		(width 0.12065)
		(layer "In7.Cu")
		(net "NFP_CORE_VID1")
	)
	(segment
		(start 40.14023 7.138772)
		(end 40.14023 6.374943)
		(width 0.12065)
		(layer "In7.Cu")
		(net "NFP_CORE_VID1")
	)
	(segment
		(start 22.225 15.123846)
		(end 22.164675 15.184171)
		(width 0.12065)
		(layer "In7.Cu")
		(net "NFP_CORE_VID1")
	)
	(segment
		(start 23.241 17.78)
		(end 23.241 18.923)
		(width 0.12065)
		(layer "In7.Cu")
		(net "NFP_CORE_VID1")
	)
	(segment
		(start 40.14023 6.374943)
		(end 39.734287 5.969)
		(width 0.12065)
		(layer "In7.Cu")
		(net "NFP_CORE_VID1")
	)
	(segment
		(start 39.243 5.477713)
		(end 38.845287 5.08)
		(width 0.12065)
		(layer "In7.Cu")
		(net "NFP_CORE_VID1")
	)
	(segment
		(start 27.635937 20.32)
		(end 28.194 20.878063)
		(width 0.12065)
		(layer "In7.Cu")
		(net "NFP_CORE_VID1")
	)
	(segment
		(start 22.225 12.573)
		(end 22.225 15.123846)
		(width 0.12065)
		(layer "In7.Cu")
		(net "NFP_CORE_VID1")
	)
	(segment
		(start 22.733 10.033)
		(end 22.733 9.154846)
		(width 0.12065)
		(layer "In7.Cu")
		(net "NFP_CORE_VID1")
	)
	(segment
		(start 26.477646 11.176)
		(end 26.034975 11.176)
		(width 0.12065)
		(layer "In7.Cu")
		(net "NFP_CORE_VID1")
	)
	(segment
		(start 26.99352 11.102975)
		(end 26.550671 11.102975)
		(width 0.12065)
		(layer "In7.Cu")
		(net "NFP_CORE_VID1")
	)
	(segment
		(start 22.733 9.154846)
		(end 22.341078 8.762924)
		(width 0.12065)
		(layer "In7.Cu")
		(net "NFP_CORE_VID1")
	)
	(segment
		(start 35.941076 6.857924)
		(end 35.433076 6.857924)
		(width 0.12065)
		(layer "In7.Cu")
		(net "NFP_CORE_VID1")
	)
	(segment
		(start 21.783675 8.950325)
		(end 21.783675 12.131675)
		(width 0.12065)
		(layer "In7.Cu")
		(net "NFP_CORE_VID1")
	)
	(segment
		(start 28.991941 29.372941)
		(end 28.991941 30.063059)
		(width 0.12065)
		(layer "In7.Cu")
		(net "NFP_CORE_VID1")
	)
	(segment
		(start 28.991941 30.063059)
		(end 28.321 30.734)
		(width 0.12065)
		(layer "In7.Cu")
		(net "NFP_CORE_VID1")
	)
	(segment
		(start 24.836171 11.871325)
		(end 24.521846 11.557)
		(width 0.12065)
		(layer "In7.Cu")
		(net "NFP_CORE_VID1")
	)
	(segment
		(start 24.257 11.557)
		(end 22.733 10.033)
		(width 0.12065)
		(layer "In7.Cu")
		(net "NFP_CORE_VID1")
	)
	(segment
		(start 28.194 21.971025)
		(end 28.448 22.225025)
		(width 0.12065)
		(layer "In7.Cu")
		(net "NFP_CORE_VID1")
	)
	(segment
		(start 27.174495 10.922)
		(end 26.99352 11.102975)
		(width 0.12065)
		(layer "In7.Cu")
		(net "NFP_CORE_VID1")
	)
	(segment
		(start 26.034975 11.176)
		(end 25.33965 11.871325)
		(width 0.12065)
		(layer "In7.Cu")
		(net "NFP_CORE_VID1")
	)
	(segment
		(start 28.448 22.225025)
		(end 28.448 28.829)
		(width 0.12065)
		(layer "In7.Cu")
		(net "NFP_CORE_VID1")
	)
	(segment
		(start 28.194 20.878063)
		(end 28.194 21.971025)
		(width 0.12065)
		(layer "In7.Cu")
		(net "NFP_CORE_VID1")
	)
	(segment
		(start 32.893025 9.525)
		(end 31.496025 10.922)
		(width 0.12065)
		(layer "In7.Cu")
		(net "NFP_CORE_VID1")
	)
	(segment
		(start 23.241 18.923)
		(end 24.638 20.32)
		(width 0.12065)
		(layer "In7.Cu")
		(net "NFP_CORE_VID1")
	)
	(segment
		(start 37.719 5.08)
		(end 35.941076 6.857924)
		(width 0.12065)
		(layer "In7.Cu")
		(net "NFP_CORE_VID1")
	)
	(segment
		(start 21.971076 8.762924)
		(end 21.783675 8.950325)
		(width 0.12065)
		(layer "In7.Cu")
		(net "NFP_CORE_VID1")
	)
	(segment
		(start 24.638 20.32)
		(end 27.635937 20.32)
		(width 0.12065)
		(layer "In7.Cu")
		(net "NFP_CORE_VID1")
	)
	(segment
		(start 28.448 28.829)
		(end 28.991941 29.372941)
		(width 0.12065)
		(layer "In7.Cu")
		(net "NFP_CORE_VID1")
	)
	(segment
		(start 25.33965 11.871325)
		(end 24.836171 11.871325)
		(width 0.12065)
		(layer "In7.Cu")
		(net "NFP_CORE_VID1")
	)
	(segment
		(start 22.479 17.018)
		(end 23.241 17.78)
		(width 0.12065)
		(layer "In7.Cu")
		(net "NFP_CORE_VID1")
	)
	(segment
		(start 32.893025 9.397975)
		(end 32.893025 9.525)
		(width 0.12065)
		(layer "In7.Cu")
		(net "NFP_CORE_VID1")
	)
	(segment
		(start 22.164675 15.941675)
		(end 22.479 16.256)
		(width 0.12065)
		(layer "In7.Cu")
		(net "NFP_CORE_VID1")
	)
	(segment
		(start 39.737005 7.541997)
		(end 40.14023 7.138772)
		(width 0.12065)
		(layer "In7.Cu")
		(net "NFP_CORE_VID1")
	)
	(segment
		(start 39.243 5.715)
		(end 39.243 5.477713)
		(width 0.12065)
		(layer "In7.Cu")
		(net "NFP_CORE_VID1")
	)
	(segment
		(start 22.164675 15.184171)
		(end 22.164675 15.941675)
		(width 0.12065)
		(layer "In7.Cu")
		(net "NFP_CORE_VID1")
	)
	(segment
		(start 24.521846 11.557)
		(end 24.257 11.557)
		(width 0.12065)
		(layer "In7.Cu")
		(net "NFP_CORE_VID1")
	)
	(segment
		(start 28.321 30.734)
		(end 28.321 31.496)
		(width 0.12065)
		(layer "In7.Cu")
		(net "NFP_CORE_VID1")
	)
	(segment
		(start 35.433076 6.857924)
		(end 32.893025 9.397975)
		(width 0.12065)
		(layer "In7.Cu")
		(net "NFP_CORE_VID1")
	)
	(segment
		(start 38.845287 5.08)
		(end 37.719 5.08)
		(width 0.12065)
		(layer "In7.Cu")
		(net "NFP_CORE_VID1")
	)
	(segment
		(start 26.550671 11.102975)
		(end 26.477646 11.176)
		(width 0.12065)
		(layer "In7.Cu")
		(net "NFP_CORE_VID1")
	)
	(segment
		(start 21.783675 12.131675)
		(end 22.225 12.573)
		(width 0.12065)
		(layer "In7.Cu")
		(net "NFP_CORE_VID1")
	)
	(segment
		(start 39.734287 5.969)
		(end 39.497 5.969)
		(width 0.12065)
		(layer "In7.Cu")
		(net "NFP_CORE_VID1")
	)
	(segment
		(start 39.497 5.969)
		(end 39.243 5.715)
		(width 0.12065)
		(layer "In7.Cu")
		(net "NFP_CORE_VID1")
	)
	(segment
		(start 31.496025 10.922)
		(end 27.174495 10.922)
		(width 0.12065)
		(layer "In7.Cu")
		(net "NFP_CORE_VID1")
	)
	(segment
		(start 40.237004 6.042)
		(end 39.737005 5.542001)
		(width 0.13208)
		(layer "F.Cu")
		(net "NFP_CORE_VID0")
	)
	(via
		(at 39.737005 5.542001)
		(size 0.4826)
		(drill 0.25654)
		(layers "F.Cu" "B.Cu")
		(net "NFP_CORE_VID0")
	)
	(via
		(at 26.543 31.496)
		(size 0.508)
		(drill 0.254)
		(layers "F.Cu" "B.Cu")
		(net "NFP_CORE_VID0")
	)
	(segment
		(start 26.543 31.496)
		(end 26.543 32.2199)
		(width 0.14732)
		(layer "B.Cu")
		(net "NFP_CORE_VID0")
	)
	(segment
		(start 34.798 6.741846)
		(end 34.427846 7.112)
		(width 0.12065)
		(layer "In7.Cu")
		(net "NFP_CORE_VID0")
	)
	(segment
		(start 28.204541 22.362566)
		(end 28.204541 29.834459)
		(width 0.12065)
		(layer "In7.Cu")
		(net "NFP_CORE_VID0")
	)
	(segment
		(start 27.315541 20.830896)
		(end 27.315541 21.473566)
		(width 0.12065)
		(layer "In7.Cu")
		(net "NFP_CORE_VID0")
	)
	(segment
		(start 34.427846 7.162165)
		(end 30.988686 10.601325)
		(width 0.12065)
		(layer "In7.Cu")
		(net "NFP_CORE_VID0")
	)
	(segment
		(start 28.179141 29.859859)
		(end 28.179141 29.905604)
		(width 0.12065)
		(layer "In7.Cu")
		(net "NFP_CORE_VID0")
	)
	(segment
		(start 35.81941 5.720436)
		(end 35.300564 5.720436)
		(width 0.12065)
		(layer "In7.Cu")
		(net "NFP_CORE_VID0")
	)
	(segment
		(start 28.179141 29.905604)
		(end 26.588745 31.496)
		(width 0.12065)
		(layer "In7.Cu")
		(net "NFP_CORE_VID0")
	)
	(segment
		(start 34.798 6.223)
		(end 34.798 6.741846)
		(width 0.12065)
		(layer "In7.Cu")
		(net "NFP_CORE_VID0")
	)
	(segment
		(start 22.542525 8.318525)
		(end 21.780475 8.318525)
		(width 0.12065)
		(layer "In7.Cu")
		(net "NFP_CORE_VID0")
	)
	(segment
		(start 21.396325 12.760325)
		(end 21.844 13.208)
		(width 0.12065)
		(layer "In7.Cu")
		(net "NFP_CORE_VID0")
	)
	(segment
		(start 26.588745 31.496)
		(end 26.543 31.496)
		(width 0.12065)
		(layer "In7.Cu")
		(net "NFP_CORE_VID0")
	)
	(segment
		(start 21.844 13.208)
		(end 21.844 15.974746)
		(width 0.12065)
		(layer "In7.Cu")
		(net "NFP_CORE_VID0")
	)
	(segment
		(start 38.904062 4.138778)
		(end 37.401068 4.138778)
		(width 0.12065)
		(layer "In7.Cu")
		(net "NFP_CORE_VID0")
	)
	(segment
		(start 21.971 17.78)
		(end 21.971 18.161)
		(width 0.12065)
		(layer "In7.Cu")
		(net "NFP_CORE_VID0")
	)
	(segment
		(start 23.053675 8.829675)
		(end 22.542525 8.318525)
		(width 0.12065)
		(layer "In7.Cu")
		(net "NFP_CORE_VID0")
	)
	(segment
		(start 37.401068 4.138778)
		(end 35.81941 5.720436)
		(width 0.12065)
		(layer "In7.Cu")
		(net "NFP_CORE_VID0")
	)
	(segment
		(start 28.204541 29.834459)
		(end 28.179141 29.859859)
		(width 0.12065)
		(layer "In7.Cu")
		(net "NFP_CORE_VID0")
	)
	(segment
		(start 39.737005 5.542001)
		(end 39.243 5.047996)
		(width 0.12065)
		(layer "In7.Cu")
		(net "NFP_CORE_VID0")
	)
	(segment
		(start 27.086204 20.601559)
		(end 27.315541 20.830896)
		(width 0.12065)
		(layer "In7.Cu")
		(net "NFP_CORE_VID0")
	)
	(segment
		(start 23.053675 9.718675)
		(end 23.053675 8.829675)
		(width 0.12065)
		(layer "In7.Cu")
		(net "NFP_CORE_VID0")
	)
	(segment
		(start 27.840254 9.906)
		(end 26.890929 10.855325)
		(width 0.12065)
		(layer "In7.Cu")
		(net "NFP_CORE_VID0")
	)
	(segment
		(start 28.447975 9.906)
		(end 27.840254 9.906)
		(width 0.12065)
		(layer "In7.Cu")
		(net "NFP_CORE_VID0")
	)
	(segment
		(start 38.956285 4.191)
		(end 38.904062 4.138778)
		(width 0.12065)
		(layer "In7.Cu")
		(net "NFP_CORE_VID0")
	)
	(segment
		(start 27.315541 21.473566)
		(end 28.204541 22.362566)
		(width 0.12065)
		(layer "In7.Cu")
		(net "NFP_CORE_VID0")
	)
	(segment
		(start 26.890929 10.855325)
		(end 24.190325 10.855325)
		(width 0.12065)
		(layer "In7.Cu")
		(net "NFP_CORE_VID0")
	)
	(segment
		(start 34.427846 7.112)
		(end 34.427846 7.162165)
		(width 0.12065)
		(layer "In7.Cu")
		(net "NFP_CORE_VID0")
	)
	(segment
		(start 21.463 17.272)
		(end 21.971 17.78)
		(width 0.12065)
		(layer "In7.Cu")
		(net "NFP_CORE_VID0")
	)
	(segment
		(start 21.971 18.161)
		(end 24.411559 20.601559)
		(width 0.12065)
		(layer "In7.Cu")
		(net "NFP_CORE_VID0")
	)
	(segment
		(start 39.243 4.445)
		(end 38.989 4.191)
		(width 0.12065)
		(layer "In7.Cu")
		(net "NFP_CORE_VID0")
	)
	(segment
		(start 21.780475 8.318525)
		(end 21.396325 8.702675)
		(width 0.12065)
		(layer "In7.Cu")
		(net "NFP_CORE_VID0")
	)
	(segment
		(start 24.190325 10.855325)
		(end 23.053675 9.718675)
		(width 0.12065)
		(layer "In7.Cu")
		(net "NFP_CORE_VID0")
	)
	(segment
		(start 24.411559 20.601559)
		(end 27.086204 20.601559)
		(width 0.12065)
		(layer "In7.Cu")
		(net "NFP_CORE_VID0")
	)
	(segment
		(start 21.844 15.974746)
		(end 21.463 16.355746)
		(width 0.12065)
		(layer "In7.Cu")
		(net "NFP_CORE_VID0")
	)
	(segment
		(start 35.300564 5.720436)
		(end 34.798 6.223)
		(width 0.12065)
		(layer "In7.Cu")
		(net "NFP_CORE_VID0")
	)
	(segment
		(start 30.988686 10.601325)
		(end 29.1433 10.601325)
		(width 0.12065)
		(layer "In7.Cu")
		(net "NFP_CORE_VID0")
	)
	(segment
		(start 38.989 4.191)
		(end 38.956285 4.191)
		(width 0.12065)
		(layer "In7.Cu")
		(net "NFP_CORE_VID0")
	)
	(segment
		(start 21.463 16.355746)
		(end 21.463 17.272)
		(width 0.12065)
		(layer "In7.Cu")
		(net "NFP_CORE_VID0")
	)
	(segment
		(start 29.1433 10.601325)
		(end 28.447975 9.906)
		(width 0.12065)
		(layer "In7.Cu")
		(net "NFP_CORE_VID0")
	)
	(segment
		(start 21.396325 8.702675)
		(end 21.396325 12.760325)
		(width 0.12065)
		(layer "In7.Cu")
		(net "NFP_CORE_VID0")
	)
	(segment
		(start 39.243 5.047996)
		(end 39.243 4.445)
		(width 0.12065)
		(layer "In7.Cu")
		(net "NFP_CORE_VID0")
	)
	(segment
		(start 34.9123 36.83)
		(end 34.544 36.83)
		(width 0.14732)
		(layer "F.Cu")
		(net "NFP_CORE_PWM2")
	)
	(segment
		(start 34.544 36.83)
		(end 34.52401 36.84999)
		(width 0.14732)
		(layer "F.Cu")
		(net "NFP_CORE_PWM2")
	)
	(segment
		(start 34.52401 36.84999)
		(end 34.0614 36.84999)
		(width 0.14732)
		(layer "F.Cu")
		(net "NFP_CORE_PWM2")
	)
	(via
		(at 45.10024 37.719)
		(size 0.508)
		(drill 0.254)
		(layers "F.Cu" "B.Cu")
		(net "NFP_CORE_PWM2")
	)
	(via
		(at 34.9123 36.83)
		(size 0.508)
		(drill 0.2667)
		(layers "F.Cu" "B.Cu")
		(net "NFP_CORE_PWM2")
	)
	(segment
		(start 45.1485 37.719)
		(end 45.2755 37.846)
		(width 0.2032)
		(layer "B.Cu")
		(net "NFP_CORE_PWM2")
	)
	(segment
		(start 45.10024 37.719)
		(end 45.1485 37.719)
		(width 0.2032)
		(layer "B.Cu")
		(net "NFP_CORE_PWM2")
	)
	(segment
		(start 45.2755 37.846)
		(end 45.2755 38.389992)
		(width 0.2032)
		(layer "B.Cu")
		(net "NFP_CORE_PWM2")
	)
	(segment
		(start 34.417 37.8333)
		(end 34.417 38.608)
		(width 0.12065)
		(layer "In3.Cu")
		(net "NFP_CORE_PWM2")
	)
	(segment
		(start 42.290975 38.227)
		(end 42.925975 38.862)
		(width 0.12065)
		(layer "In3.Cu")
		(net "NFP_CORE_PWM2")
	)
	(segment
		(start 42.925975 38.862)
		(end 43.95724 38.862)
		(width 0.12065)
		(layer "In3.Cu")
		(net "NFP_CORE_PWM2")
	)
	(segment
		(start 43.95724 38.862)
		(end 45.10024 37.719)
		(width 0.12065)
		(layer "In3.Cu")
		(net "NFP_CORE_PWM2")
	)
	(segment
		(start 34.417 38.608)
		(end 34.671 38.862)
		(width 0.12065)
		(layer "In3.Cu")
		(net "NFP_CORE_PWM2")
	)
	(segment
		(start 35.867975 38.554025)
		(end 40.43995 38.554025)
		(width 0.12065)
		(layer "In3.Cu")
		(net "NFP_CORE_PWM2")
	)
	(segment
		(start 40.766975 38.227)
		(end 42.290975 38.227)
		(width 0.12065)
		(layer "In3.Cu")
		(net "NFP_CORE_PWM2")
	)
	(segment
		(start 34.9123 37.338)
		(end 34.417 37.8333)
		(width 0.12065)
		(layer "In3.Cu")
		(net "NFP_CORE_PWM2")
	)
	(segment
		(start 35.56 38.862)
		(end 35.867975 38.554025)
		(width 0.12065)
		(layer "In3.Cu")
		(net "NFP_CORE_PWM2")
	)
	(segment
		(start 34.9123 36.83)
		(end 34.9123 37.338)
		(width 0.12065)
		(layer "In3.Cu")
		(net "NFP_CORE_PWM2")
	)
	(segment
		(start 40.43995 38.554025)
		(end 40.766975 38.227)
		(width 0.12065)
		(layer "In3.Cu")
		(net "NFP_CORE_PWM2")
	)
	(segment
		(start 34.671 38.862)
		(end 35.56 38.862)
		(width 0.12065)
		(layer "In3.Cu")
		(net "NFP_CORE_PWM2")
	)
	(segment
		(start 34.500337 36.349991)
		(end 34.0614 36.349991)
		(width 0.14732)
		(layer "F.Cu")
		(net "NFP_CORE_PWM1")
	)
	(segment
		(start 35.052 35.798328)
		(end 34.500337 36.349991)
		(width 0.14732)
		(layer "F.Cu")
		(net "NFP_CORE_PWM1")
	)
	(segment
		(start 35.052 35.814)
		(end 35.052 35.798328)
		(width 0.14732)
		(layer "F.Cu")
		(net "NFP_CORE_PWM1")
	)
	(via
		(at 35.052 35.814)
		(size 0.508)
		(drill 0.2667)
		(layers "F.Cu" "B.Cu")
		(net "NFP_CORE_PWM1")
	)
	(via
		(at 64.69634 37.719)
		(size 0.508)
		(drill 0.254)
		(layers "F.Cu" "B.Cu")
		(net "NFP_CORE_PWM1")
	)
	(segment
		(start 64.8716 37.846)
		(end 64.8716 38.389992)
		(width 0.2032)
		(layer "B.Cu")
		(net "NFP_CORE_PWM1")
	)
	(segment
		(start 64.69634 37.719)
		(end 64.7446 37.719)
		(width 0.2032)
		(layer "B.Cu")
		(net "NFP_CORE_PWM1")
	)
	(segment
		(start 64.7446 37.719)
		(end 64.8716 37.846)
		(width 0.2032)
		(layer "B.Cu")
		(net "NFP_CORE_PWM1")
	)
	(segment
		(start 41.275 35.179)
		(end 42.037 34.417)
		(width 0.12065)
		(layer "In6.Cu")
		(net "NFP_CORE_PWM1")
	)
	(segment
		(start 44.45 33.02)
		(end 67.945 33.02)
		(width 0.12065)
		(layer "In6.Cu")
		(net "NFP_CORE_PWM1")
	)
	(segment
		(start 35.052 35.814)
		(end 35.433 35.433)
		(width 0.12065)
		(layer "In6.Cu")
		(net "NFP_CORE_PWM1")
	)
	(segment
		(start 67.945 33.02)
		(end 68.199 33.274)
		(width 0.12065)
		(layer "In6.Cu")
		(net "NFP_CORE_PWM1")
	)
	(segment
		(start 68.072 37.211)
		(end 67.325875 37.957125)
		(width 0.12065)
		(layer "In6.Cu")
		(net "NFP_CORE_PWM1")
	)
	(segment
		(start 39.497 35.433)
		(end 39.751 35.179)
		(width 0.12065)
		(layer "In6.Cu")
		(net "NFP_CORE_PWM1")
	)
	(segment
		(start 68.199 33.274)
		(end 68.199 36.322)
		(width 0.12065)
		(layer "In6.Cu")
		(net "NFP_CORE_PWM1")
	)
	(segment
		(start 68.072 36.449)
		(end 68.072 37.211)
		(width 0.12065)
		(layer "In6.Cu")
		(net "NFP_CORE_PWM1")
	)
	(segment
		(start 68.199 36.322)
		(end 68.072 36.449)
		(width 0.12065)
		(layer "In6.Cu")
		(net "NFP_CORE_PWM1")
	)
	(segment
		(start 43.053 34.417)
		(end 44.45 33.02)
		(width 0.12065)
		(layer "In6.Cu")
		(net "NFP_CORE_PWM1")
	)
	(segment
		(start 64.934465 37.957125)
		(end 64.69634 37.719)
		(width 0.12065)
		(layer "In6.Cu")
		(net "NFP_CORE_PWM1")
	)
	(segment
		(start 67.325875 37.957125)
		(end 64.934465 37.957125)
		(width 0.12065)
		(layer "In6.Cu")
		(net "NFP_CORE_PWM1")
	)
	(segment
		(start 42.037 34.417)
		(end 43.053 34.417)
		(width 0.12065)
		(layer "In6.Cu")
		(net "NFP_CORE_PWM1")
	)
	(segment
		(start 39.751 35.179)
		(end 41.275 35.179)
		(width 0.12065)
		(layer "In6.Cu")
		(net "NFP_CORE_PWM1")
	)
	(segment
		(start 35.433 35.433)
		(end 39.497 35.433)
		(width 0.12065)
		(layer "In6.Cu")
		(net "NFP_CORE_PWM1")
	)
	(segment
		(start 36.5379 24.4221)
		(end 35.259366 24.4221)
		(width 0.127)
		(layer "F.Cu")
		(net "NFP_CLK_NRESET_OUT_L")
	)
	(segment
		(start 40.237004 23.041991)
		(end 39.737005 23.54199)
		(width 0.13208)
		(layer "F.Cu")
		(net "NFP_CLK_NRESET_OUT_L")
	)
	(segment
		(start 35.259366 24.4221)
		(end 35.133077 24.548389)
		(width 0.127)
		(layer "F.Cu")
		(net "NFP_CLK_NRESET_OUT_L")
	)
	(segment
		(start 35.133077 24.548389)
		(end 34.746006 24.548389)
		(width 0.127)
		(layer "F.Cu")
		(net "NFP_CLK_NRESET_OUT_L")
	)
	(segment
		(start 37.084 23.876)
		(end 36.5379 24.4221)
		(width 0.127)
		(layer "F.Cu")
		(net "NFP_CLK_NRESET_OUT_L")
	)
	(via
		(at 37.084 23.876)
		(size 0.4572)
		(drill 0.20574)
		(layers "F.Cu" "B.Cu")
		(net "NFP_CLK_NRESET_OUT_L")
	)
	(via
		(at 39.737005 23.54199)
		(size 0.4826)
		(drill 0.20574)
		(layers "F.Cu" "B.Cu")
		(net "NFP_CLK_NRESET_OUT_L")
	)
	(segment
		(start 39.737005 23.54199)
		(end 40.236877 24.041862)
		(width 0.14732)
		(layer "B.Cu")
		(net "NFP_CLK_NRESET_OUT_L")
	)
	(segment
		(start 40.236877 24.041862)
		(end 40.237029 24.041862)
		(width 0.14732)
		(layer "B.Cu")
		(net "NFP_CLK_NRESET_OUT_L")
	)
	(segment
		(start 39.275995 24.003)
		(end 39.737005 23.54199)
		(width 0.12065)
		(layer "In6.Cu")
		(net "NFP_CLK_NRESET_OUT_L")
	)
	(segment
		(start 37.084 23.876)
		(end 37.211 24.003)
		(width 0.12065)
		(layer "In6.Cu")
		(net "NFP_CLK_NRESET_OUT_L")
	)
	(segment
		(start 37.211 24.003)
		(end 39.275995 24.003)
		(width 0.12065)
		(layer "In6.Cu")
		(net "NFP_CLK_NRESET_OUT_L")
	)
	(segment
		(start 26.035 21.8059)
		(end 26.035 20.955)
		(width 0.14732)
		(layer "F.Cu")
		(net "NFP_CLK_NRESET_L")
	)
	(segment
		(start 43.236998 23.041991)
		(end 42.736999 23.54199)
		(width 0.13208)
		(layer "F.Cu")
		(net "NFP_CLK_NRESET_L")
	)
	(via
		(at 26.035 21.8059)
		(size 0.4572)
		(drill 0.20574)
		(layers "F.Cu" "B.Cu")
		(net "NFP_CLK_NRESET_L")
	)
	(via
		(at 42.736999 23.54199)
		(size 0.4826)
		(drill 0.20574)
		(layers "F.Cu" "B.Cu")
		(net "NFP_CLK_NRESET_L")
	)
	(via
		(at 26.035 20.955)
		(size 0.762)
		(drill 0.381)
		(layers "F.Cu" "B.Cu")
		(net "NFP_CLK_NRESET_L")
	)
	(segment
		(start 42.275989 24.003)
		(end 42.736999 23.54199)
		(width 0.12065)
		(layer "In6.Cu")
		(net "NFP_CLK_NRESET_L")
	)
	(segment
		(start 28.829 22.098)
		(end 29.591 22.86)
		(width 0.12065)
		(layer "In6.Cu")
		(net "NFP_CLK_NRESET_L")
	)
	(segment
		(start 40.627732 24.003)
		(end 42.275989 24.003)
		(width 0.12065)
		(layer "In6.Cu")
		(net "NFP_CLK_NRESET_L")
	)
	(segment
		(start 29.591 22.86)
		(end 35.56 22.86)
		(width 0.12065)
		(layer "In6.Cu")
		(net "NFP_CLK_NRESET_L")
	)
	(segment
		(start 35.56 22.86)
		(end 36.057459 23.357459)
		(width 0.12065)
		(layer "In6.Cu")
		(net "NFP_CLK_NRESET_L")
	)
	(segment
		(start 38.227 22.987)
		(end 39.878 22.987)
		(width 0.12065)
		(layer "In6.Cu")
		(net "NFP_CLK_NRESET_L")
	)
	(segment
		(start 37.856541 23.357459)
		(end 38.227 22.987)
		(width 0.12065)
		(layer "In6.Cu")
		(net "NFP_CLK_NRESET_L")
	)
	(segment
		(start 26.3271 22.098)
		(end 28.829 22.098)
		(width 0.12065)
		(layer "In6.Cu")
		(net "NFP_CLK_NRESET_L")
	)
	(segment
		(start 36.057459 23.357459)
		(end 37.856541 23.357459)
		(width 0.12065)
		(layer "In6.Cu")
		(net "NFP_CLK_NRESET_L")
	)
	(segment
		(start 40.333778 23.442778)
		(end 40.333778 23.709046)
		(width 0.12065)
		(layer "In6.Cu")
		(net "NFP_CLK_NRESET_L")
	)
	(segment
		(start 39.878 22.987)
		(end 40.333778 23.442778)
		(width 0.12065)
		(layer "In6.Cu")
		(net "NFP_CLK_NRESET_L")
	)
	(segment
		(start 26.035 21.8059)
		(end 26.3271 22.098)
		(width 0.12065)
		(layer "In6.Cu")
		(net "NFP_CLK_NRESET_L")
	)
	(segment
		(start 40.333778 23.709046)
		(end 40.627732 24.003)
		(width 0.12065)
		(layer "In6.Cu")
		(net "NFP_CLK_NRESET_L")
	)
	(segment
		(start 51.943 41.529)
		(end 52.2351 41.2369)
		(width 0.2032)
		(layer "F.Cu")
		(net "L_2_CORE_PHASE")
	)
	(segment
		(start 47.9044 41.529)
		(end 51.943 41.529)
		(width 0.2032)
		(layer "F.Cu")
		(net "L_2_CORE_PHASE")
	)
	(segment
		(start 52.2351 41.2369)
		(end 52.2351 36.957)
		(width 0.2032)
		(layer "F.Cu")
		(net "L_2_CORE_PHASE")
	)
	(segment
		(start 47.8917 41.5417)
		(end 47.9044 41.529)
		(width 0.2032)
		(layer "F.Cu")
		(net "L_2_CORE_PHASE")
	)
	(via
		(at 47.5869 40.767)
		(size 0.6096)
		(drill 0.25654)
		(layers "F.Cu" "B.Cu")
		(net "L_2_CORE_PHASE")
	)
	(via
		(at 47.5869 42.418)
		(size 0.6096)
		(drill 0.25654)
		(layers "F.Cu" "B.Cu")
		(net "L_2_CORE_PHASE")
	)
	(via
		(at 46.3423 40.767)
		(size 0.6096)
		(drill 0.25654)
		(layers "F.Cu" "B.Cu")
		(net "L_2_CORE_PHASE")
	)
	(via
		(at 43.688 43.815)
		(size 0.762)
		(drill 0.381)
		(layers "F.Cu" "B.Cu")
		(net "L_2_CORE_PHASE")
	)
	(via
		(at 46.3423 42.418)
		(size 0.6096)
		(drill 0.25654)
		(layers "F.Cu" "B.Cu")
		(net "L_2_CORE_PHASE")
	)
	(via
		(at 50.1015 40.767)
		(size 0.6096)
		(drill 0.25654)
		(layers "F.Cu" "B.Cu")
		(net "L_2_CORE_PHASE")
	)
	(via
		(at 48.8569 40.767)
		(size 0.6096)
		(drill 0.25654)
		(layers "F.Cu" "B.Cu")
		(net "L_2_CORE_PHASE")
	)
	(via
		(at 50.1015 42.418)
		(size 0.6096)
		(drill 0.25654)
		(layers "F.Cu" "B.Cu")
		(net "L_2_CORE_PHASE")
	)
	(via
		(at 48.8569 42.418)
		(size 0.6096)
		(drill 0.25654)
		(layers "F.Cu" "B.Cu")
		(net "L_2_CORE_PHASE")
	)
	(segment
		(start 51.1683 40.389988)
		(end 50.478512 40.389988)
		(width 0.2032)
		(layer "B.Cu")
		(net "L_2_CORE_PHASE")
	)
	(segment
		(start 50.478512 40.389988)
		(end 50.1015 40.767)
		(width 0.2032)
		(layer "B.Cu")
		(net "L_2_CORE_PHASE")
	)
	(segment
		(start 65.913 37.719)
		(end 65.278 38.354)
		(width 0.2032)
		(layer "F.Cu")
		(net "L_1_CORE_PHASE")
	)
	(segment
		(start 65.278 41.275)
		(end 65.532 41.529)
		(width 0.2032)
		(layer "F.Cu")
		(net "L_1_CORE_PHASE")
	)
	(segment
		(start 65.913 37.4269)
		(end 65.913 37.719)
		(width 0.2032)
		(layer "F.Cu")
		(net "L_1_CORE_PHASE")
	)
	(segment
		(start 69.5706 41.529)
		(end 69.5833 41.5417)
		(width 0.2032)
		(layer "F.Cu")
		(net "L_1_CORE_PHASE")
	)
	(segment
		(start 66.3829 36.957)
		(end 65.913 37.4269)
		(width 0.2032)
		(layer "F.Cu")
		(net "L_1_CORE_PHASE")
	)
	(segment
		(start 65.278 38.354)
		(end 65.278 41.275)
		(width 0.2032)
		(layer "F.Cu")
		(net "L_1_CORE_PHASE")
	)
	(segment
		(start 65.532 41.529)
		(end 69.5706 41.529)
		(width 0.2032)
		(layer "F.Cu")
		(net "L_1_CORE_PHASE")
	)
	(via
		(at 68.453 40.767)
		(size 0.6096)
		(drill 0.25654)
		(layers "F.Cu" "B.Cu")
		(net "L_1_CORE_PHASE")
	)
	(via
		(at 67.183 40.767)
		(size 0.6096)
		(drill 0.25654)
		(layers "F.Cu" "B.Cu")
		(net "L_1_CORE_PHASE")
	)
	(via
		(at 69.6976 40.767)
		(size 0.6096)
		(drill 0.25654)
		(layers "F.Cu" "B.Cu")
		(net "L_1_CORE_PHASE")
	)
	(via
		(at 65.9384 40.767)
		(size 0.6096)
		(drill 0.25654)
		(layers "F.Cu" "B.Cu")
		(net "L_1_CORE_PHASE")
	)
	(via
		(at 65.9384 42.418)
		(size 0.6096)
		(drill 0.25654)
		(layers "F.Cu" "B.Cu")
		(net "L_1_CORE_PHASE")
	)
	(via
		(at 68.453 42.418)
		(size 0.6096)
		(drill 0.25654)
		(layers "F.Cu" "B.Cu")
		(net "L_1_CORE_PHASE")
	)
	(via
		(at 67.183 42.418)
		(size 0.6096)
		(drill 0.25654)
		(layers "F.Cu" "B.Cu")
		(net "L_1_CORE_PHASE")
	)
	(via
		(at 69.6976 42.418)
		(size 0.6096)
		(drill 0.25654)
		(layers "F.Cu" "B.Cu")
		(net "L_1_CORE_PHASE")
	)
	(via
		(at 64.516 44.831)
		(size 0.762)
		(drill 0.381)
		(layers "F.Cu" "B.Cu")
		(net "L_1_CORE_PHASE")
	)
	(segment
		(start 70.074612 40.389988)
		(end 69.6976 40.767)
		(width 0.2032)
		(layer "B.Cu")
		(net "L_1_CORE_PHASE")
	)
	(segment
		(start 70.7644 40.389988)
		(end 70.074612 40.389988)
		(width 0.2032)
		(layer "B.Cu")
		(net "L_1_CORE_PHASE")
	)
	(segment
		(start 62.23701 32.041998)
		(end 62.736984 32.541972)
		(width 0.254)
		(layer "F.Cu")
		(net "DDR_VDDQ")
	)
	(segment
		(start 75.057 46.228)
		(end 75.057 46.482)
		(width 0.254)
		(layer "F.Cu")
		(net "DDR_VDDQ")
	)
	(segment
		(start 63.737007 13.54201)
		(end 63.237008 14.042009)
		(width 0.254)
		(layer "F.Cu")
		(net "DDR_VDDQ")
	)
	(segment
		(start 74.6379 20.574)
		(end 74.6379 19.869099)
		(width 0.254)
		(layer "F.Cu")
		(net "DDR_VDDQ")
	)
	(segment
		(start 81.8261 23.343108)
		(end 81.850992 23.368)
		(width 0.254)
		(layer "F.Cu")
		(net "DDR_VDDQ")
	)
	(segment
		(start 81.8261 22.479)
		(end 81.8261 23.343108)
		(width 0.254)
		(layer "F.Cu")
		(net "DDR_VDDQ")
	)
	(segment
		(start 75.184 4.191)
		(end 74.803 3.787902)
		(width 0.254)
		(layer "F.Cu")
		(net "DDR_VDDQ")
	)
	(segment
		(start 61.737011 27.542007)
		(end 61.237012 27.042008)
		(width 0.254)
		(layer "F.Cu")
		(net "DDR_VDDQ")
	)
	(segment
		(start 73.66 26.9621)
		(end 73.8251 26.797)
		(width 0.254)
		(layer "F.Cu")
		(net "DDR_VDDQ")
	)
	(segment
		(start 72.9869 23.495)
		(end 72.9869 24.148898)
		(width 0.254)
		(layer "F.Cu")
		(net "DDR_VDDQ")
	)
	(segment
		(start 76.029007 29.591)
		(end 76.251003 29.812996)
		(width 0.254)
		(layer "F.Cu")
		(net "DDR_VDDQ")
	)
	(segment
		(start 69.736995 33.541995)
		(end 69.236996 33.041996)
		(width 0.4826)
		(layer "F.Cu")
		(net "DDR_VDDQ")
	)
	(segment
		(start 80.5561 34.671)
		(end 80.518 34.671)
		(width 0.2032)
		(layer "F.Cu")
		(net "DDR_VDDQ")
	)
	(segment
		(start 75.438 12.643002)
		(end 75.451005 12.656007)
		(width 0.254)
		(layer "F.Cu")
		(net "DDR_VDDQ")
	)
	(segment
		(start 73.66 28.7401)
		(end 73.66 26.9621)
		(width 0.254)
		(layer "F.Cu")
		(net "DDR_VDDQ")
	)
	(segment
		(start 81.534 20.574)
		(end 81.0641 20.574)
		(width 0.254)
		(layer "F.Cu")
		(net "DDR_VDDQ")
	)
	(segment
		(start 81.534 9.398)
		(end 81.850992 9.081008)
		(width 0.254)
		(layer "F.Cu")
		(net "DDR_VDDQ")
	)
	(segment
		(start 68.736997 17.542002)
		(end 68.236998 18.042001)
		(width 0.254)
		(layer "F.Cu")
		(net "DDR_VDDQ")
	)
	(segment
		(start 81.534 11.811)
		(end 81.0641 11.811)
		(width 0.254)
		(layer "F.Cu")
		(net "DDR_VDDQ")
	)
	(segment
		(start 72.9869 24.148898)
		(end 73.05101 24.213007)
		(width 0.254)
		(layer "F.Cu")
		(net "DDR_VDDQ")
	)
	(segment
		(start 69.736995 6.541999)
		(end 69.236996 7.041998)
		(width 0.254)
		(layer "F.Cu")
		(net "DDR_VDDQ")
	)
	(segment
		(start 73.152 24.9809)
		(end 73.818902 24.9809)
		(width 0.254)
		(layer "F.Cu")
		(net "DDR_VDDQ")
	)
	(segment
		(start 67.736999 33.541995)
		(end 67.237 33.041996)
		(width 0.254)
		(layer "F.Cu")
		(net "DDR_VDDQ")
	)
	(segment
		(start 75.916968 29.591)
		(end 76.029007 29.591)
		(width 0.254)
		(layer "F.Cu")
		(net "DDR_VDDQ")
	)
	(segment
		(start 79.356001 41.129001)
		(end 79.121 40.894)
		(width 0.2032)
		(layer "F.Cu")
		(net "DDR_VDDQ")
	)
	(segment
		(start 65.737003 17.542002)
		(end 65.237004 18.042001)
		(width 0.254)
		(layer "F.Cu")
		(net "DDR_VDDQ")
	)
	(segment
		(start 76.3651 5.715)
		(end 76.3651 6.584899)
		(width 0.254)
		(layer "F.Cu")
		(net "DDR_VDDQ")
	)
	(segment
		(start 74.3712 43.942)
		(end 74.803 44.3738)
		(width 0.254)
		(layer "F.Cu")
		(net "DDR_VDDQ")
	)
	(segment
		(start 62.737009 9.541993)
		(end 62.23701 10.041992)
		(width 0.254)
		(layer "F.Cu")
		(net "DDR_VDDQ")
	)
	(segment
		(start 74.6379 19.869099)
		(end 74.651006 19.855993)
		(width 0.254)
		(layer "F.Cu")
		(net "DDR_VDDQ")
	)
	(segment
		(start 81.850992 12.127992)
		(end 81.534 11.811)
		(width 0.254)
		(layer "F.Cu")
		(net "DDR_VDDQ")
	)
	(segment
		(start 75.0189 23.780902)
		(end 75.451005 24.213007)
		(width 0.254)
		(layer "F.Cu")
		(net "DDR_VDDQ")
	)
	(segment
		(start 81.850992 19.855993)
		(end 81.850992 20.257008)
		(width 0.254)
		(layer "F.Cu")
		(net "DDR_VDDQ")
	)
	(segment
		(start 77.056894 8.2931)
		(end 77.051002 8.298993)
		(width 0.254)
		(layer "F.Cu")
		(net "DDR_VDDQ")
	)
	(segment
		(start 69.736995 13.54201)
		(end 69.236996 14.042009)
		(width 0.254)
		(layer "F.Cu")
		(net "DDR_VDDQ")
	)
	(segment
		(start 63.737007 22.541992)
		(end 63.237008 22.041993)
		(width 0.254)
		(layer "F.Cu")
		(net "DDR_VDDQ")
	)
	(segment
		(start 81.850992 20.257008)
		(end 81.534 20.574)
		(width 0.254)
		(layer "F.Cu")
		(net "DDR_VDDQ")
	)
	(segment
		(start 74.6379 31.426099)
		(end 74.651006 31.412993)
		(width 0.254)
		(layer "F.Cu")
		(net "DDR_VDDQ")
	)
	(segment
		(start 74.6379 8.312099)
		(end 74.651006 8.298993)
		(width 0.254)
		(layer "F.Cu")
		(net "DDR_VDDQ")
	)
	(segment
		(start 66.737001 13.54201)
		(end 66.237002 14.042009)
		(width 0.254)
		(layer "F.Cu")
		(net "DDR_VDDQ")
	)
	(segment
		(start 65.737003 26.542009)
		(end 65.237004 26.04201)
		(width 0.254)
		(layer "F.Cu")
		(net "DDR_VDDQ")
	)
	(segment
		(start 67.736999 30.542001)
		(end 67.237 30.042002)
		(width 0.254)
		(layer "F.Cu")
		(net "DDR_VDDQ")
	)
	(segment
		(start 75.438 11.9761)
		(end 75.438 12.643002)
		(width 0.254)
		(layer "F.Cu")
		(net "DDR_VDDQ")
	)
	(segment
		(start 80.137 41.129001)
		(end 79.356001 41.129001)
		(width 0.2032)
		(layer "F.Cu")
		(net "DDR_VDDQ")
	)
	(segment
		(start 73.818902 24.9809)
		(end 73.851008 25.013006)
		(width 0.254)
		(layer "F.Cu")
		(net "DDR_VDDQ")
	)
	(segment
		(start 75.320068 28.9941)
		(end 75.916968 29.591)
		(width 0.254)
		(layer "F.Cu")
		(net "DDR_VDDQ")
	)
	(segment
		(start 81.8769 32.258)
		(end 81.850992 32.155892)
		(width 0.254)
		(layer "F.Cu")
		(net "DDR_VDDQ")
	)
	(segment
		(start 81.153 35.2679)
		(end 80.5561 34.671)
		(width 0.2032)
		(layer "F.Cu")
		(net "DDR_VDDQ")
	)
	(segment
		(start 74.3712 28.9941)
		(end 73.914 28.9941)
		(width 0.254)
		(layer "F.Cu")
		(net "DDR_VDDQ")
	)
	(segment
		(start 66.737001 22.541992)
		(end 66.237002 22.041993)
		(width 0.254)
		(layer "F.Cu")
		(net "DDR_VDDQ")
	)
	(segment
		(start 73.1139 12.593117)
		(end 73.05101 12.656007)
		(width 0.254)
		(layer "F.Cu")
		(net "DDR_VDDQ")
	)
	(segment
		(start 81.0641 9.398)
		(end 81.534 9.398)
		(width 0.254)
		(layer "F.Cu")
		(net "DDR_VDDQ")
	)
	(segment
		(start 74.6379 32.258)
		(end 74.6379 31.426099)
		(width 0.254)
		(layer "F.Cu")
		(net "DDR_VDDQ")
	)
	(segment
		(start 77.051002 31.839002)
		(end 77.051002 31.412993)
		(width 0.254)
		(layer "F.Cu")
		(net "DDR_VDDQ")
	)
	(segment
		(start 76.3651 6.584899)
		(end 76.251003 6.698996)
		(width 0.254)
		(layer "F.Cu")
		(net "DDR_VDDQ")
	)
	(segment
		(start 78.232 32.157314)
		(end 77.369314 32.157314)
		(width 0.254)
		(layer "F.Cu")
		(net "DDR_VDDQ")
	)
	(segment
		(start 77.978 8.2931)
		(end 77.056894 8.2931)
		(width 0.254)
		(layer "F.Cu")
		(net "DDR_VDDQ")
	)
	(segment
		(start 73.1139 11.938)
		(end 73.1139 12.593117)
		(width 0.254)
		(layer "F.Cu")
		(net "DDR_VDDQ")
	)
	(segment
		(start 73.914 28.9941)
		(end 73.66 28.7401)
		(width 0.254)
		(layer "F.Cu")
		(net "DDR_VDDQ")
	)
	(segment
		(start 61.737011 19.541998)
		(end 61.237012 19.041999)
		(width 0.254)
		(layer "F.Cu")
		(net "DDR_VDDQ")
	)
	(segment
		(start 81.850992 9.081008)
		(end 81.850992 8.298993)
		(width 0.254)
		(layer "F.Cu")
		(net "DDR_VDDQ")
	)
	(segment
		(start 74.803 45.974)
		(end 75.057 46.228)
		(width 0.254)
		(layer "F.Cu")
		(net "DDR_VDDQ")
	)
	(segment
		(start 77.369314 32.157314)
		(end 77.051002 31.839002)
		(width 0.254)
		(layer "F.Cu")
		(net "DDR_VDDQ")
	)
	(segment
		(start 81.850992 12.656007)
		(end 81.850992 12.127992)
		(width 0.254)
		(layer "F.Cu")
		(net "DDR_VDDQ")
	)
	(segment
		(start 75.3999 4.318)
		(end 75.184 4.191)
		(width 0.254)
		(layer "F.Cu")
		(net "DDR_VDDQ")
	)
	(segment
		(start 74.6379 9.017)
		(end 74.6379 8.312099)
		(width 0.254)
		(layer "F.Cu")
		(net "DDR_VDDQ")
	)
	(segment
		(start 63.737007 33.541995)
		(end 63.237008 33.041996)
		(width 0.254)
		(layer "F.Cu")
		(net "DDR_VDDQ")
	)
	(segment
		(start 63.737007 30.542001)
		(end 63.237008 30.042002)
		(width 0.254)
		(layer "F.Cu")
		(net "DDR_VDDQ")
	)
	(segment
		(start 81.850992 32.155892)
		(end 81.850992 31.412993)
		(width 0.254)
		(layer "F.Cu")
		(net "DDR_VDDQ")
	)
	(segment
		(start 75.0189 23.495)
		(end 75.0189 23.780902)
		(width 0.254)
		(layer "F.Cu")
		(net "DDR_VDDQ")
	)
	(segment
		(start 69.736995 22.541992)
		(end 69.236996 22.041993)
		(width 0.254)
		(layer "F.Cu")
		(net "DDR_VDDQ")
	)
	(segment
		(start 65.737003 33.541995)
		(end 65.237004 33.041996)
		(width 0.254)
		(layer "F.Cu")
		(net "DDR_VDDQ")
	)
	(segment
		(start 74.803 44.3738)
		(end 74.803 45.974)
		(width 0.254)
		(layer "F.Cu")
		(net "DDR_VDDQ")
	)
	(segment
		(start 68.736997 26.542009)
		(end 68.236998 26.04201)
		(width 0.254)
		(layer "F.Cu")
		(net "DDR_VDDQ")
	)
	(segment
		(start 74.3712 28.9941)
		(end 75.320068 28.9941)
		(width 0.254)
		(layer "F.Cu")
		(net "DDR_VDDQ")
	)
	(via
		(at 67.736999 30.542001)
		(size 0.4826)
		(drill 0.20574)
		(layers "F.Cu" "B.Cu")
		(net "DDR_VDDQ")
	)
	(via
		(at 73.05101 12.656007)
		(size 0.4572)
		(drill 0.20574)
		(layers "F.Cu" "B.Cu")
		(net "DDR_VDDQ")
	)
	(via
		(at 74.651006 8.298993)
		(size 0.4572)
		(drill 0.20574)
		(layers "F.Cu" "B.Cu")
		(net "DDR_VDDQ")
	)
	(via
		(at 77.051002 31.412993)
		(size 0.4572)
		(drill 0.20574)
		(layers "F.Cu" "B.Cu")
		(net "DDR_VDDQ")
	)
	(via
		(at 81.850992 31.412993)
		(size 0.4572)
		(drill 0.20574)
		(layers "F.Cu" "B.Cu")
		(net "DDR_VDDQ")
	)
	(via
		(at 68.736997 26.542009)
		(size 0.4826)
		(drill 0.20574)
		(layers "F.Cu" "B.Cu")
		(net "DDR_VDDQ")
	)
	(via
		(at 81.850992 12.656007)
		(size 0.4572)
		(drill 0.20574)
		(layers "F.Cu" "B.Cu")
		(net "DDR_VDDQ")
	)
	(via
		(at 79.450997 13.456006)
		(size 0.4572)
		(drill 0.20574)
		(layers "F.Cu" "B.Cu")
		(net "DDR_VDDQ")
	)
	(via
		(at 75.946 46.101)
		(size 0.508)
		(drill 0.25654)
		(layers "F.Cu" "B.Cu")
		(net "DDR_VDDQ")
	)
	(via
		(at 67.736999 33.541995)
		(size 0.4826)
		(drill 0.20574)
		(layers "F.Cu" "B.Cu")
		(net "DDR_VDDQ")
	)
	(via
		(at 65.737003 17.542002)
		(size 0.4826)
		(drill 0.20574)
		(layers "F.Cu" "B.Cu")
		(net "DDR_VDDQ")
	)
	(via
		(at 73.851008 8.298993)
		(size 0.4572)
		(drill 0.20574)
		(layers "F.Cu" "B.Cu")
		(net "DDR_VDDQ")
	)
	(via
		(at 81.850992 19.855993)
		(size 0.4572)
		(drill 0.20574)
		(layers "F.Cu" "B.Cu")
		(net "DDR_VDDQ")
	)
	(via
		(at 79.450997 1.899006)
		(size 0.4572)
		(drill 0.20574)
		(layers "F.Cu" "B.Cu")
		(net "DDR_VDDQ")
	)
	(via
		(at 77.051002 1.899006)
		(size 0.4572)
		(drill 0.20574)
		(layers "F.Cu" "B.Cu")
		(net "DDR_VDDQ")
	)
	(via
		(at 63.737007 13.54201)
		(size 0.4826)
		(drill 0.20574)
		(layers "F.Cu" "B.Cu")
		(net "DDR_VDDQ")
	)
	(via
		(at 65.737003 33.541995)
		(size 0.4826)
		(drill 0.20574)
		(layers "F.Cu" "B.Cu")
		(net "DDR_VDDQ")
	)
	(via
		(at 72.251011 30.612994)
		(size 0.4572)
		(drill 0.20574)
		(layers "F.Cu" "B.Cu")
		(net "DDR_VDDQ")
	)
	(via
		(at 77.051002 8.298993)
		(size 0.4572)
		(drill 0.20574)
		(layers "F.Cu" "B.Cu")
		(net "DDR_VDDQ")
	)
	(via
		(at 73.05101 8.298993)
		(size 0.4572)
		(drill 0.20574)
		(layers "F.Cu" "B.Cu")
		(net "DDR_VDDQ")
	)
	(via
		(at 77.051002 13.456006)
		(size 0.4572)
		(drill 0.20574)
		(layers "F.Cu" "B.Cu")
		(net "DDR_VDDQ")
	)
	(via
		(at 77.051002 19.855993)
		(size 0.4572)
		(drill 0.20574)
		(layers "F.Cu" "B.Cu")
		(net "DDR_VDDQ")
	)
	(via
		(at 72.251011 1.899006)
		(size 0.4572)
		(drill 0.20574)
		(layers "F.Cu" "B.Cu")
		(net "DDR_VDDQ")
	)
	(via
		(at 76.251003 29.812996)
		(size 0.4572)
		(drill 0.20574)
		(layers "F.Cu" "B.Cu")
		(net "DDR_VDDQ")
	)
	(via
		(at 76.708 51.689)
		(size 0.508)
		(drill 0.254)
		(layers "F.Cu" "B.Cu")
		(net "DDR_VDDQ")
	)
	(via
		(at 69.736995 13.54201)
		(size 0.4826)
		(drill 0.20574)
		(layers "F.Cu" "B.Cu")
		(net "DDR_VDDQ")
	)
	(via
		(at 75.451005 24.213007)
		(size 0.4572)
		(drill 0.20574)
		(layers "F.Cu" "B.Cu")
		(net "DDR_VDDQ")
	)
	(via
		(at 73.851008 13.456006)
		(size 0.4572)
		(drill 0.20574)
		(layers "F.Cu" "B.Cu")
		(net "DDR_VDDQ")
	)
	(via
		(at 83.450989 24.154486)
		(size 0.4572)
		(drill 0.20574)
		(layers "F.Cu" "B.Cu")
		(net "DDR_VDDQ")
	)
	(via
		(at 83.450989 12.656007)
		(size 0.4572)
		(drill 0.20574)
		(layers "F.Cu" "B.Cu")
		(net "DDR_VDDQ")
	)
	(via
		(at 77.724 51.689)
		(size 0.508)
		(drill 0.254)
		(layers "F.Cu" "B.Cu")
		(net "DDR_VDDQ")
	)
	(via
		(at 79.121 40.894)
		(size 0.508)
		(drill 0.254)
		(layers "F.Cu" "B.Cu")
		(net "DDR_VDDQ")
	)
	(via
		(at 61.737011 27.542007)
		(size 0.4826)
		(drill 0.20574)
		(layers "F.Cu" "B.Cu")
		(net "DDR_VDDQ")
	)
	(via
		(at 61.737011 19.541998)
		(size 0.4826)
		(drill 0.20574)
		(layers "F.Cu" "B.Cu")
		(net "DDR_VDDQ")
	)
	(via
		(at 69.736995 6.541999)
		(size 0.4826)
		(drill 0.20574)
		(layers "F.Cu" "B.Cu")
		(net "DDR_VDDQ")
	)
	(via
		(at 74.651006 31.412993)
		(size 0.4572)
		(drill 0.20574)
		(layers "F.Cu" "B.Cu")
		(net "DDR_VDDQ")
	)
	(via
		(at 68.736997 17.542002)
		(size 0.4826)
		(drill 0.20574)
		(layers "F.Cu" "B.Cu")
		(net "DDR_VDDQ")
	)
	(via
		(at 81.850992 8.298993)
		(size 0.4572)
		(drill 0.20574)
		(layers "F.Cu" "B.Cu")
		(net "DDR_VDDQ")
	)
	(via
		(at 66.737001 22.541992)
		(size 0.4826)
		(drill 0.20574)
		(layers "F.Cu" "B.Cu")
		(net "DDR_VDDQ")
	)
	(via
		(at 74.651006 19.855993)
		(size 0.4572)
		(drill 0.20574)
		(layers "F.Cu" "B.Cu")
		(net "DDR_VDDQ")
	)
	(via
		(at 74.803 3.787902)
		(size 0.508)
		(drill 0.254)
		(layers "F.Cu" "B.Cu")
		(net "DDR_VDDQ")
	)
	(via
		(at 73.851008 1.899006)
		(size 0.4572)
		(drill 0.20574)
		(layers "F.Cu" "B.Cu")
		(net "DDR_VDDQ")
	)
	(via
		(at 65.737003 26.542009)
		(size 0.4826)
		(drill 0.20574)
		(layers "F.Cu" "B.Cu")
		(net "DDR_VDDQ")
	)
	(via
		(at 73.851008 25.013006)
		(size 0.4572)
		(drill 0.20574)
		(layers "F.Cu" "B.Cu")
		(net "DDR_VDDQ")
	)
	(via
		(at 76.251003 18.255996)
		(size 0.4572)
		(drill 0.20574)
		(layers "F.Cu" "B.Cu")
		(net "DDR_VDDQ")
	)
	(via
		(at 73.05101 1.099007)
		(size 0.4572)
		(drill 0.20574)
		(layers "F.Cu" "B.Cu")
		(net "DDR_VDDQ")
	)
	(via
		(at 76.708 50.8)
		(size 0.508)
		(drill 0.254)
		(layers "F.Cu" "B.Cu")
		(net "DDR_VDDQ")
	)
	(via
		(at 79.450997 19.055994)
		(size 0.4572)
		(drill 0.20574)
		(layers "F.Cu" "B.Cu")
		(net "DDR_VDDQ")
	)
	(via
		(at 83.450989 19.855993)
		(size 0.4572)
		(drill 0.20574)
		(layers "F.Cu" "B.Cu")
		(net "DDR_VDDQ")
	)
	(via
		(at 73.55901 22.041993)
		(size 0.4572)
		(drill 0.20574)
		(layers "F.Cu" "B.Cu")
		(net "DDR_VDDQ")
	)
	(via
		(at 63.737007 33.541995)
		(size 0.4826)
		(drill 0.20574)
		(layers "F.Cu" "B.Cu")
		(net "DDR_VDDQ")
	)
	(via
		(at 79.450997 30.612994)
		(size 0.4572)
		(drill 0.20574)
		(layers "F.Cu" "B.Cu")
		(net "DDR_VDDQ")
	)
	(via
		(at 72.251011 13.456006)
		(size 0.4572)
		(drill 0.20574)
		(layers "F.Cu" "B.Cu")
		(net "DDR_VDDQ")
	)
	(via
		(at 63.737007 22.541992)
		(size 0.4826)
		(drill 0.20574)
		(layers "F.Cu" "B.Cu")
		(net "DDR_VDDQ")
	)
	(via
		(at 81.850992 23.368)
		(size 0.4572)
		(drill 0.20574)
		(layers "F.Cu" "B.Cu")
		(net "DDR_VDDQ")
	)
	(via
		(at 76.251003 6.698996)
		(size 0.4572)
		(drill 0.20574)
		(layers "F.Cu" "B.Cu")
		(net "DDR_VDDQ")
	)
	(via
		(at 75.057 46.482)
		(size 0.508)
		(drill 0.254)
		(layers "F.Cu" "B.Cu")
		(net "DDR_VDDQ")
	)
	(via
		(at 69.736995 22.541992)
		(size 0.4826)
		(drill 0.20574)
		(layers "F.Cu" "B.Cu")
		(net "DDR_VDDQ")
	)
	(via
		(at 69.736995 33.541995)
		(size 0.4826)
		(drill 0.20574)
		(layers "F.Cu" "B.Cu")
		(net "DDR_VDDQ")
	)
	(via
		(at 63.737007 30.542001)
		(size 0.4826)
		(drill 0.20574)
		(layers "F.Cu" "B.Cu")
		(net "DDR_VDDQ")
	)
	(via
		(at 73.851008 19.855993)
		(size 0.4572)
		(drill 0.20574)
		(layers "F.Cu" "B.Cu")
		(net "DDR_VDDQ")
	)
	(via
		(at 62.737009 9.541993)
		(size 0.4826)
		(drill 0.20574)
		(layers "F.Cu" "B.Cu")
		(net "DDR_VDDQ")
	)
	(via
		(at 79.450997 7.498994)
		(size 0.4572)
		(drill 0.20574)
		(layers "F.Cu" "B.Cu")
		(net "DDR_VDDQ")
	)
	(via
		(at 66.737001 13.54201)
		(size 0.4826)
		(drill 0.20574)
		(layers "F.Cu" "B.Cu")
		(net "DDR_VDDQ")
	)
	(via
		(at 81.850992 1.099007)
		(size 0.4572)
		(drill 0.20574)
		(layers "F.Cu" "B.Cu")
		(net "DDR_VDDQ")
	)
	(via
		(at 73.05101 31.412993)
		(size 0.4572)
		(drill 0.20574)
		(layers "F.Cu" "B.Cu")
		(net "DDR_VDDQ")
	)
	(via
		(at 80.518 34.671)
		(size 0.508)
		(drill 0.254)
		(layers "F.Cu" "B.Cu")
		(net "DDR_VDDQ")
	)
	(via
		(at 75.946 47.625)
		(size 0.508)
		(drill 0.25654)
		(layers "F.Cu" "B.Cu")
		(net "DDR_VDDQ")
	)
	(via
		(at 77.051002 25.013006)
		(size 0.4572)
		(drill 0.20574)
		(layers "F.Cu" "B.Cu")
		(net "DDR_VDDQ")
	)
	(via
		(at 72.251011 19.055994)
		(size 0.4572)
		(drill 0.20574)
		(layers "F.Cu" "B.Cu")
		(net "DDR_VDDQ")
	)
	(via
		(at 62.736984 32.541972)
		(size 0.4826)
		(drill 0.20574)
		(layers "F.Cu" "B.Cu")
		(net "DDR_VDDQ")
	)
	(via
		(at 73.05101 24.213007)
		(size 0.4572)
		(drill 0.20574)
		(layers "F.Cu" "B.Cu")
		(net "DDR_VDDQ")
	)
	(via
		(at 75.451005 12.656007)
		(size 0.4572)
		(drill 0.20574)
		(layers "F.Cu" "B.Cu")
		(net "DDR_VDDQ")
	)
	(via
		(at 83.450989 8.298993)
		(size 0.4572)
		(drill 0.20574)
		(layers "F.Cu" "B.Cu")
		(net "DDR_VDDQ")
	)
	(via
		(at 72.251011 25.013006)
		(size 0.4572)
		(drill 0.20574)
		(layers "F.Cu" "B.Cu")
		(net "DDR_VDDQ")
	)
	(via
		(at 72.251011 7.498994)
		(size 0.4572)
		(drill 0.20574)
		(layers "F.Cu" "B.Cu")
		(net "DDR_VDDQ")
	)
	(via
		(at 83.50951 31.471514)
		(size 0.4572)
		(drill 0.20574)
		(layers "F.Cu" "B.Cu")
		(net "DDR_VDDQ")
	)
	(via
		(at 75.451005 1.099007)
		(size 0.4572)
		(drill 0.20574)
		(layers "F.Cu" "B.Cu")
		(net "DDR_VDDQ")
	)
	(via
		(at 76.454 49.53)
		(size 0.508)
		(drill 0.25654)
		(layers "F.Cu" "B.Cu")
		(net "DDR_VDDQ")
	)
	(via
		(at 79.450997 25.013006)
		(size 0.4572)
		(drill 0.20574)
		(layers "F.Cu" "B.Cu")
		(net "DDR_VDDQ")
	)
	(via
		(at 83.450989 1.099007)
		(size 0.4572)
		(drill 0.20574)
		(layers "F.Cu" "B.Cu")
		(net "DDR_VDDQ")
	)
	(via
		(at 73.851008 31.412993)
		(size 0.4572)
		(drill 0.20574)
		(layers "F.Cu" "B.Cu")
		(net "DDR_VDDQ")
	)
	(via
		(at 73.05101 19.855993)
		(size 0.4572)
		(drill 0.20574)
		(layers "F.Cu" "B.Cu")
		(net "DDR_VDDQ")
	)
	(via
		(at 77.724 50.8)
		(size 0.508)
		(drill 0.254)
		(layers "F.Cu" "B.Cu")
		(net "DDR_VDDQ")
	)
	(segment
		(start 63.737007 31.631407)
		(end 63.737007 30.542001)
		(width 0.508)
		(layer "B.Cu")
		(net "DDR_VDDQ")
	)
	(segment
		(start 69.236971 14.042136)
		(end 69.236971 14.042034)
		(width 0.254)
		(layer "B.Cu")
		(net "DDR_VDDQ")
	)
	(segment
		(start 73.451009 19.455994)
		(end 73.05101 19.855993)
		(width 0.254)
		(layer "B.Cu")
		(net "DDR_VDDQ")
	)
	(segment
		(start 75.051006 7.898994)
		(end 74.651006 8.298993)
		(width 0.254)
		(layer "B.Cu")
		(net "DDR_VDDQ")
	)
	(segment
		(start 71.851012 1.499006)
		(end 72.251011 1.899006)
		(width 0.254)
		(layer "B.Cu")
		(net "DDR_VDDQ")
	)
	(segment
		(start 79.050998 25.413005)
		(end 79.450997 25.013006)
		(width 0.254)
		(layer "B.Cu")
		(net "DDR_VDDQ")
	)
	(segment
		(start 71.851012 24.613006)
		(end 72.251011 25.013006)
		(width 0.254)
		(layer "B.Cu")
		(net "DDR_VDDQ")
	)
	(segment
		(start 72.65101 13.856005)
		(end 72.251011 13.456006)
		(width 0.254)
		(layer "B.Cu")
		(net "DDR_VDDQ")
	)
	(segment
		(start 71.851012 30.212995)
		(end 72.251011 30.612994)
		(width 0.254)
		(layer "B.Cu")
		(net "DDR_VDDQ")
	)
	(segment
		(start 83.05099 24.613006)
		(end 83.450989 24.154486)
		(width 0.254)
		(layer "B.Cu")
		(net "DDR_VDDQ")
	)
	(segment
		(start 63.237135 14.041882)
		(end 63.236983 14.041882)
		(width 0.254)
		(layer "B.Cu")
		(net "DDR_VDDQ")
	)
	(segment
		(start 71.851012 18.655995)
		(end 72.251011 19.055994)
		(width 0.254)
		(layer "B.Cu")
		(net "DDR_VDDQ")
	)
	(segment
		(start 81.450993 1.499006)
		(end 81.850992 1.099007)
		(width 0.254)
		(layer "B.Cu")
		(net "DDR_VDDQ")
	)
	(segment
		(start 69.236971 14.042034)
		(end 69.736995 13.54201)
		(width 0.254)
		(layer "B.Cu")
		(net "DDR_VDDQ")
	)
	(segment
		(start 81.450993 23.767999)
		(end 81.850992 23.368)
		(width 0.254)
		(layer "B.Cu")
		(net "DDR_VDDQ")
	)
	(segment
		(start 81.450993 19.455994)
		(end 81.850992 19.855993)
		(width 0.254)
		(layer "B.Cu")
		(net "DDR_VDDQ")
	)
	(segment
		(start 69.236971 7.042023)
		(end 69.236971 7.04215)
		(width 0.254)
		(layer "B.Cu")
		(net "DDR_VDDQ")
	)
	(segment
		(start 65.737003 27.076375)
		(end 65.228978 27.5844)
		(width 0.508)
		(layer "B.Cu")
		(net "DDR_VDDQ")
	)
	(segment
		(start 73.451009 13.056006)
		(end 73.05101 12.656007)
		(width 0.254)
		(layer "B.Cu")
		(net "DDR_VDDQ")
	)
	(segment
		(start 73.451009 1.499006)
		(end 73.05101 1.099007)
		(width 0.254)
		(layer "B.Cu")
		(net "DDR_VDDQ")
	)
	(segment
		(start 67.236975 13.042138)
		(end 67.236873 13.042138)
		(width 0.254)
		(layer "B.Cu")
		(net "DDR_VDDQ")
	)
	(segment
		(start 81.450993 13.056006)
		(end 81.850992 12.656007)
		(width 0.254)
		(layer "B.Cu")
		(net "DDR_VDDQ")
	)
	(segment
		(start 79.050998 2.299005)
		(end 79.450997 1.899006)
		(width 0.254)
		(layer "B.Cu")
		(net "DDR_VDDQ")
	)
	(segment
		(start 77.451001 31.012994)
		(end 77.051002 31.412993)
		(width 0.254)
		(layer "B.Cu")
		(net "DDR_VDDQ")
	)
	(segment
		(start 74.251007 2.299005)
		(end 73.851008 1.899006)
		(width 0.254)
		(layer "B.Cu")
		(net "DDR_VDDQ")
	)
	(segment
		(start 65.737003 26.542009)
		(end 65.737003 27.076375)
		(width 0.508)
		(layer "B.Cu")
		(net "DDR_VDDQ")
	)
	(segment
		(start 63.236983 10.041966)
		(end 63.236983 10.042144)
		(width 0.254)
		(layer "B.Cu")
		(net "DDR_VDDQ")
	)
	(segment
		(start 73.451009 7.898994)
		(end 73.05101 8.298993)
		(width 0.254)
		(layer "B.Cu")
		(net "DDR_VDDQ")
	)
	(segment
		(start 79.050998 18.655995)
		(end 79.450997 19.055994)
		(width 0.254)
		(layer "B.Cu")
		(net "DDR_VDDQ")
	)
	(segment
		(start 68.736997 17.542002)
		(end 68.236973 18.042026)
		(width 0.254)
		(layer "B.Cu")
		(net "DDR_VDDQ")
	)
	(segment
		(start 66.236977 18.041976)
		(end 66.236977 18.042128)
		(width 0.254)
		(layer "B.Cu")
		(net "DDR_VDDQ")
	)
	(segment
		(start 65.228978 27.5844)
		(end 64.262 27.5844)
		(width 0.508)
		(layer "B.Cu")
		(net "DDR_VDDQ")
	)
	(segment
		(start 62.737009 9.541993)
		(end 63.236983 10.041966)
		(width 0.254)
		(layer "B.Cu")
		(net "DDR_VDDQ")
	)
	(segment
		(start 64.1604 32.004)
		(end 63.737007 31.631407)
		(width 0.508)
		(layer "B.Cu")
		(net "DDR_VDDQ")
	)
	(segment
		(start 75.051006 31.012994)
		(end 74.651006 31.412993)
		(width 0.254)
		(layer "B.Cu")
		(net "DDR_VDDQ")
	)
	(segment
		(start 63.737007 13.54201)
		(end 63.237135 14.041882)
		(width 0.254)
		(layer "B.Cu")
		(net "DDR_VDDQ")
	)
	(segment
		(start 83.05099 1.499006)
		(end 83.450989 1.099007)
		(width 0.254)
		(layer "B.Cu")
		(net "DDR_VDDQ")
	)
	(segment
		(start 68.236973 7.04215)
		(end 69.236971 7.04215)
		(width 0.254)
		(layer "B.Cu")
		(net "DDR_VDDQ")
	)
	(segment
		(start 63.737007 22.541992)
		(end 64.237006 22.041993)
		(width 0.2032)
		(layer "B.Cu")
		(net "DDR_VDDQ")
	)
	(segment
		(start 64.236981 14.042136)
		(end 64.236981 14.041984)
		(width 0.254)
		(layer "B.Cu")
		(net "DDR_VDDQ")
	)
	(segment
		(start 67.236873 13.042138)
		(end 66.737001 13.54201)
		(width 0.254)
		(layer "B.Cu")
		(net "DDR_VDDQ")
	)
	(segment
		(start 65.737003 17.542002)
		(end 66.236977 18.041976)
		(width 0.254)
		(layer "B.Cu")
		(net "DDR_VDDQ")
	)
	(segment
		(start 77.451001 25.413005)
		(end 77.051002 25.013006)
		(width 0.254)
		(layer "B.Cu")
		(net "DDR_VDDQ")
	)
	(segment
		(start 83.05099 31.012994)
		(end 83.50951 31.471514)
		(width 0.254)
		(layer "B.Cu")
		(net "DDR_VDDQ")
	)
	(segment
		(start 61.529087 18.542)
		(end 61.529087 19.334074)
		(width 0.254)
		(layer "B.Cu")
		(net "DDR_VDDQ")
	)
	(segment
		(start 83.05099 13.056006)
		(end 83.450989 12.656007)
		(width 0.254)
		(layer "B.Cu")
		(net "DDR_VDDQ")
	)
	(segment
		(start 77.451001 7.898994)
		(end 77.051002 8.298993)
		(width 0.254)
		(layer "B.Cu")
		(net "DDR_VDDQ")
	)
	(segment
		(start 77.451001 2.299005)
		(end 77.051002 1.899006)
		(width 0.254)
		(layer "B.Cu")
		(net "DDR_VDDQ")
	)
	(segment
		(start 72.65101 25.413005)
		(end 72.251011 25.013006)
		(width 0.254)
		(layer "B.Cu")
		(net "DDR_VDDQ")
	)
	(segment
		(start 79.050998 30.212995)
		(end 79.450997 30.612994)
		(width 0.254)
		(layer "B.Cu")
		(net "DDR_VDDQ")
	)
	(segment
		(start 81.450993 7.898994)
		(end 81.850992 8.298993)
		(width 0.254)
		(layer "B.Cu")
		(net "DDR_VDDQ")
	)
	(segment
		(start 71.851012 13.056006)
		(end 72.251011 13.456006)
		(width 0.254)
		(layer "B.Cu")
		(net "DDR_VDDQ")
	)
	(segment
		(start 79.050998 13.856005)
		(end 79.450997 13.456006)
		(width 0.254)
		(layer "B.Cu")
		(net "DDR_VDDQ")
	)
	(segment
		(start 61.529087 19.334074)
		(end 61.737011 19.541998)
		(width 0.254)
		(layer "B.Cu")
		(net "DDR_VDDQ")
	)
	(segment
		(start 75.051006 19.455994)
		(end 74.651006 19.855993)
		(width 0.254)
		(layer "B.Cu")
		(net "DDR_VDDQ")
	)
	(segment
		(start 72.65101 2.299005)
		(end 72.251011 1.899006)
		(width 0.254)
		(layer "B.Cu")
		(net "DDR_VDDQ")
	)
	(segment
		(start 79.050998 7.098995)
		(end 79.450997 7.498994)
		(width 0.254)
		(layer "B.Cu")
		(net "DDR_VDDQ")
	)
	(segment
		(start 83.05099 7.898994)
		(end 83.450989 8.298993)
		(width 0.254)
		(layer "B.Cu")
		(net "DDR_VDDQ")
	)
	(segment
		(start 75.851004 1.499006)
		(end 75.451005 1.099007)
		(width 0.254)
		(layer "B.Cu")
		(net "DDR_VDDQ")
	)
	(segment
		(start 69.736995 6.541999)
		(end 69.236971 7.042023)
		(width 0.254)
		(layer "B.Cu")
		(net "DDR_VDDQ")
	)
	(segment
		(start 76.651002 6.298997)
		(end 76.251003 6.698996)
		(width 0.254)
		(layer "B.Cu")
		(net "DDR_VDDQ")
	)
	(segment
		(start 81.450993 24.613006)
		(end 81.450993 23.767999)
		(width 0.254)
		(layer "B.Cu")
		(net "DDR_VDDQ")
	)
	(segment
		(start 83.05099 19.455994)
		(end 83.450989 19.855993)
		(width 0.254)
		(layer "B.Cu")
		(net "DDR_VDDQ")
	)
	(segment
		(start 64.236981 14.041984)
		(end 63.737007 13.54201)
		(width 0.254)
		(layer "B.Cu")
		(net "DDR_VDDQ")
	)
	(segment
		(start 74.251007 7.898994)
		(end 73.851008 8.298993)
		(width 0.254)
		(layer "B.Cu")
		(net "DDR_VDDQ")
	)
	(segment
		(start 77.451001 13.856005)
		(end 77.051002 13.456006)
		(width 0.254)
		(layer "B.Cu")
		(net "DDR_VDDQ")
	)
	(segment
		(start 71.851012 7.098995)
		(end 72.251011 7.498994)
		(width 0.254)
		(layer "B.Cu")
		(net "DDR_VDDQ")
	)
	(segment
		(start 74.251007 19.455994)
		(end 73.851008 19.855993)
		(width 0.254)
		(layer "B.Cu")
		(net "DDR_VDDQ")
	)
	(segment
		(start 77.451001 19.455994)
		(end 77.051002 19.855993)
		(width 0.254)
		(layer "B.Cu")
		(net "DDR_VDDQ")
	)
	(segment
		(start 76.651002 17.855997)
		(end 76.251003 18.255996)
		(width 0.254)
		(layer "B.Cu")
		(net "DDR_VDDQ")
	)
	(segment
		(start 73.451009 24.613006)
		(end 73.05101 24.213007)
		(width 0.254)
		(layer "B.Cu")
		(net "DDR_VDDQ")
	)
	(segment
		(start 64.237006 22.041993)
		(end 64.237108 22.041993)
		(width 0.2032)
		(layer "B.Cu")
		(net "DDR_VDDQ")
	)
	(segment
		(start 74.251007 13.856005)
		(end 73.851008 13.456006)
		(width 0.254)
		(layer "B.Cu")
		(net "DDR_VDDQ")
	)
	(segment
		(start 68.236973 18.042026)
		(end 68.236973 18.042128)
		(width 0.254)
		(layer "B.Cu")
		(net "DDR_VDDQ")
	)
	(segment
		(start 75.851004 24.613006)
		(end 75.451005 24.213007)
		(width 0.254)
		(layer "B.Cu")
		(net "DDR_VDDQ")
	)
	(segment
		(start 76.651002 29.412997)
		(end 76.251003 29.812996)
		(width 0.254)
		(layer "B.Cu")
		(net "DDR_VDDQ")
	)
	(segment
		(start 81.450993 31.012994)
		(end 81.850992 31.412993)
		(width 0.254)
		(layer "B.Cu")
		(net "DDR_VDDQ")
	)
	(segment
		(start 74.251007 25.413005)
		(end 73.851008 25.013006)
		(width 0.254)
		(layer "B.Cu")
		(net "DDR_VDDQ")
	)
	(segment
		(start 73.451009 31.012994)
		(end 73.05101 31.412993)
		(width 0.254)
		(layer "B.Cu")
		(net "DDR_VDDQ")
	)
	(segment
		(start 74.251007 31.012994)
		(end 73.851008 31.412993)
		(width 0.254)
		(layer "B.Cu")
		(net "DDR_VDDQ")
	)
	(segment
		(start 75.851004 13.056006)
		(end 75.451005 12.656007)
		(width 0.254)
		(layer "B.Cu")
		(net "DDR_VDDQ")
	)
	(segment
		(start 80.518 39.497)
		(end 79.121 40.894)
		(width 0.254)
		(layer "In3.Cu")
		(net "DDR_VDDQ")
	)
	(segment
		(start 80.518 34.671)
		(end 80.518 39.497)
		(width 0.254)
		(layer "In3.Cu")
		(net "DDR_VDDQ")
	)
	(segment
		(start 45.236994 17.042003)
		(end 44.736995 16.542004)
		(width 0.254)
		(layer "F.Cu")
		(net "GND")
	)
	(segment
		(start 14.877999 39.76309)
		(end 15.081809 39.9669)
		(width 0.2032)
		(layer "F.Cu")
		(net "GND")
	)
	(segment
		(start 56.736996 33.541995)
		(end 56.236997 33.041996)
		(width 0.254)
		(layer "F.Cu")
		(net "GND")
	)
	(segment
		(start 54.237001 23.041991)
		(end 53.737002 23.54199)
		(width 0.254)
		(layer "F.Cu")
		(net "GND")
	)
	(segment
		(start 16.6497 38.810895)
		(end 17.268241 38.810895)
		(width 0.2032)
		(layer "F.Cu")
		(net "GND")
	)
	(segment
		(start 56.736996 16.542004)
		(end 56.236997 17.042003)
		(width 0.254)
		(layer "F.Cu")
		(net "GND")
	)
	(segment
		(start 45.236994 6.042)
		(end 44.736995 5.542001)
		(width 0.254)
		(layer "F.Cu")
		(net "GND")
	)
	(segment
		(start 66.548 45.212)
		(end 66.802 44.958)
		(width 0.2032)
		(layer "F.Cu")
		(net "GND")
	)
	(segment
		(start 16.6497 37.211)
		(end 15.875 37.211)
		(width 0.2032)
		(layer "F.Cu")
		(net "GND")
	)
	(segment
		(start 3.937 19.812)
		(end 5.1181 19.812)
		(width 0.508)
		(layer "F.Cu")
		(net "GND")
	)
	(segment
		(start 49.237011 18.042001)
		(end 48.737012 17.542002)
		(width 0.254)
		(layer "F.Cu")
		(net "GND")
	)
	(segment
		(start 42.237 7.041998)
		(end 42.237 6.042)
		(width 0.254)
		(layer "F.Cu")
		(net "GND")
	)
	(segment
		(start 15.227198 40.093773)
		(end 15.5321 40.297075)
		(width 0.381)
		(layer "F.Cu")
		(net "GND")
	)
	(segment
		(start 53.237003 26.04201)
		(end 52.737004 26.542009)
		(width 0.254)
		(layer "F.Cu")
		(net "GND")
	)
	(segment
		(start 42.237 22.041993)
		(end 41.737001 22.541992)
		(width 0.254)
		(layer "F.Cu")
		(net "GND")
	)
	(segment
		(start 40.237004 25.042012)
		(end 39.737005 25.542011)
		(width 0.254)
		(layer "F.Cu")
		(net "GND")
	)
	(segment
		(start 49.237011 6.042)
		(end 49.73701 5.542001)
		(width 0.254)
		(layer "F.Cu")
		(net "GND")
	)
	(segment
		(start 49.237011 20.041997)
		(end 48.737012 20.541996)
		(width 0.254)
		(layer "F.Cu")
		(net "GND")
	)
	(segment
		(start 75.4761 8.324088)
		(end 75.451005 8.298993)
		(width 0.254)
		(layer "F.Cu")
		(net "GND")
	)
	(segment
		(start 56.736996 10.541991)
		(end 56.236997 11.04199)
		(width 0.254)
		(layer "F.Cu")
		(net "GND")
	)
	(segment
		(start 61.737011 31.541999)
		(end 61.237012 31.042)
		(width 0.254)
		(layer "F.Cu")
		(net "GND")
	)
	(segment
		(start 64.250062 51.143916)
		(end 64.250062 50.534062)
		(width 0.2032)
		(layer "F.Cu")
		(net "GND")
	)
	(segment
		(start 53.237003 3.042006)
		(end 52.737004 2.542007)
		(width 0.254)
		(layer "F.Cu")
		(net "GND")
	)
	(segment
		(start 57.736994 30.542001)
		(end 57.236995 30.042002)
		(width 0.254)
		(layer "F.Cu")
		(net "GND")
	)
	(segment
		(start 56.736996 29.542003)
		(end 56.236997 29.042004)
		(width 0.254)
		(layer "F.Cu")
		(net "GND")
	)
	(segment
		(start 81.153 42.0116)
		(end 81.070399 41.928999)
		(width 0.2032)
		(layer "F.Cu")
		(net "GND")
	)
	(segment
		(start 68.736997 3.542005)
		(end 69.236996 4.042004)
		(width 0.508)
		(layer "F.Cu")
		(net "GND")
	)
	(segment
		(start 54.237001 8.041996)
		(end 53.737002 7.541997)
		(width 0.254)
		(layer "F.Cu")
		(net "GND")
	)
	(segment
		(start 54.237001 15.042007)
		(end 53.737002 14.542008)
		(width 0.254)
		(layer "F.Cu")
		(net "GND")
	)
	(segment
		(start 80.2386 48.387)
		(end 79.9719 48.1203)
		(width 0.508)
		(layer "F.Cu")
		(net "GND")
	)
	(segment
		(start 18.542 1.7399)
		(end 18.542 2.159)
		(width 0.254)
		(layer "F.Cu")
		(net "GND")
	)
	(segment
		(start 56.736996 31.541999)
		(end 56.236997 31.042)
		(width 0.254)
		(layer "F.Cu")
		(net "GND")
	)
	(segment
		(start 48.236988 8.041996)
		(end 48.736987 7.541997)
		(width 0.254)
		(layer "F.Cu")
		(net "GND")
	)
	(segment
		(start 62.737009 8.541995)
		(end 62.23701 9.041994)
		(width 0.254)
		(layer "F.Cu")
		(net "GND")
	)
	(segment
		(start 17.072178 34.474277)
		(end 17.072178 35.124822)
		(width 0.508)
		(layer "F.Cu")
		(net "GND")
	)
	(segment
		(start 80.2259 11.811)
		(end 80.264 11.8491)
		(width 0.254)
		(layer "F.Cu")
		(net "GND")
	)
	(segment
		(start 15.081809 39.9669)
		(end 15.100325 39.9669)
		(width 0.2032)
		(layer "F.Cu")
		(net "GND")
	)
	(segment
		(start 47.0789 46.609)
		(end 47.0789 44.674663)
		(width 0.2032)
		(layer "F.Cu")
		(net "GND")
	)
	(segment
		(start 17.097477 48.7045)
		(end 16.51 48.7045)
		(width 0.2032)
		(layer "F.Cu")
		(net "GND")
	)
	(segment
		(start 47.23699 20.041997)
		(end 46.736991 20.541996)
		(width 0.254)
		(layer "F.Cu")
		(net "GND")
	)
	(segment
		(start 43.236998 6.042)
		(end 42.736999 5.542001)
		(width 0.254)
		(layer "F.Cu")
		(net "GND")
	)
	(segment
		(start 79.9719 48.1203)
		(end 79.9719 47.752)
		(width 0.508)
		(layer "F.Cu")
		(net "GND")
	)
	(segment
		(start 76.327 12.58001)
		(end 76.251003 12.656007)
		(width 0.254)
		(layer "F.Cu")
		(net "GND")
	)
	(segment
		(start 75.4761 32.258)
		(end 75.4761 31.438088)
		(width 0.254)
		(layer "F.Cu")
		(net "GND")
	)
	(segment
		(start 61.737011 30.542001)
		(end 61.237012 30.042002)
		(width 0.254)
		(layer "F.Cu")
		(net "GND")
	)
	(segment
		(start 56.736996 2.542007)
		(end 57.236995 3.042006)
		(width 0.254)
		(layer "F.Cu")
		(net "GND")
	)
	(segment
		(start 75.4761 20.574)
		(end 75.4761 19.881088)
		(width 0.254)
		(layer "F.Cu")
		(net "GND")
	)
	(segment
		(start 41.237002 5.042002)
		(end 40.737003 4.542003)
		(width 0.254)
		(layer "F.Cu")
		(net "GND")
	)
	(segment
		(start 75.5269 5.2451)
		(end 75.7809 4.9911)
		(width 0.254)
		(layer "F.Cu")
		(net "GND")
	)
	(segment
		(start 73.914 45.3009)
		(end 73.4949 45.3009)
		(width 0.508)
		(layer "F.Cu")
		(net "GND")
	)
	(segment
		(start 67.237 7.041998)
		(end 67.237 8.041996)
		(width 0.254)
		(layer "F.Cu")
		(net "GND")
	)
	(segment
		(start 59.73699 26.542009)
		(end 59.236991 26.04201)
		(width 0.254)
		(layer "F.Cu")
		(net "GND")
	)
	(segment
		(start 46.236992 15.042007)
		(end 45.736993 14.542008)
		(width 0.254)
		(layer "F.Cu")
		(net "GND")
	)
	(segment
		(start 10.5029 39.9161)
		(end 11.237443 39.181557)
		(width 0.508)
		(layer "F.Cu")
		(net "GND")
	)
	(segment
		(start 77.978 7.4549)
		(end 78.606904 7.4549)
		(width 0.254)
		(layer "F.Cu")
		(net "GND")
	)
	(segment
		(start 45.236994 12.041988)
		(end 44.736995 11.541989)
		(width 0.254)
		(layer "F.Cu")
		(net "GND")
	)
	(segment
		(start 57.736994 26.542009)
		(end 57.236995 26.04201)
		(width 0.254)
		(layer "F.Cu")
		(net "GND")
	)
	(segment
		(start 16.129 48.3235)
		(end 16.51 48.7045)
		(width 0.508)
		(layer "F.Cu")
		(net "GND")
	)
	(segment
		(start 45.236994 28.042006)
		(end 44.736995 28.542005)
		(width 0.254)
		(layer "F.Cu")
		(net "GND")
	)
	(segment
		(start 18.7579 4.318)
		(end 18.7579 5.08)
		(width 0.254)
		(layer "F.Cu")
		(net "GND")
	)
	(segment
		(start 11.7221 37.4269)
		(end 11.43 37.719)
		(width 0.2032)
		(layer "F.Cu")
		(net "GND")
	)
	(segment
		(start 59.73699 32.541997)
		(end 59.236991 32.041998)
		(width 0.254)
		(layer "F.Cu")
		(net "GND")
	)
	(segment
		(start 46.726577 52.2351)
		(end 45.974 52.2351)
		(width 0.2032)
		(layer "F.Cu")
		(net "GND")
	)
	(segment
		(start 11.43 35.179)
		(end 11.0109 34.7599)
		(width 0.508)
		(layer "F.Cu")
		(net "GND")
	)
	(segment
		(start 54.237001 21.041995)
		(end 53.737002 21.541994)
		(width 0.254)
		(layer "F.Cu")
		(net "GND")
	)
	(segment
		(start 53.237003 30.042002)
		(end 52.737004 30.542001)
		(width 0.254)
		(layer "F.Cu")
		(net "GND")
	)
	(segment
		(start 5.334 6.985)
		(end 5.334 5.8039)
		(width 0.508)
		(layer "F.Cu")
		(net "GND")
	)
	(segment
		(start 54.237001 19.041999)
		(end 53.737002 19.541998)
		(width 0.254)
		(layer "F.Cu")
		(net "GND")
	)
	(segment
		(start 53.237003 28.042006)
		(end 52.737004 28.542005)
		(width 0.254)
		(layer "F.Cu")
		(net "GND")
	)
	(segment
		(start 82.435598 43.0276)
		(end 82.435598 42.328998)
		(width 0.2032)
		(layer "F.Cu")
		(net "GND")
	)
	(segment
		(start 77.851 26.1239)
		(end 77.851 25.1841)
		(width 0.254)
		(layer "F.Cu")
		(net "GND")
	)
	(segment
		(start 15.748 29.0195)
		(end 13.5255 29.0195)
		(width 0.508)
		(layer "F.Cu")
		(net "GND")
	)
	(segment
		(start 76.327 11.9761)
		(end 76.327 12.58001)
		(width 0.254)
		(layer "F.Cu")
		(net "GND")
	)
	(segment
		(start 40.237004 29.042004)
		(end 39.737005 29.542003)
		(width 0.254)
		(layer "F.Cu")
		(net "GND")
	)
	(segment
		(start 75.4761 31.438088)
		(end 75.451005 31.412993)
		(width 0.254)
		(layer "F.Cu")
		(net "GND")
	)
	(segment
		(start 62.140084 50.033936)
		(end 62.733936 50.033936)
		(width 0.2032)
		(layer "F.Cu")
		(net "GND")
	)
	(segment
		(start 66.737001 4.542003)
		(end 66.237002 5.042002)
		(width 0.254)
		(layer "F.Cu")
		(net "GND")
	)
	(segment
		(start 75.4761 9.017)
		(end 75.4761 8.324088)
		(width 0.254)
		(layer "F.Cu")
		(net "GND")
	)
	(segment
		(start 58.736992 31.541999)
		(end 58.236993 31.042)
		(width 0.254)
		(layer "F.Cu")
		(net "GND")
	)
	(segment
		(start 77.6859 4.9911)
		(end 78.486 4.191)
		(width 0.254)
		(layer "F.Cu")
		(net "GND")
	)
	(segment
		(start 60.736988 4.542003)
		(end 60.236989 5.042002)
		(width 0.254)
		(layer "F.Cu")
		(net "GND")
	)
	(segment
		(start 54.237001 33.041996)
		(end 53.737002 33.541995)
		(width 0.254)
		(layer "F.Cu")
		(net "GND")
	)
	(segment
		(start 49.237011 16.042005)
		(end 48.737012 15.542006)
		(width 0.254)
		(layer "F.Cu")
		(net "GND")
	)
	(segment
		(start 22.987 3.937)
		(end 23.237012 4.187012)
		(width 0.254)
		(layer "F.Cu")
		(net "GND")
	)
	(segment
		(start 65.237004 8.041996)
		(end 65.237004 7.041998)
		(width 0.254)
		(layer "F.Cu")
		(net "GND")
	)
	(segment
		(start 51.237007 18.042001)
		(end 50.737008 17.542002)
		(width 0.254)
		(layer "F.Cu")
		(net "GND")
	)
	(segment
		(start 18.7579 5.08)
		(end 18.8849 5.207)
		(width 0.254)
		(layer "F.Cu")
		(net "GND")
	)
	(segment
		(start 80.264 11.8491)
		(end 80.264 12.446)
		(width 0.254)
		(layer "F.Cu")
		(net "GND")
	)
	(segment
		(start 59.73699 22.541992)
		(end 59.236991 22.041993)
		(width 0.254)
		(layer "F.Cu")
		(net "GND")
	)
	(segment
		(start 54.237001 17.042003)
		(end 53.737002 16.542004)
		(width 0.254)
		(layer "F.Cu")
		(net "GND")
	)
	(segment
		(start 52.237005 27.042008)
		(end 51.737006 27.542007)
		(width 0.254)
		(layer "F.Cu")
		(net "GND")
	)
	(segment
		(start 52.237005 21.041995)
		(end 51.737006 21.541994)
		(width 0.254)
		(layer "F.Cu")
		(net "GND")
	)
	(segment
		(start 48.236988 27.042008)
		(end 47.736989 27.542007)
		(width 0.254)
		(layer "F.Cu")
		(net "GND")
	)
	(segment
		(start 68.736997 7.541997)
		(end 68.236998 8.041996)
		(width 0.254)
		(layer "F.Cu")
		(net "GND")
	)
	(segment
		(start 17.268241 38.810895)
		(end 17.272 38.814654)
		(width 0.2032)
		(layer "F.Cu")
		(net "GND")
	)
	(segment
		(start 41.91 47.2059)
		(end 42.6339 47.2059)
		(width 0.2032)
		(layer "F.Cu")
		(net "GND")
	)
	(segment
		(start 81.0387 32.8803)
		(end 80.923486 32.995514)
		(width 0.254)
		(layer "F.Cu")
		(net "GND")
	)
	(segment
		(start 49.237011 26.04201)
		(end 48.737012 26.542009)
		(width 0.254)
		(layer "F.Cu")
		(net "GND")
	)
	(segment
		(start 83.312 37.5539)
		(end 82.423 37.5539)
		(width 0.2032)
		(layer "F.Cu")
		(net "GND")
	)
	(segment
		(start 28.1686 38.850011)
		(end 29.325011 38.850011)
		(width 0.2032)
		(layer "F.Cu")
		(net "GND")
	)
	(segment
		(start 62.737009 7.541997)
		(end 62.23701 8.041996)
		(width 0.254)
		(layer "F.Cu")
		(net "GND")
	)
	(segment
		(start 56.736996 12.542012)
		(end 56.236997 13.042011)
		(width 0.254)
		(layer "F.Cu")
		(net "GND")
	)
	(segment
		(start 56.736996 21.541994)
		(end 56.236997 21.041995)
		(width 0.254)
		(layer "F.Cu")
		(net "GND")
	)
	(segment
		(start 75.5269 5.715)
		(end 75.5269 5.2451)
		(width 0.254)
		(layer "F.Cu")
		(net "GND")
	)
	(segment
		(start 50.237009 23.041991)
		(end 49.73701 23.54199)
		(width 0.254)
		(layer "F.Cu")
		(net "GND")
	)
	(segment
		(start 5.334 19.3167)
		(end 5.334 20.701)
		(width 0.508)
		(layer "F.Cu")
		(net "GND")
	)
	(segment
		(start 65.737003 8.541995)
		(end 65.237004 9.041994)
		(width 0.254)
		(layer "F.Cu")
		(net "GND")
	)
	(segment
		(start 56.736996 23.54199)
		(end 56.236997 23.041991)
		(width 0.254)
		(layer "F.Cu")
		(net "GND")
	)
	(segment
		(start 44.236996 15.042007)
		(end 43.736997 14.542008)
		(width 0.254)
		(layer "F.Cu")
		(net "GND")
	)
	(segment
		(start 60.736988 10.541991)
		(end 60.236989 11.04199)
		(width 0.254)
		(layer "F.Cu")
		(net "GND")
	)
	(segment
		(start 43.236998 19.041999)
		(end 42.736999 19.541998)
		(width 0.254)
		(layer "F.Cu")
		(net "GND")
	)
	(segment
		(start 43.688 49.99736)
		(end 44.91736 49.99736)
		(width 0.2032)
		(layer "F.Cu")
		(net "GND")
	)
	(segment
		(start 46.236992 29.042004)
		(end 45.736993 29.542003)
		(width 0.254)
		(layer "F.Cu")
		(net "GND")
	)
	(segment
		(start 82.1182 42.0116)
		(end 81.6356 41.529)
		(width 0.2032)
		(layer "F.Cu")
		(net "GND")
	)
	(segment
		(start 14.877999 39.3827)
		(end 14.877999 39.76309)
		(width 0.2032)
		(layer "F.Cu")
		(net "GND")
	)
	(segment
		(start 4.953 21.082)
		(end 3.937 21.082)
		(width 0.508)
		(layer "F.Cu")
		(net "GND")
	)
	(segment
		(start 29.8831 20.7137)
		(end 29.8831 21.60811)
		(width 0.127)
		(layer "F.Cu")
		(net "GND")
	)
	(segment
		(start 48.236988 29.042004)
		(end 47.736989 29.542003)
		(width 0.254)
		(layer "F.Cu")
		(net "GND")
	)
	(segment
		(start 47.23699 16.042005)
		(end 46.736991 15.542006)
		(width 0.254)
		(layer "F.Cu")
		(net "GND")
	)
	(segment
		(start 58.736992 29.542003)
		(end 58.236993 29.042004)
		(width 0.254)
		(layer "F.Cu")
		(net "GND")
	)
	(segment
		(start 61.237012 7.041998)
		(end 62.23701 7.041998)
		(width 0.254)
		(layer "F.Cu")
		(net "GND")
	)
	(segment
		(start 67.736999 5.542001)
		(end 67.237 6.042)
		(width 0.254)
		(layer "F.Cu")
		(net "GND")
	)
	(segment
		(start 48.236988 7.041998)
		(end 49.237011 7.041998)
		(width 0.254)
		(layer "F.Cu")
		(net "GND")
	)
	(segment
		(start 73.9521 12.554915)
		(end 73.851008 12.656007)
		(width 0.254)
		(layer "F.Cu")
		(net "GND")
	)
	(segment
		(start 25.527 28.9179)
		(end 24.384 28.9179)
		(width 0.2032)
		(layer "F.Cu")
		(net "GND")
	)
	(segment
		(start 66.737001 34.541993)
		(end 66.237002 34.041994)
		(width 0.254)
		(layer "F.Cu")
		(net "GND")
	)
	(segment
		(start 49.237011 34.041994)
		(end 48.737012 34.541993)
		(width 0.254)
		(layer "F.Cu")
		(net "GND")
	)
	(segment
		(start 11.868201 37.280799)
		(end 11.856009 37.280799)
		(width 0.2032)
		(layer "F.Cu")
		(net "GND")
	)
	(segment
		(start 60.736988 12.542012)
		(end 60.236989 13.042011)
		(width 0.254)
		(layer "F.Cu")
		(net "GND")
	)
	(segment
		(start 80.923486 32.995514)
		(end 80.137 32.995514)
		(width 0.254)
		(layer "F.Cu")
		(net "GND")
	)
	(segment
		(start 66.737001 21.541994)
		(end 66.237002 21.041995)
		(width 0.254)
		(layer "F.Cu")
		(net "GND")
	)
	(segment
		(start 64.737005 34.541993)
		(end 64.237006 34.041994)
		(width 0.254)
		(layer "F.Cu")
		(net "GND")
	)
	(segment
		(start 54.737 2.542007)
		(end 55.236999 3.042006)
		(width 0.254)
		(layer "F.Cu")
		(net "GND")
	)
	(segment
		(start 56.736996 14.542008)
		(end 56.236997 15.042007)
		(width 0.254)
		(layer "F.Cu")
		(net "GND")
	)
	(segment
		(start 41.237002 7.041998)
		(end 40.737003 6.541999)
		(width 0.254)
		(layer "F.Cu")
		(net "GND")
	)
	(segment
		(start 58.736992 16.542004)
		(end 58.236993 17.042003)
		(width 0.254)
		(layer "F.Cu")
		(net "GND")
	)
	(segment
		(start 55.736998 28.542005)
		(end 55.236999 28.042006)
		(width 0.254)
		(layer "F.Cu")
		(net "GND")
	)
	(segment
		(start 44.236996 24.041989)
		(end 43.736997 24.541988)
		(width 0.254)
		(layer "F.Cu")
		(net "GND")
	)
	(segment
		(start 53.237003 32.041998)
		(end 52.737004 32.541997)
		(width 0.254)
		(layer "F.Cu")
		(net "GND")
	)
	(segment
		(start 59.73699 28.542005)
		(end 59.236991 28.042006)
		(width 0.254)
		(layer "F.Cu")
		(net "GND")
	)
	(segment
		(start 46.236992 27.042008)
		(end 45.736993 27.542007)
		(width 0.254)
		(layer "F.Cu")
		(net "GND")
	)
	(segment
		(start 14.97965 34.2392)
		(end 14.877999 34.505951)
		(width 0.2032)
		(layer "F.Cu")
		(net "GND")
	)
	(segment
		(start 15.100325 39.9669)
		(end 15.227198 40.093773)
		(width 0.2032)
		(layer "F.Cu")
		(net "GND")
	)
	(segment
		(start 48.236988 33.041996)
		(end 47.736989 33.541995)
		(width 0.254)
		(layer "F.Cu")
		(net "GND")
	)
	(segment
		(start 10.2235 47.752)
		(end 11.43 48.9585)
		(width 0.508)
		(layer "F.Cu")
		(net "GND")
	)
	(segment
		(start 48.2346 52.1716)
		(end 47.879 52.2986)
		(width 0.2032)
		(layer "F.Cu")
		(net "GND")
	)
	(segment
		(start 60.736988 16.542004)
		(end 60.236989 17.042003)
		(width 0.254)
		(layer "F.Cu")
		(net "GND")
	)
	(segment
		(start 21.720988 32.642988)
		(end 20.9042 32.642988)
		(width 0.2032)
		(layer "F.Cu")
		(net "GND")
	)
	(segment
		(start 14.877999 34.505951)
		(end 14.877999 35.0393)
		(width 0.2032)
		(layer "F.Cu")
		(net "GND")
	)
	(segment
		(start 23.237012 4.187012)
		(end 24.0538 4.187012)
		(width 0.254)
		(layer "F.Cu")
		(net "GND")
	)
	(segment
		(start 64.237006 6.042)
		(end 64.237006 7.041998)
		(width 0.254)
		(layer "F.Cu")
		(net "GND")
	)
	(segment
		(start 59.73699 5.542001)
		(end 59.236991 6.042)
		(width 0.254)
		(layer "F.Cu")
		(net "GND")
	)
	(segment
		(start 74.93 5.715)
		(end 74.803 5.588)
		(width 0.254)
		(layer "F.Cu")
		(net "GND")
	)
	(segment
		(start 48.236988 25.042012)
		(end 47.736989 25.542011)
		(width 0.254)
		(layer "F.Cu")
		(net "GND")
	)
	(segment
		(start 66.237002 7.041998)
		(end 67.237 7.041998)
		(width 0.254)
		(layer "F.Cu")
		(net "GND")
	)
	(segment
		(start 47.23699 22.041993)
		(end 46.736991 22.541992)
		(width 0.254)
		(layer "F.Cu")
		(net "GND")
	)
	(segment
		(start 73.8251 23.495)
		(end 73.8251 24.187099)
		(width 0.254)
		(layer "F.Cu")
		(net "GND")
	)
	(segment
		(start 84.2391 50.419)
		(end 85.217 50.419)
		(width 0.508)
		(layer "F.Cu")
		(net "GND")
	)
	(segment
		(start 44.236996 10.041992)
		(end 43.736997 9.541993)
		(width 0.254)
		(layer "F.Cu")
		(net "GND")
	)
	(segment
		(start 46.236992 31.042)
		(end 45.736993 31.541999)
		(width 0.254)
		(layer "F.Cu")
		(net "GND")
	)
	(segment
		(start 60.736988 33.541995)
		(end 60.236989 33.041996)
		(width 0.254)
		(layer "F.Cu")
		(net "GND")
	)
	(segment
		(start 32.889012 8.8773)
		(end 32.889012 8.004988)
		(width 0.2032)
		(layer "F.Cu")
		(net "GND")
	)
	(segment
		(start 60.736988 14.542008)
		(end 60.236989 15.042007)
		(width 0.254)
		(layer "F.Cu")
		(net "GND")
	)
	(segment
		(start 55.736998 24.541988)
		(end 55.236999 24.041989)
		(width 0.254)
		(layer "F.Cu")
		(net "GND")
	)
	(segment
		(start 47.23699 9.041994)
		(end 46.736991 8.541995)
		(width 0.254)
		(layer "F.Cu")
		(net "GND")
	)
	(segment
		(start 32.74601 21.770924)
		(end 32.74601 22.048394)
		(width 0.127)
		(layer "F.Cu")
		(net "GND")
	)
	(segment
		(start 13.5255 29.0195)
		(end 13.208 28.702)
		(width 0.508)
		(layer "F.Cu")
		(net "GND")
	)
	(segment
		(start 55.736998 13.54201)
		(end 55.236999 14.042009)
		(width 0.254)
		(layer "F.Cu")
		(net "GND")
	)
	(segment
		(start 69.736995 5.542001)
		(end 69.236996 6.042)
		(width 0.254)
		(layer "F.Cu")
		(net "GND")
	)
	(segment
		(start 61.737011 28.542005)
		(end 61.237012 28.042006)
		(width 0.254)
		(layer "F.Cu")
		(net "GND")
	)
	(segment
		(start 70.736993 32.541997)
		(end 70.236994 32.041998)
		(width 0.508)
		(layer "F.Cu")
		(net "GND")
	)
	(segment
		(start 17.580077 49.1871)
		(end 17.097477 48.7045)
		(width 0.2032)
		(layer "F.Cu")
		(net "GND")
	)
	(segment
		(start 52.237005 33.041996)
		(end 51.737006 33.541995)
		(width 0.254)
		(layer "F.Cu")
		(net "GND")
	)
	(segment
		(start 16.712895 35.611105)
		(end 16.6497 35.611105)
		(width 0.2032)
		(layer "F.Cu")
		(net "GND")
	)
	(segment
		(start 54.237001 31.042)
		(end 53.737002 31.541999)
		(width 0.254)
		(layer "F.Cu")
		(net "GND")
	)
	(segment
		(start 41.237002 3.042006)
		(end 41.737001 2.542007)
		(width 0.508)
		(layer "F.Cu")
		(net "GND")
	)
	(segment
		(start 60.236989 6.042)
		(end 60.236989 7.041998)
		(width 0.254)
		(layer "F.Cu")
		(net "GND")
	)
	(segment
		(start 33.389011 7.735011)
		(end 33.274 7.62)
		(width 0.2032)
		(layer "F.Cu")
		(net "GND")
	)
	(segment
		(start 44.236996 16.042005)
		(end 43.736997 15.542006)
		(width 0.254)
		(layer "F.Cu")
		(net "GND")
	)
	(segment
		(start 16.129 47.498)
		(end 16.129 48.3235)
		(width 0.508)
		(layer "F.Cu")
		(net "GND")
	)
	(segment
		(start 61.737011 29.542003)
		(end 61.237012 29.042004)
		(width 0.254)
		(layer "F.Cu")
		(net "GND")
	)
	(segment
		(start 73.8251 24.187099)
		(end 73.851008 24.213007)
		(width 0.254)
		(layer "F.Cu")
		(net "GND")
	)
	(segment
		(start 58.736992 4.542003)
		(end 58.236993 5.042002)
		(width 0.254)
		(layer "F.Cu")
		(net "GND")
	)
	(segment
		(start 40.237004 4.042004)
		(end 39.737005 3.542005)
		(width 0.508)
		(layer "F.Cu")
		(net "GND")
	)
	(segment
		(start 48.236988 5.042002)
		(end 47.736989 4.542003)
		(width 0.254)
		(layer "F.Cu")
		(net "GND")
	)
	(segment
		(start 58.736992 27.542007)
		(end 58.236993 27.042008)
		(width 0.254)
		(layer "F.Cu")
		(net "GND")
	)
	(segment
		(start 55.736998 34.541993)
		(end 55.236999 34.041994)
		(width 0.254)
		(layer "F.Cu")
		(net "GND")
	)
	(segment
		(start 11.5824 28.194)
		(end 12.0904 28.702)
		(width 0.508)
		(layer "F.Cu")
		(net "GND")
	)
	(segment
		(start 22.098 28.9179)
		(end 23.241 28.9179)
		(width 0.2032)
		(layer "F.Cu")
		(net "GND")
	)
	(segment
		(start 50.237009 27.042008)
		(end 49.73701 27.542007)
		(width 0.254)
		(layer "F.Cu")
		(net "GND")
	)
	(segment
		(start 44.236996 27.042008)
		(end 43.736997 27.542007)
		(width 0.254)
		(layer "F.Cu")
		(net "GND")
	)
	(segment
		(start 52.237005 11.04199)
		(end 51.737006 10.541991)
		(width 0.254)
		(layer "F.Cu")
		(net "GND")
	)
	(segment
		(start 52.237005 31.042)
		(end 51.737006 31.541999)
		(width 0.254)
		(layer "F.Cu")
		(net "GND")
	)
	(segment
		(start 50.237009 29.042004)
		(end 49.73701 29.542003)
		(width 0.254)
		(layer "F.Cu")
		(net "GND")
	)
	(segment
		(start 59.73699 24.541988)
		(end 59.236991 24.041989)
		(width 0.254)
		(layer "F.Cu")
		(net "GND")
	)
	(segment
		(start 51.237007 12.041988)
		(end 50.737008 11.541989)
		(width 0.254)
		(layer "F.Cu")
		(net "GND")
	)
	(segment
		(start 51.237007 30.042002)
		(end 50.737008 30.542001)
		(width 0.254)
		(layer "F.Cu")
		(net "GND")
	)
	(segment
		(start 32.74601 28.87439)
		(end 31.877 29.7434)
		(width 0.14732)
		(layer "F.Cu")
		(net "GND")
	)
	(segment
		(start 52.237005 23.041991)
		(end 51.737006 23.54199)
		(width 0.254)
		(layer "F.Cu")
		(net "GND")
	)
	(segment
		(start 57.736994 28.542005)
		(end 57.236995 28.042006)
		(width 0.254)
		(layer "F.Cu")
		(net "GND")
	)
	(segment
		(start 60.736988 21.541994)
		(end 60.236989 21.041995)
		(width 0.254)
		(layer "F.Cu")
		(net "GND")
	)
	(segment
		(start 78.486 4.191)
		(end 78.5749 4.191)
		(width 0.254)
		(layer "F.Cu")
		(net "GND")
	)
	(segment
		(start 50.237009 21.041995)
		(end 49.73701 21.541994)
		(width 0.254)
		(layer "F.Cu")
		(net "GND")
	)
	(segment
		(start 60.736988 8.541995)
		(end 60.236989 9.041994)
		(width 0.254)
		(layer "F.Cu")
		(net "GND")
	)
	(segment
		(start 80.2386 49.53)
		(end 80.2386 48.387)
		(width 0.508)
		(layer "F.Cu")
		(net "GND")
	)
	(segment
		(start 74.2442 42.164)
		(end 73.406 42.799)
		(width 0.254)
		(layer "F.Cu")
		(net "GND")
	)
	(segment
		(start 64.237006 7.041998)
		(end 63.237008 7.041998)
		(width 0.254)
		(layer "F.Cu")
		(net "GND")
	)
	(segment
		(start 45.085 52.2351)
		(end 45.974 52.2351)
		(width 0.2032)
		(layer "F.Cu")
		(net "GND")
	)
	(segment
		(start 52.237005 13.042011)
		(end 51.737006 12.542012)
		(width 0.254)
		(layer "F.Cu")
		(net "GND")
	)
	(segment
		(start 80.391 20.066)
		(end 80.391 20.4089)
		(width 0.254)
		(layer "F.Cu")
		(net "GND")
	)
	(segment
		(start 13.335 37.211)
		(end 12.3063 37.211)
		(width 0.2032)
		(layer "F.Cu")
		(net "GND")
	)
	(segment
		(start 44.236996 5.042002)
		(end 43.736997 4.542003)
		(width 0.254)
		(layer "F.Cu")
		(net "GND")
	)
	(segment
		(start 17.653 39.116)
		(end 18.8595 40.3225)
		(width 0.508)
		(layer "F.Cu")
		(net "GND")
	)
	(segment
		(start 63.737007 8.541995)
		(end 63.237008 9.041994)
		(width 0.254)
		(layer "F.Cu")
		(net "GND")
	)
	(segment
		(start 73.851008 29.957751)
		(end 73.851008 30.612994)
		(width 0.254)
		(layer "F.Cu")
		(net "GND")
	)
	(segment
		(start 45.236994 9.041994)
		(end 44.736995 8.541995)
		(width 0.254)
		(layer "F.Cu")
		(net "GND")
	)
	(segment
		(start 49.237011 28.042006)
		(end 48.737012 28.542005)
		(width 0.254)
		(layer "F.Cu")
		(net "GND")
	)
	(segment
		(start 39.237006 4.042004)
		(end 38.737007 3.542005)
		(width 0.508)
		(layer "F.Cu")
		(net "GND")
	)
	(segment
		(start 58.736992 23.54199)
		(end 58.236993 23.041991)
		(width 0.254)
		(layer "F.Cu")
		(net "GND")
	)
	(segment
		(start 33.389011 8.8773)
		(end 33.389011 7.735011)
		(width 0.2032)
		(layer "F.Cu")
		(net "GND")
	)
	(segment
		(start 26.2509 40.386)
		(end 26.2509 41.275)
		(width 0.2032)
		(layer "F.Cu")
		(net "GND")
	)
	(segment
		(start 63.737007 29.542003)
		(end 63.237008 29.042004)
		(width 0.254)
		(layer "F.Cu")
		(net "GND")
	)
	(segment
		(start 48.236988 11.04199)
		(end 47.736989 10.541991)
		(width 0.254)
		(layer "F.Cu")
		(net "GND")
	)
	(segment
		(start 5.334 20.701)
		(end 4.953 21.082)
		(width 0.508)
		(layer "F.Cu")
		(net "GND")
	)
	(segment
		(start 81.050994 8.298993)
		(end 81.050994 8.531174)
		(width 0.254)
		(layer "F.Cu")
		(net "GND")
	)
	(segment
		(start 15.5321 40.297075)
		(end 15.5321 40.894)
		(width 0.381)
		(layer "F.Cu")
		(net "GND")
	)
	(segment
		(start 78.4479 19.812)
		(end 78.4479 20.574)
		(width 0.254)
		(layer "F.Cu")
		(net "GND")
	)
	(segment
		(start 61.737011 2.542007)
		(end 61.237012 3.042006)
		(width 0.254)
		(layer "F.Cu")
		(net "GND")
	)
	(segment
		(start 69.736995 12.542012)
		(end 69.236996 13.042011)
		(width 0.254)
		(layer "F.Cu")
		(net "GND")
	)
	(segment
		(start 67.736999 29.542003)
		(end 67.237 29.042004)
		(width 0.254)
		(layer "F.Cu")
		(net "GND")
	)
	(segment
		(start 52.237005 8.041996)
		(end 51.737006 7.541997)
		(width 0.254)
		(layer "F.Cu")
		(net "GND")
	)
	(segment
		(start 50.237009 5.042002)
		(end 49.73701 4.542003)
		(width 0.254)
		(layer "F.Cu")
		(net "GND")
	)
	(segment
		(start 66.737001 7.541997)
		(end 66.237002 8.041996)
		(width 0.254)
		(layer "F.Cu")
		(net "GND")
	)
	(segment
		(start 53.237003 24.041989)
		(end 52.737004 24.541988)
		(width 0.254)
		(layer "F.Cu")
		(net "GND")
	)
	(segment
		(start 11.608105 38.810895)
		(end 12.3063 38.810895)
		(width 0.2032)
		(layer "F.Cu")
		(net "GND")
	)
	(segment
		(start 47.23699 3.042006)
		(end 46.736991 2.542007)
		(width 0.254)
		(layer "F.Cu")
		(net "GND")
	)
	(segment
		(start 52.237005 5.042002)
		(end 51.737006 4.542003)
		(width 0.254)
		(layer "F.Cu")
		(net "GND")
	)
	(segment
		(start 42.6339 47.2059)
		(end 42.672 47.244)
		(width 0.2032)
		(layer "F.Cu")
		(net "GND")
	)
	(segment
		(start 51.237007 3.042006)
		(end 50.737008 2.542007)
		(width 0.254)
		(layer "F.Cu")
		(net "GND")
	)
	(segment
		(start 64.237006 7.041998)
		(end 65.237004 7.041998)
		(width 0.254)
		(layer "F.Cu")
		(net "GND")
	)
	(segment
		(start 46.236992 21.041995)
		(end 45.736993 21.541994)
		(width 0.254)
		(layer "F.Cu")
		(net "GND")
	)
	(segment
		(start 50.237009 13.042011)
		(end 49.73701 12.542012)
		(width 0.254)
		(layer "F.Cu")
		(net "GND")
	)
	(segment
		(start 50.237009 15.042007)
		(end 49.73701 14.542008)
		(width 0.254)
		(layer "F.Cu")
		(net "GND")
	)
	(segment
		(start 60.736988 19.541998)
		(end 60.236989 19.041999)
		(width 0.254)
		(layer "F.Cu")
		(net "GND")
	)
	(segment
		(start 47.23699 30.042002)
		(end 46.736991 30.542001)
		(width 0.254)
		(layer "F.Cu")
		(net "GND")
	)
	(segment
		(start 3.937 7.366)
		(end 4.953 7.366)
		(width 0.508)
		(layer "F.Cu")
		(net "GND")
	)
	(segment
		(start 67.736999 3.542005)
		(end 68.236998 4.042004)
		(width 0.254)
		(layer "F.Cu")
		(net "GND")
	)
	(segment
		(start 48.236988 23.041991)
		(end 47.736989 23.54199)
		(width 0.254)
		(layer "F.Cu")
		(net "GND")
	)
	(segment
		(start 5.334 5.8039)
		(end 5.1181 6.096)
		(width 0.508)
		(layer "F.Cu")
		(net "GND")
	)
	(segment
		(start 45.236994 14.042009)
		(end 44.736995 13.54201)
		(width 0.254)
		(layer "F.Cu")
		(net "GND")
	)
	(segment
		(start 51.237007 34.041994)
		(end 50.737008 34.541993)
		(width 0.254)
		(layer "F.Cu")
		(net "GND")
	)
	(segment
		(start 51.237007 24.041989)
		(end 50.737008 24.541988)
		(width 0.254)
		(layer "F.Cu")
		(net "GND")
	)
	(segment
		(start 58.736992 21.541994)
		(end 58.236993 21.041995)
		(width 0.254)
		(layer "F.Cu")
		(net "GND")
	)
	(segment
		(start 46.236992 13.042011)
		(end 45.736993 12.542012)
		(width 0.254)
		(layer "F.Cu")
		(net "GND")
	)
	(segment
		(start 46.236992 5.042002)
		(end 45.736993 4.542003)
		(width 0.254)
		(layer "F.Cu")
		(net "GND")
	)
	(segment
		(start 4.953 7.366)
		(end 5.334 6.985)
		(width 0.508)
		(layer "F.Cu")
		(net "GND")
	)
	(segment
		(start 48.236988 19.041999)
		(end 47.736989 19.541998)
		(width 0.254)
		(layer "F.Cu")
		(net "GND")
	)
	(segment
		(start 65.237004 7.041998)
		(end 66.237002 7.041998)
		(width 0.254)
		(layer "F.Cu")
		(net "GND")
	)
	(segment
		(start 67.736999 6.541999)
		(end 67.237 7.041998)
		(width 0.254)
		(layer "F.Cu")
		(net "GND")
	)
	(segment
		(start 59.73699 11.541989)
		(end 59.236991 12.041988)
		(width 0.254)
		(layer "F.Cu")
		(net "GND")
	)
	(segment
		(start 58.736992 10.541991)
		(end 58.236993 11.04199)
		(width 0.254)
		(layer "F.Cu")
		(net "GND")
	)
	(segment
		(start 11.43 37.719)
		(end 10.7061 37.719)
		(width 0.508)
		(layer "F.Cu")
		(net "GND")
	)
	(segment
		(start 40.386 37.4015)
		(end 40.386 36.195)
		(width 0.508)
		(layer "F.Cu")
		(net "GND")
	)
	(segment
		(start 59.73699 30.542001)
		(end 59.236991 30.042002)
		(width 0.254)
		(layer "F.Cu")
		(net "GND")
	)
	(segment
		(start 75.5269 5.715)
		(end 74.93 5.715)
		(width 0.254)
		(layer "F.Cu")
		(net "GND")
	)
	(segment
		(start 40.237004 21.041995)
		(end 39.737005 21.541994)
		(width 0.254)
		(layer "F.Cu")
		(net "GND")
	)
	(segment
		(start 51.237007 6.042)
		(end 50.737008 5.542001)
		(width 0.254)
		(layer "F.Cu")
		(net "GND")
	)
	(segment
		(start 65.737003 16.542004)
		(end 65.237004 17.042003)
		(width 0.254)
		(layer "F.Cu")
		(net "GND")
	)
	(segment
		(start 54.237001 13.042011)
		(end 53.737002 12.542012)
		(width 0.254)
		(layer "F.Cu")
		(net "GND")
	)
	(segment
		(start 41.237002 34.041994)
		(end 40.737003 34.541993)
		(width 0.508)
		(layer "F.Cu")
		(net "GND")
	)
	(segment
		(start 43.236998 31.042)
		(end 42.736999 31.541999)
		(width 0.254)
		(layer "F.Cu")
		(net "GND")
	)
	(segment
		(start 40.237004 3.042006)
		(end 39.737005 2.542007)
		(width 0.508)
		(layer "F.Cu")
		(net "GND")
	)
	(segment
		(start 64.737005 33.541995)
		(end 64.237006 33.041996)
		(width 0.254)
		(layer "F.Cu")
		(net "GND")
	)
	(segment
		(start 52.237005 15.042007)
		(end 51.737006 14.542008)
		(width 0.254)
		(layer "F.Cu")
		(net "GND")
	)
	(segment
		(start 19.558 2.5781)
		(end 18.9611 2.5781)
		(width 0.254)
		(layer "F.Cu")
		(net "GND")
	)
	(segment
		(start 76.251003 8.941003)
		(end 76.581 9.271)
		(width 0.254)
		(layer "F.Cu")
		(net "GND")
	)
	(segment
		(start 49.237011 7.041998)
		(end 49.237011 8.041996)
		(width 0.254)
		(layer "F.Cu")
		(net "GND")
	)
	(segment
		(start 73.9521 11.938)
		(end 73.9521 12.554915)
		(width 0.254)
		(layer "F.Cu")
		(net "GND")
	)
	(segment
		(start 53.237003 10.041992)
		(end 52.737004 9.541993)
		(width 0.254)
		(layer "F.Cu")
		(net "GND")
	)
	(segment
		(start 31.888989 3.8227)
		(end 31.888989 4.964989)
		(width 0.2032)
		(layer "F.Cu")
		(net "GND")
	)
	(segment
		(start 58.736992 19.541998)
		(end 58.236993 19.041999)
		(width 0.254)
		(layer "F.Cu")
		(net "GND")
	)
	(segment
		(start 56.736996 25.542011)
		(end 56.236997 25.042012)
		(width 0.254)
		(layer "F.Cu")
		(net "GND")
	)
	(segment
		(start 63.737007 2.542007)
		(end 63.237008 3.042006)
		(width 0.254)
		(layer "F.Cu")
		(net "GND")
	)
	(segment
		(start 54.237001 29.042004)
		(end 53.737002 29.542003)
		(width 0.254)
		(layer "F.Cu")
		(net "GND")
	)
	(segment
		(start 31.888989 4.964989)
		(end 32.004 5.08)
		(width 0.2032)
		(layer "F.Cu")
		(net "GND")
	)
	(segment
		(start 80.474007 12.656007)
		(end 81.050994 12.656007)
		(width 0.254)
		(layer "F.Cu")
		(net "GND")
	)
	(segment
		(start 69.736995 21.541994)
		(end 69.236996 21.041995)
		(width 0.254)
		(layer "F.Cu")
		(net "GND")
	)
	(segment
		(start 61.737011 33.541995)
		(end 61.237012 33.041996)
		(width 0.254)
		(layer "F.Cu")
		(net "GND")
	)
	(segment
		(start 52.237005 25.042012)
		(end 51.737006 25.542011)
		(width 0.254)
		(layer "F.Cu")
		(net "GND")
	)
	(segment
		(start 42.237 5.042002)
		(end 41.737001 4.542003)
		(width 0.254)
		(layer "F.Cu")
		(net "GND")
	)
	(segment
		(start 80.5434 9.038768)
		(end 80.5434 9.0805)
		(width 0.254)
		(layer "F.Cu")
		(net "GND")
	)
	(segment
		(start 61.737011 9.541993)
		(end 61.237012 10.041992)
		(width 0.254)
		(layer "F.Cu")
		(net "GND")
	)
	(segment
		(start 56.736996 19.541998)
		(end 56.236997 19.041999)
		(width 0.254)
		(layer "F.Cu")
		(net "GND")
	)
	(segment
		(start 50.237009 7.041998)
		(end 49.237011 7.041998)
		(width 0.254)
		(layer "F.Cu")
		(net "GND")
	)
	(segment
		(start 75.7809 4.9911)
		(end 77.216 4.9911)
		(width 0.254)
		(layer "F.Cu")
		(net "GND")
	)
	(segment
		(start 59.73699 34.541993)
		(end 59.236991 34.041994)
		(width 0.254)
		(layer "F.Cu")
		(net "GND")
	)
	(segment
		(start 66.548 46.1899)
		(end 66.548 45.212)
		(width 0.2032)
		(layer "F.Cu")
		(net "GND")
	)
	(segment
		(start 48.236988 17.042003)
		(end 47.736989 16.542004)
		(width 0.254)
		(layer "F.Cu")
		(net "GND")
	)
	(segment
		(start 32.388988 3.8227)
		(end 32.388988 4.695012)
		(width 0.2032)
		(layer "F.Cu")
		(net "GND")
	)
	(segment
		(start 11.862105 35.611105)
		(end 11.43 35.179)
		(width 0.2032)
		(layer "F.Cu")
		(net "GND")
	)
	(segment
		(start 62.23701 7.041998)
		(end 63.237008 7.041998)
		(width 0.254)
		(layer "F.Cu")
		(net "GND")
	)
	(segment
		(start 57.736994 5.542001)
		(end 57.236995 6.042)
		(width 0.254)
		(layer "F.Cu")
		(net "GND")
	)
	(segment
		(start 66.737001 33.541995)
		(end 66.237002 33.041996)
		(width 0.254)
		(layer "F.Cu")
		(net "GND")
	)
	(segment
		(start 57.736994 13.54201)
		(end 57.236995 14.042009)
		(width 0.254)
		(layer "F.Cu")
		(net "GND")
	)
	(segment
		(start 62.733936 49.534064)
		(end 62.992 49.276)
		(width 0.2032)
		(layer "F.Cu")
		(net "GND")
	)
	(segment
		(start 80.601007 19.855993)
		(end 80.391 20.066)
		(width 0.254)
		(layer "F.Cu")
		(net "GND")
	)
	(segment
		(start 77.47 26.4541)
		(end 77.851 26.1239)
		(width 0.254)
		(layer "F.Cu")
		(net "GND")
	)
	(segment
		(start 57.736994 32.541997)
		(end 57.236995 32.041998)
		(width 0.254)
		(layer "F.Cu")
		(net "GND")
	)
	(segment
		(start 36.3601 4.064)
		(end 36.3601 5.207)
		(width 0.508)
		(layer "F.Cu")
		(net "GND")
	)
	(segment
		(start 73.406 42.799)
		(end 73.152 43.053)
		(width 0.254)
		(layer "F.Cu")
		(net "GND")
	)
	(segment
		(start 77.597 10.5029)
		(end 77.597 9.3091)
		(width 0.254)
		(layer "F.Cu")
		(net "GND")
	)
	(segment
		(start 61.237012 8.041996)
		(end 61.237012 7.041998)
		(width 0.254)
		(layer "F.Cu")
		(net "GND")
	)
	(segment
		(start 63.737007 21.541994)
		(end 63.237008 21.041995)
		(width 0.254)
		(layer "F.Cu")
		(net "GND")
	)
	(segment
		(start 55.736998 5.542001)
		(end 55.236999 6.042)
		(width 0.254)
		(layer "F.Cu")
		(net "GND")
	)
	(segment
		(start 1.778 31.75)
		(end 0.635 33.02)
		(width 0.2032)
		(layer "F.Cu")
		(net "GND")
	)
	(segment
		(start 40.237004 34.041994)
		(end 39.737005 34.541993)
		(width 0.508)
		(layer "F.Cu")
		(net "GND")
	)
	(segment
		(start 50.237009 31.042)
		(end 49.73701 31.541999)
		(width 0.254)
		(layer "F.Cu")
		(net "GND")
	)
	(segment
		(start 47.23699 6.042)
		(end 46.736991 5.542001)
		(width 0.254)
		(layer "F.Cu")
		(net "GND")
	)
	(segment
		(start 65.737003 25.542011)
		(end 65.237004 25.042012)
		(width 0.254)
		(layer "F.Cu")
		(net "GND")
	)
	(segment
		(start 69.736995 34.541993)
		(end 69.236996 34.041994)
		(width 0.508)
		(layer "F.Cu")
		(net "GND")
	)
	(segment
		(start 53.237003 9.041994)
		(end 52.737004 8.541995)
		(width 0.254)
		(layer "F.Cu")
		(net "GND")
	)
	(segment
		(start 26.67 43.9801)
		(end 26.67 44.7675)
		(width 0.2032)
		(layer "F.Cu")
		(net "GND")
	)
	(segment
		(start 65.737003 5.542001)
		(end 65.237004 6.042)
		(width 0.254)
		(layer "F.Cu")
		(net "GND")
	)
	(segment
		(start 44.236996 21.041995)
		(end 43.736997 21.541994)
		(width 0.254)
		(layer "F.Cu")
		(net "GND")
	)
	(segment
		(start 78.479904 25.1841)
		(end 77.851 25.1841)
		(width 0.254)
		(layer "F.Cu")
		(net "GND")
	)
	(segment
		(start 42.418 52.2351)
		(end 43.307 52.2351)
		(width 0.2032)
		(layer "F.Cu")
		(net "GND")
	)
	(segment
		(start 61.737011 34.541993)
		(end 61.237012 34.041994)
		(width 0.254)
		(layer "F.Cu")
		(net "GND")
	)
	(segment
		(start 63.737007 34.541993)
		(end 63.237008 34.041994)
		(width 0.254)
		(layer "F.Cu")
		(net "GND")
	)
	(segment
		(start 54.237001 25.042012)
		(end 53.737002 25.542011)
		(width 0.254)
		(layer "F.Cu")
		(net "GND")
	)
	(segment
		(start 49.237011 14.042009)
		(end 48.737012 13.54201)
		(width 0.254)
		(layer "F.Cu")
		(net "GND")
	)
	(segment
		(start 62.733936 50.033936)
		(end 62.992 50.292)
		(width 0.2032)
		(layer "F.Cu")
		(net "GND")
	)
	(segment
		(start 49.237011 3.042006)
		(end 48.737012 2.542007)
		(width 0.254)
		(layer "F.Cu")
		(net "GND")
	)
	(segment
		(start 60.736988 29.542003)
		(end 60.236989 29.042004)
		(width 0.254)
		(layer "F.Cu")
		(net "GND")
	)
	(segment
		(start 55.736998 32.541997)
		(end 55.236999 32.041998)
		(width 0.254)
		(layer "F.Cu")
		(net "GND")
	)
	(segment
		(start 49.237011 22.041993)
		(end 48.737012 22.541992)
		(width 0.254)
		(layer "F.Cu")
		(net "GND")
	)
	(segment
		(start 47.23699 32.041998)
		(end 46.736991 32.541997)
		(width 0.254)
		(layer "F.Cu")
		(net "GND")
	)
	(segment
		(start 67.736999 34.541993)
		(end 67.237 34.041994)
		(width 0.254)
		(layer "F.Cu")
		(net "GND")
	)
	(segment
		(start 48.236988 13.042011)
		(end 47.736989 12.542012)
		(width 0.254)
		(layer "F.Cu")
		(net "GND")
	)
	(segment
		(start 47.736989 5.542001)
		(end 48.236988 6.042)
		(width 0.254)
		(layer "F.Cu")
		(net "GND")
	)
	(segment
		(start 46.236992 11.04199)
		(end 45.736993 10.541991)
		(width 0.254)
		(layer "F.Cu")
		(net "GND")
	)
	(segment
		(start 57.736994 17.542002)
		(end 57.236995 18.042001)
		(width 0.254)
		(layer "F.Cu")
		(net "GND")
	)
	(segment
		(start 17.072178 35.124822)
		(end 17.072178 35.251822)
		(width 0.2032)
		(layer "F.Cu")
		(net "GND")
	)
	(segment
		(start 46.236992 33.041996)
		(end 45.736993 33.541995)
		(width 0.254)
		(layer "F.Cu")
		(net "GND")
	)
	(segment
		(start 48.236988 6.042)
		(end 48.236988 7.041998)
		(width 0.254)
		(layer "F.Cu")
		(net "GND")
	)
	(segment
		(start 18.9611 2.5781)
		(end 18.542 2.159)
		(width 0.254)
		(layer "F.Cu")
		(net "GND")
	)
	(segment
		(start 53.237003 20.041997)
		(end 52.737004 20.541996)
		(width 0.254)
		(layer "F.Cu")
		(net "GND")
	)
	(segment
		(start 73.4949 45.3009)
		(end 73.152 44.958)
		(width 0.508)
		(layer "F.Cu")
		(net "GND")
	)
	(segment
		(start 50.237009 6.042)
		(end 50.237009 7.041998)
		(width 0.254)
		(layer "F.Cu")
		(net "GND")
	)
	(segment
		(start 59.73699 20.541996)
		(end 59.236991 20.041997)
		(width 0.254)
		(layer "F.Cu")
		(net "GND")
	)
	(segment
		(start 84.201 37.5539)
		(end 84.201 36.703)
		(width 0.2032)
		(layer "F.Cu")
		(net "GND")
	)
	(segment
		(start 14.478 35.6235)
		(end 14.478 35.0393)
		(width 0.2032)
		(layer "F.Cu")
		(net "GND")
	)
	(segment
		(start 60.736988 31.541999)
		(end 60.236989 31.042)
		(width 0.254)
		(layer "F.Cu")
		(net "GND")
	)
	(segment
		(start 30.24599 21.971)
		(end 30.24599 22.048394)
		(width 0.127)
		(layer "F.Cu")
		(net "GND")
	)
	(segment
		(start 43.236998 7.041998)
		(end 42.237 7.041998)
		(width 0.254)
		(layer "F.Cu")
		(net "GND")
	)
	(segment
		(start 77.216 4.9911)
		(end 77.6859 4.9911)
		(width 0.254)
		(layer "F.Cu")
		(net "GND")
	)
	(segment
		(start 67.736999 4.542003)
		(end 68.236998 5.042002)
		(width 0.254)
		(layer "F.Cu")
		(net "GND")
	)
	(segment
		(start 50.237009 11.04199)
		(end 49.73701 10.541991)
		(width 0.254)
		(layer "F.Cu")
		(net "GND")
	)
	(segment
		(start 26.2128 41.3131)
		(end 26.2509 41.275)
		(width 0.2032)
		(layer "F.Cu")
		(net "GND")
	)
	(segment
		(start 67.736999 2.542007)
		(end 67.237 3.042006)
		(width 0.254)
		(layer "F.Cu")
		(net "GND")
	)
	(segment
		(start 5.1181 19.812)
		(end 5.334 19.3167)
		(width 0.508)
		(layer "F.Cu")
		(net "GND")
	)
	(segment
		(start 53.237003 14.042009)
		(end 52.737004 13.54201)
		(width 0.254)
		(layer "F.Cu")
		(net "GND")
	)
	(segment
		(start 5.1181 6.096)
		(end 3.937 6.096)
		(width 0.508)
		(layer "F.Cu")
		(net "GND")
	)
	(segment
		(start 55.736998 9.541993)
		(end 55.236999 10.041992)
		(width 0.254)
		(layer "F.Cu")
		(net "GND")
	)
	(segment
		(start 11.237443 39.181557)
		(end 11.608105 38.810895)
		(width 0.2032)
		(layer "F.Cu")
		(net "GND")
	)
	(segment
		(start 53.237003 6.042)
		(end 52.737004 5.542001)
		(width 0.254)
		(layer "F.Cu")
		(net "GND")
	)
	(segment
		(start 45.236994 22.041993)
		(end 44.736995 22.541992)
		(width 0.254)
		(layer "F.Cu")
		(net "GND")
	)
	(segment
		(start 47.879 52.2986)
		(end 46.790077 52.2986)
		(width 0.2032)
		(layer "F.Cu")
		(net "GND")
	)
	(segment
		(start 81.050994 31.412993)
		(end 81.050994 32.194094)
		(width 0.254)
		(layer "F.Cu")
		(net "GND")
	)
	(segment
		(start 50.237009 8.041996)
		(end 49.73701 7.541997)
		(width 0.254)
		(layer "F.Cu")
		(net "GND")
	)
	(segment
		(start 80.264 12.446)
		(end 80.474007 12.656007)
		(width 0.254)
		(layer "F.Cu")
		(net "GND")
	)
	(segment
		(start 17.272 38.814654)
		(end 17.351654 38.814654)
		(width 0.2032)
		(layer "F.Cu")
		(net "GND")
	)
	(segment
		(start 12.3063 37.211)
		(end 11.938 37.211)
		(width 0.2032)
		(layer "F.Cu")
		(net "GND")
	)
	(segment
		(start 59.73699 15.542006)
		(end 59.236991 16.042005)
		(width 0.254)
		(layer "F.Cu")
		(net "GND")
	)
	(segment
		(start 54.237001 11.04199)
		(end 53.737002 10.541991)
		(width 0.254)
		(layer "F.Cu")
		(net "GND")
	)
	(segment
		(start 55.736998 20.541996)
		(end 55.236999 20.041997)
		(width 0.254)
		(layer "F.Cu")
		(net "GND")
	)
	(segment
		(start 60.736988 27.542007)
		(end 60.236989 27.042008)
		(width 0.254)
		(layer "F.Cu")
		(net "GND")
	)
	(segment
		(start 70.736993 33.541995)
		(end 70.236994 33.041996)
		(width 0.508)
		(layer "F.Cu")
		(net "GND")
	)
	(segment
		(start 36.3601 5.207)
		(end 36.957 5.207)
		(width 0.508)
		(layer "F.Cu")
		(net "GND")
	)
	(segment
		(start 78.606904 7.4549)
		(end 78.650998 7.498994)
		(width 0.254)
		(layer "F.Cu")
		(net "GND")
	)
	(segment
		(start 32.889012 8.004988)
		(end 33.274 7.62)
		(width 0.2032)
		(layer "F.Cu")
		(net "GND")
	)
	(segment
		(start 19.8501 16.4719)
		(end 19.812 16.51)
		(width 0.508)
		(layer "F.Cu")
		(net "GND")
	)
	(segment
		(start 56.736996 7.541997)
		(end 56.236997 8.041996)
		(width 0.254)
		(layer "F.Cu")
		(net "GND")
	)
	(segment
		(start 59.73699 9.541993)
		(end 59.236991 10.041992)
		(width 0.254)
		(layer "F.Cu")
		(net "GND")
	)
	(segment
		(start 51.237007 14.042009)
		(end 50.737008 13.54201)
		(width 0.254)
		(layer "F.Cu")
		(net "GND")
	)
	(segment
		(start 51.237007 22.041993)
		(end 50.737008 22.541992)
		(width 0.254)
		(layer "F.Cu")
		(net "GND")
	)
	(segment
		(start 65.737003 34.541993)
		(end 65.237004 34.041994)
		(width 0.254)
		(layer "F.Cu")
		(net "GND")
	)
	(segment
		(start 61.737011 10.541991)
		(end 61.237012 11.04199)
		(width 0.254)
		(layer "F.Cu")
		(net "GND")
	)
	(segment
		(start 55.736998 26.542009)
		(end 55.236999 26.04201)
		(width 0.254)
		(layer "F.Cu")
		(net "GND")
	)
	(segment
		(start 50.237009 19.041999)
		(end 49.73701 19.541998)
		(width 0.254)
		(layer "F.Cu")
		(net "GND")
	)
	(segment
		(start 0.635 33.7439)
		(end 0.635 33.02)
		(width 0.2032)
		(layer "F.Cu")
		(net "GND")
	)
	(segment
		(start 50.237009 25.042012)
		(end 49.73701 25.542011)
		(width 0.254)
		(layer "F.Cu")
		(net "GND")
	)
	(segment
		(start 55.736998 22.541992)
		(end 55.236999 22.041993)
		(width 0.254)
		(layer "F.Cu")
		(net "GND")
	)
	(segment
		(start 83.312 37.5539)
		(end 84.201 37.5539)
		(width 0.2032)
		(layer "F.Cu")
		(net "GND")
	)
	(segment
		(start 60.736988 7.541997)
		(end 60.236989 8.041996)
		(width 0.254)
		(layer "F.Cu")
		(net "GND")
	)
	(segment
		(start 77.597 9.3091)
		(end 77.5589 9.271)
		(width 0.254)
		(layer "F.Cu")
		(net "GND")
	)
	(segment
		(start 41.237002 16.042005)
		(end 40.737003 15.542006)
		(width 0.254)
		(layer "F.Cu")
		(net "GND")
	)
	(segment
		(start 51.237007 26.04201)
		(end 50.737008 26.542009)
		(width 0.254)
		(layer "F.Cu")
		(net "GND")
	)
	(segment
		(start 39.237006 33.041996)
		(end 38.737007 33.541995)
		(width 0.508)
		(layer "F.Cu")
		(net "GND")
	)
	(segment
		(start 46.236992 23.041991)
		(end 45.736993 23.54199)
		(width 0.254)
		(layer "F.Cu")
		(net "GND")
	)
	(segment
		(start 45.236994 32.041998)
		(end 44.736995 32.541997)
		(width 0.254)
		(layer "F.Cu")
		(net "GND")
	)
	(segment
		(start 55.736998 30.542001)
		(end 55.236999 30.042002)
		(width 0.254)
		(layer "F.Cu")
		(net "GND")
	)
	(segment
		(start 47.23699 26.04201)
		(end 46.736991 26.542009)
		(width 0.254)
		(layer "F.Cu")
		(net "GND")
	)
	(segment
		(start 18.8849 1.397)
		(end 18.542 1.7399)
		(width 0.254)
		(layer "F.Cu")
		(net "GND")
	)
	(segment
		(start 19.431 47.625)
		(end 18.542 48.514)
		(width 0.2032)
		(layer "F.Cu")
		(net "GND")
	)
	(segment
		(start 46.236992 25.042012)
		(end 45.736993 25.542011)
		(width 0.254)
		(layer "F.Cu")
		(net "GND")
	)
	(segment
		(start 45.236994 3.042006)
		(end 44.736995 2.542007)
		(width 0.254)
		(layer "F.Cu")
		(net "GND")
	)
	(segment
		(start 42.237 6.042)
		(end 41.737001 5.542001)
		(width 0.254)
		(layer "F.Cu")
		(net "GND")
	)
	(segment
		(start 73.152 28.6131)
		(end 73.152 29.258743)
		(width 0.254)
		(layer "F.Cu")
		(net "GND")
	)
	(segment
		(start 51.237007 28.042006)
		(end 50.737008 28.542005)
		(width 0.254)
		(layer "F.Cu")
		(net "GND")
	)
	(segment
		(start 64.250062 50.534062)
		(end 64.008 50.292)
		(width 0.2032)
		(layer "F.Cu")
		(net "GND")
	)
	(segment
		(start 63.737007 5.542001)
		(end 63.237008 6.042)
		(width 0.254)
		(layer "F.Cu")
		(net "GND")
	)
	(segment
		(start 40.237004 20.041997)
		(end 39.737005 20.541996)
		(width 0.254)
		(layer "F.Cu")
		(net "GND")
	)
	(segment
		(start 18.8595 40.3225)
		(end 18.8595 40.894)
		(width 0.508)
		(layer "F.Cu")
		(net "GND")
	)
	(segment
		(start 51.237007 20.041997)
		(end 50.737008 20.541996)
		(width 0.254)
		(layer "F.Cu")
		(net "GND")
	)
	(segment
		(start 41.237002 4.042004)
		(end 40.737003 3.542005)
		(width 0.254)
		(layer "F.Cu")
		(net "GND")
	)
	(segment
		(start 10.5029 39.9161)
		(end 10.5029 40.894)
		(width 0.508)
		(layer "F.Cu")
		(net "GND")
	)
	(segment
		(start 58.736992 25.542011)
		(end 58.236993 25.042012)
		(width 0.254)
		(layer "F.Cu")
		(net "GND")
	)
	(segment
		(start 21.971 32.893)
		(end 21.720988 32.642988)
		(width 0.2032)
		(layer "F.Cu")
		(net "GND")
	)
	(segment
		(start 51.237007 10.041992)
		(end 50.737008 9.541993)
		(width 0.254)
		(layer "F.Cu")
		(net "GND")
	)
	(segment
		(start 70.736993 5.542001)
		(end 70.236994 6.042)
		(width 0.254)
		(layer "F.Cu")
		(net "GND")
	)
	(segment
		(start 12.0904 28.702)
		(end 13.208 28.702)
		(width 0.508)
		(layer "F.Cu")
		(net "GND")
	)
	(segment
		(start 66.737001 5.542001)
		(end 66.237002 6.042)
		(width 0.254)
		(layer "F.Cu")
		(net "GND")
	)
	(segment
		(start 69.736995 4.542003)
		(end 69.236996 5.042002)
		(width 0.254)
		(layer "F.Cu")
		(net "GND")
	)
	(segment
		(start 73.152 29.258743)
		(end 73.851008 29.957751)
		(width 0.254)
		(layer "F.Cu")
		(net "GND")
	)
	(segment
		(start 39.237006 5.042002)
		(end 38.737007 4.542003)
		(width 0.508)
		(layer "F.Cu")
		(net "GND")
	)
	(segment
		(start 46.236992 17.042003)
		(end 45.736993 16.542004)
		(width 0.254)
		(layer "F.Cu")
		(net "GND")
	)
	(segment
		(start 44.236996 8.041996)
		(end 43.736997 7.541997)
		(width 0.254)
		(layer "F.Cu")
		(net "GND")
	)
	(segment
		(start 78.650998 19.055994)
		(end 78.650998 19.608902)
		(width 0.254)
		(layer "F.Cu")
		(net "GND")
	)
	(segment
		(start 14.5796 35.8394)
		(end 14.478 35.6235)
		(width 0.2032)
		(layer "F.Cu")
		(net "GND")
	)
	(segment
		(start 46.790077 52.2986)
		(end 46.726577 52.2351)
		(width 0.2032)
		(layer "F.Cu")
		(net "GND")
	)
	(segment
		(start 53.237003 18.042001)
		(end 52.737004 17.542002)
		(width 0.254)
		(layer "F.Cu")
		(net "GND")
	)
	(segment
		(start 36.957 5.207)
		(end 37.084 5.08)
		(width 0.508)
		(layer "F.Cu")
		(net "GND")
	)
	(segment
		(start 68.736997 33.541995)
		(end 68.236998 33.041996)
		(width 0.254)
		(layer "F.Cu")
		(net "GND")
	)
	(segment
		(start 81.235601 42.094201)
		(end 81.153 42.0116)
		(width 0.2032)
		(layer "F.Cu")
		(net "GND")
	)
	(segment
		(start 45.236994 30.042002)
		(end 44.736995 30.542001)
		(width 0.254)
		(layer "F.Cu")
		(net "GND")
	)
	(segment
		(start 49.237011 30.042002)
		(end 48.737012 30.542001)
		(width 0.254)
		(layer "F.Cu")
		(net "GND")
	)
	(segment
		(start 17.072178 35.251822)
		(end 16.712895 35.611105)
		(width 0.2032)
		(layer "F.Cu")
		(net "GND")
	)
	(segment
		(start 42.237 12.041988)
		(end 41.737001 11.541989)
		(width 0.254)
		(layer "F.Cu")
		(net "GND")
	)
	(segment
		(start 24.0538 26.1239)
		(end 24.0538 26.67)
		(width 0.508)
		(layer "F.Cu")
		(net "GND")
	)
	(segment
		(start 51.237007 32.041998)
		(end 50.737008 32.541997)
		(width 0.254)
		(layer "F.Cu")
		(net "GND")
	)
	(segment
		(start 58.736992 33.541995)
		(end 58.236993 33.041996)
		(width 0.254)
		(layer "F.Cu")
		(net "GND")
	)
	(segment
		(start 68.736997 5.542001)
		(end 68.236998 6.042)
		(width 0.254)
		(layer "F.Cu")
		(net "GND")
	)
	(segment
		(start 57.736994 24.541988)
		(end 57.236995 24.041989)
		(width 0.254)
		(layer "F.Cu")
		(net "GND")
	)
	(segment
		(start 24.765 12.7)
		(end 24.384 12.319)
		(width 0.508)
		(layer "F.Cu")
		(net "GND")
	)
	(segment
		(start 53.237003 22.041993)
		(end 52.737004 22.541992)
		(width 0.254)
		(layer "F.Cu")
		(net "GND")
	)
	(segment
		(start 70.736993 3.542005)
		(end 70.236994 4.042004)
		(width 0.508)
		(layer "F.Cu")
		(net "GND")
	)
	(segment
		(start 57.736994 11.541989)
		(end 57.236995 12.041988)
		(width 0.254)
		(layer "F.Cu")
		(net "GND")
	)
	(segment
		(start 73.152 43.053)
		(end 73.152 43.688)
		(width 0.254)
		(layer "F.Cu")
		(net "GND")
	)
	(segment
		(start 58.736992 7.541997)
		(end 58.236993 8.041996)
		(width 0.254)
		(layer "F.Cu")
		(net "GND")
	)
	(segment
		(start 58.736992 14.542008)
		(end 58.236993 15.042007)
		(width 0.254)
		(layer "F.Cu")
		(net "GND")
	)
	(segment
		(start 75.4761 19.881088)
		(end 75.451005 19.855993)
		(width 0.254)
		(layer "F.Cu")
		(net "GND")
	)
	(segment
		(start 44.91736 49.99736)
		(end 45.212 50.292)
		(width 0.2032)
		(layer "F.Cu")
		(net "GND")
	)
	(segment
		(start 78.650998 25.013006)
		(end 78.479904 25.1841)
		(width 0.254)
		(layer "F.Cu")
		(net "GND")
	)
	(segment
		(start 18.542 48.514)
		(end 18.542 48.625023)
		(width 0.2032)
		(layer "F.Cu")
		(net "GND")
	)
	(segment
		(start 58.736992 12.542012)
		(end 58.236993 13.042011)
		(width 0.254)
		(layer "F.Cu")
		(net "GND")
	)
	(segment
		(start 43.236998 8.041996)
		(end 43.236998 7.041998)
		(width 0.254)
		(layer "F.Cu")
		(net "GND")
	)
	(segment
		(start 49.237011 32.041998)
		(end 48.737012 32.541997)
		(width 0.254)
		(layer "F.Cu")
		(net "GND")
	)
	(segment
		(start 61.737011 5.542001)
		(end 61.237012 6.042)
		(width 0.254)
		(layer "F.Cu")
		(net "GND")
	)
	(segment
		(start 32.388988 4.695012)
		(end 32.004 5.08)
		(width 0.2032)
		(layer "F.Cu")
		(net "GND")
	)
	(segment
		(start 62.737009 4.542003)
		(end 62.23701 5.042002)
		(width 0.254)
		(layer "F.Cu")
		(net "GND")
	)
	(segment
		(start 81.050994 8.531174)
		(end 80.5434 9.038768)
		(width 0.254)
		(layer "F.Cu")
		(net "GND")
	)
	(segment
		(start 54.237001 5.042002)
		(end 53.737002 4.542003)
		(width 0.254)
		(layer "F.Cu")
		(net "GND")
	)
	(segment
		(start 62.140084 49.534064)
		(end 62.733936 49.534064)
		(width 0.2032)
		(layer "F.Cu")
		(net "GND")
	)
	(segment
		(start 66.737001 12.542012)
		(end 66.237002 13.042011)
		(width 0.254)
		(layer "F.Cu")
		(net "GND")
	)
	(segment
		(start 11.856009 37.280799)
		(end 11.7221 37.414708)
		(width 0.2032)
		(layer "F.Cu")
		(net "GND")
	)
	(segment
		(start 47.23699 18.042001)
		(end 46.736991 17.542002)
		(width 0.254)
		(layer "F.Cu")
		(net "GND")
	)
	(segment
		(start 56.736996 27.542007)
		(end 56.236997 27.042008)
		(width 0.254)
		(layer "F.Cu")
		(net "GND")
	)
	(segment
		(start 33.2359 20.6121)
		(end 33.2359 21.281034)
		(width 0.127)
		(layer "F.Cu")
		(net "GND")
	)
	(segment
		(start 69.736995 2.542007)
		(end 69.236996 3.042006)
		(width 0.508)
		(layer "F.Cu")
		(net "GND")
	)
	(segment
		(start 52.237005 29.042004)
		(end 51.737006 29.542003)
		(width 0.254)
		(layer "F.Cu")
		(net "GND")
	)
	(segment
		(start 47.23699 28.042006)
		(end 46.736991 28.542005)
		(width 0.254)
		(layer "F.Cu")
		(net "GND")
	)
	(segment
		(start 81.050994 32.194094)
		(end 81.0387 32.258)
		(width 0.254)
		(layer "F.Cu")
		(net "GND")
	)
	(segment
		(start 51.237007 16.042005)
		(end 50.737008 15.542006)
		(width 0.254)
		(layer "F.Cu")
		(net "GND")
	)
	(segment
		(start 68.736997 16.542004)
		(end 68.236998 17.042003)
		(width 0.254)
		(layer "F.Cu")
		(net "GND")
	)
	(segment
		(start 12.3063 35.611105)
		(end 11.862105 35.611105)
		(width 0.2032)
		(layer "F.Cu")
		(net "GND")
	)
	(segment
		(start 61.737011 8.541995)
		(end 61.237012 9.041994)
		(width 0.254)
		(layer "F.Cu")
		(net "GND")
	)
	(segment
		(start 47.0789 44.674663)
		(end 47.201912 44.551651)
		(width 0.2032)
		(layer "F.Cu")
		(net "GND")
	)
	(segment
		(start 54.237001 27.042008)
		(end 53.737002 27.542007)
		(width 0.254)
		(layer "F.Cu")
		(net "GND")
	)
	(segment
		(start 60.236989 10.041992)
		(end 60.736988 9.541993)
		(width 0.254)
		(layer "F.Cu")
		(net "GND")
	)
	(segment
		(start 17.351654 38.814654)
		(end 17.653 39.116)
		(width 0.2032)
		(layer "F.Cu")
		(net "GND")
	)
	(segment
		(start 20.701 16.4338)
		(end 20.701 16.4719)
		(width 0.508)
		(layer "F.Cu")
		(net "GND")
	)
	(segment
		(start 29.8831 21.60811)
		(end 30.24599 21.971)
		(width 0.127)
		(layer "F.Cu")
		(net "GND")
	)
	(segment
		(start 57.736994 20.541996)
		(end 57.236995 20.041997)
		(width 0.254)
		(layer "F.Cu")
		(net "GND")
	)
	(segment
		(start 25.2857 41.3131)
		(end 26.2128 41.3131)
		(width 0.2032)
		(layer "F.Cu")
		(net "GND")
	)
	(segment
		(start 60.736988 25.542011)
		(end 60.236989 25.042012)
		(width 0.254)
		(layer "F.Cu")
		(net "GND")
	)
	(segment
		(start 76.581 9.271)
		(end 77.5589 9.271)
		(width 0.254)
		(layer "F.Cu")
		(net "GND")
	)
	(segment
		(start 45.236994 26.04201)
		(end 44.736995 26.542009)
		(width 0.254)
		(layer "F.Cu")
		(net "GND")
	)
	(segment
		(start 60.236989 7.041998)
		(end 61.237012 7.041998)
		(width 0.254)
		(layer "F.Cu")
		(net "GND")
	)
	(segment
		(start 67.736999 8.541995)
		(end 67.237 9.041994)
		(width 0.254)
		(layer "F.Cu")
		(net "GND")
	)
	(segment
		(start 82.435598 42.328998)
		(end 82.1182 42.0116)
		(width 0.2032)
		(layer "F.Cu")
		(net "GND")
	)
	(segment
		(start 46.236992 8.041996)
		(end 45.736993 7.541997)
		(width 0.254)
		(layer "F.Cu")
		(net "GND")
	)
	(segment
		(start 33.2359 21.281034)
		(end 32.74601 21.770924)
		(width 0.127)
		(layer "F.Cu")
		(net "GND")
	)
	(segment
		(start 23.241 28.9179)
		(end 24.384 28.9179)
		(width 0.2032)
		(layer "F.Cu")
		(net "GND")
	)
	(segment
		(start 33.5788 20.2946)
		(end 33.2359 20.6121)
		(width 0.127)
		(layer "F.Cu")
		(net "GND")
	)
	(segment
		(start 57.736994 15.542006)
		(end 57.236995 16.042005)
		(width 0.254)
		(layer "F.Cu")
		(net "GND")
	)
	(segment
		(start 20.701 16.4719)
		(end 19.8501 16.4719)
		(width 0.508)
		(layer "F.Cu")
		(net "GND")
	)
	(segment
		(start 43.236998 3.042006)
		(end 42.736999 2.542007)
		(width 0.254)
		(layer "F.Cu")
		(net "GND")
	)
	(segment
		(start 29.325011 38.850011)
		(end 29.845 39.37)
		(width 0.2032)
		(layer "F.Cu")
		(net "GND")
	)
	(segment
		(start 30.3022 20.2946)
		(end 29.8831 20.7137)
		(width 0.127)
		(layer "F.Cu")
		(net "GND")
	)
	(segment
		(start 24.765 13.843)
		(end 24.765 12.7)
		(width 0.508)
		(layer "F.Cu")
		(net "GND")
	)
	(segment
		(start 59.73699 13.54201)
		(end 59.236991 14.042009)
		(width 0.254)
		(layer "F.Cu")
		(net "GND")
	)
	(segment
		(start 64.737005 4.542003)
		(end 64.237006 5.042002)
		(width 0.254)
		(layer "F.Cu")
		(net "GND")
	)
	(segment
		(start 48.236988 31.042)
		(end 47.736989 31.541999)
		(width 0.254)
		(layer "F.Cu")
		(net "GND")
	)
	(segment
		(start 68.736997 6.541999)
		(end 68.236998 7.041998)
		(width 0.254)
		(layer "F.Cu")
		(net "GND")
	)
	(segment
		(start 55.736998 4.542003)
		(end 56.236997 5.042002)
		(width 0.254)
		(layer "F.Cu")
		(net "GND")
	)
	(segment
		(start 61.737011 32.541997)
		(end 61.237012 32.041998)
		(width 0.254)
		(layer "F.Cu")
		(net "GND")
	)
	(segment
		(start 40.237004 33.041996)
		(end 39.737005 33.541995)
		(width 0.508)
		(layer "F.Cu")
		(net "GND")
	)
	(segment
		(start 65.737003 2.542007)
		(end 65.237004 3.042006)
		(width 0.254)
		(layer "F.Cu")
		(net "GND")
	)
	(segment
		(start 68.736997 2.542007)
		(end 68.236998 3.042006)
		(width 0.508)
		(layer "F.Cu")
		(net "GND")
	)
	(segment
		(start 50.237009 33.041996)
		(end 49.73701 33.541995)
		(width 0.254)
		(layer "F.Cu")
		(net "GND")
	)
	(segment
		(start 52.237005 19.041999)
		(end 51.737006 19.541998)
		(width 0.254)
		(layer "F.Cu")
		(net "GND")
	)
	(segment
		(start 62.737009 5.542001)
		(end 62.23701 6.042)
		(width 0.254)
		(layer "F.Cu")
		(net "GND")
	)
	(segment
		(start 62.737009 34.541993)
		(end 62.23701 34.041994)
		(width 0.254)
		(layer "F.Cu")
		(net "GND")
	)
	(segment
		(start 19.431 47.498)
		(end 19.431 47.625)
		(width 0.2032)
		(layer "F.Cu")
		(net "GND")
	)
	(segment
		(start 62.737009 33.541995)
		(end 62.23701 33.041996)
		(width 0.254)
		(layer "F.Cu")
		(net "GND")
	)
	(segment
		(start 64.737005 7.541997)
		(end 64.237006 8.041996)
		(width 0.254)
		(layer "F.Cu")
		(net "GND")
	)
	(segment
		(start 59.73699 17.542002)
		(end 59.236991 18.042001)
		(width 0.254)
		(layer "F.Cu")
		(net "GND")
	)
	(segment
		(start 48.236988 21.041995)
		(end 47.736989 21.541994)
		(width 0.254)
		(layer "F.Cu")
		(net "GND")
	)
	(segment
		(start 47.23699 24.041989)
		(end 46.736991 24.541988)
		(width 0.254)
		(layer "F.Cu")
		(net "GND")
	)
	(segment
		(start 47.23699 34.041994)
		(end 46.736991 34.541993)
		(width 0.254)
		(layer "F.Cu")
		(net "GND")
	)
	(segment
		(start 39.237006 32.041998)
		(end 38.737007 32.541997)
		(width 0.508)
		(layer "F.Cu")
		(net "GND")
	)
	(segment
		(start 44.236996 29.042004)
		(end 43.736997 29.542003)
		(width 0.254)
		(layer "F.Cu")
		(net "GND")
	)
	(segment
		(start 49.237011 12.041988)
		(end 48.737012 11.541989)
		(width 0.254)
		(layer "F.Cu")
		(net "GND")
	)
	(segment
		(start 81.050994 19.855993)
		(end 80.601007 19.855993)
		(width 0.254)
		(layer "F.Cu")
		(net "GND")
	)
	(segment
		(start 45.236994 34.041994)
		(end 44.736995 34.541993)
		(width 0.254)
		(layer "F.Cu")
		(net "GND")
	)
	(segment
		(start 57.736994 22.541992)
		(end 57.236995 22.041993)
		(width 0.254)
		(layer "F.Cu")
		(net "GND")
	)
	(segment
		(start 45.236994 20.041997)
		(end 44.736995 20.541996)
		(width 0.254)
		(layer "F.Cu")
		(net "GND")
	)
	(segment
		(start 53.237003 16.042005)
		(end 52.737004 15.542006)
		(width 0.254)
		(layer "F.Cu")
		(net "GND")
	)
	(segment
		(start 80.5434 9.0805)
		(end 80.2259 9.398)
		(width 0.254)
		(layer "F.Cu")
		(net "GND")
	)
	(segment
		(start 55.736998 17.542002)
		(end 55.236999 18.042001)
		(width 0.254)
		(layer "F.Cu")
		(net "GND")
	)
	(segment
		(start 55.736998 15.542006)
		(end 55.236999 16.042005)
		(width 0.254)
		(layer "F.Cu")
		(net "GND")
	)
	(segment
		(start 42.237 8.041996)
		(end 41.737001 7.541997)
		(width 0.254)
		(layer "F.Cu")
		(net "GND")
	)
	(segment
		(start 49.237011 24.041989)
		(end 48.737012 24.541988)
		(width 0.254)
		(layer "F.Cu")
		(net "GND")
	)
	(segment
		(start 57.736994 34.541993)
		(end 57.236995 34.041994)
		(width 0.254)
		(layer "F.Cu")
		(net "GND")
	)
	(segment
		(start 46.236992 19.041999)
		(end 45.736993 19.541998)
		(width 0.254)
		(layer "F.Cu")
		(net "GND")
	)
	(segment
		(start 60.736988 23.54199)
		(end 60.236989 23.041991)
		(width 0.254)
		(layer "F.Cu")
		(net "GND")
	)
	(segment
		(start 45.236994 24.041989)
		(end 44.736995 24.541988)
		(width 0.254)
		(layer "F.Cu")
		(net "GND")
	)
	(segment
		(start 63.737007 12.542012)
		(end 63.237008 13.042011)
		(width 0.254)
		(layer "F.Cu")
		(net "GND")
	)
	(segment
		(start 40.237004 11.04199)
		(end 39.737005 10.541991)
		(width 0.254)
		(layer "F.Cu")
		(net "GND")
	)
	(segment
		(start 7.493 47.752)
		(end 10.2235 47.752)
		(width 0.508)
		(layer "F.Cu")
		(net "GND")
	)
	(segment
		(start 55.736998 11.541989)
		(end 55.236999 12.041988)
		(width 0.254)
		(layer "F.Cu")
		(net "GND")
	)
	(segment
		(start 18.542 48.625023)
		(end 17.979923 49.1871)
		(width 0.2032)
		(layer "F.Cu")
		(net "GND")
	)
	(segment
		(start 42.237 17.042003)
		(end 41.737001 16.542004)
		(width 0.254)
		(layer "F.Cu")
		(net "GND")
	)
	(segment
		(start 50.237009 17.042003)
		(end 49.73701 16.542004)
		(width 0.254)
		(layer "F.Cu")
		(net "GND")
	)
	(segment
		(start 17.979923 49.1871)
		(end 17.580077 49.1871)
		(width 0.2032)
		(layer "F.Cu")
		(net "GND")
	)
	(segment
		(start 80.391 20.4089)
		(end 80.2259 20.574)
		(width 0.254)
		(layer "F.Cu")
		(net "GND")
	)
	(segment
		(start 41.237002 6.042)
		(end 40.737003 5.542001)
		(width 0.254)
		(layer "F.Cu")
		(net "GND")
	)
	(segment
		(start 43.236998 17.042003)
		(end 42.736999 16.542004)
		(width 0.254)
		(layer "F.Cu")
		(net "GND")
	)
	(segment
		(start 70.736993 4.542003)
		(end 70.236994 5.042002)
		(width 0.508)
		(layer "F.Cu")
		(net "GND")
	)
	(segment
		(start 11.938 37.211)
		(end 11.868201 37.280799)
		(width 0.2032)
		(layer "F.Cu")
		(net "GND")
	)
	(segment
		(start 11.7221 37.414708)
		(end 11.7221 37.4269)
		(width 0.2032)
		(layer "F.Cu")
		(net "GND")
	)
	(segment
		(start 59.73699 2.542007)
		(end 59.236991 3.042006)
		(width 0.254)
		(layer "F.Cu")
		(net "GND")
	)
	(segment
		(start 68.736997 8.541995)
		(end 68.236998 9.041994)
		(width 0.254)
		(layer "F.Cu")
		(net "GND")
	)
	(segment
		(start 53.237003 34.041994)
		(end 52.737004 34.541993)
		(width 0.254)
		(layer "F.Cu")
		(net "GND")
	)
	(segment
		(start 32.74601 28.548406)
		(end 32.74601 28.87439)
		(width 0.14732)
		(layer "F.Cu")
		(net "GND")
	)
	(segment
		(start 10.7061 37.719)
		(end 10.033 38.3921)
		(width 0.508)
		(layer "F.Cu")
		(net "GND")
	)
	(segment
		(start 78.650998 19.608902)
		(end 78.4479 19.812)
		(width 0.254)
		(layer "F.Cu")
		(net "GND")
	)
	(segment
		(start 11.0109 34.7599)
		(end 11.0109 33.528)
		(width 0.508)
		(layer "F.Cu")
		(net "GND")
	)
	(segment
		(start 81.0387 32.258)
		(end 81.0387 32.8803)
		(width 0.254)
		(layer "F.Cu")
		(net "GND")
	)
	(segment
		(start 52.237005 17.042003)
		(end 51.737006 16.542004)
		(width 0.254)
		(layer "F.Cu")
		(net "GND")
	)
	(segment
		(start 68.736997 34.541993)
		(end 68.236998 34.041994)
		(width 0.508)
		(layer "F.Cu")
		(net "GND")
	)
	(segment
		(start 63.237008 7.041998)
		(end 63.237008 8.041996)
		(width 0.254)
		(layer "F.Cu")
		(net "GND")
	)
	(segment
		(start 76.251003 8.298993)
		(end 76.251003 8.941003)
		(width 0.254)
		(layer "F.Cu")
		(net "GND")
	)
	(segment
		(start 11.5824 27.2669)
		(end 11.5824 28.194)
		(width 0.508)
		(layer "F.Cu")
		(net "GND")
	)
	(segment
		(start 47.23699 14.042009)
		(end 46.736991 13.54201)
		(width 0.254)
		(layer "F.Cu")
		(net "GND")
	)
	(segment
		(start 68.736997 25.542011)
		(end 68.236998 25.042012)
		(width 0.254)
		(layer "F.Cu")
		(net "GND")
	)
	(segment
		(start 81.235601 43.0276)
		(end 81.235601 42.094201)
		(width 0.2032)
		(layer "F.Cu")
		(net "GND")
	)
	(segment
		(start 81.070399 41.928999)
		(end 80.137 41.928999)
		(width 0.2032)
		(layer "F.Cu")
		(net "GND")
	)
	(via
		(at 50.737008 34.541993)
		(size 0.4826)
		(drill 0.20574)
		(layers "F.Cu" "B.Cu")
		(net "GND")
	)
	(via
		(at 50.737008 17.542002)
		(size 0.4826)
		(drill 0.20574)
		(layers "F.Cu" "B.Cu")
		(net "GND")
	)
	(via
		(at 84.201 36.703)
		(size 0.508)
		(drill 0.2667)
		(layers "F.Cu" "B.Cu")
		(net "GND")
	)
	(via
		(at 1.905 13.716)
		(size 0.6096)
		(drill 0.25654)
		(layers "F.Cu" "B.Cu")
		(net "GND")
	)
	(via
		(at 39.737005 33.541995)
		(size 0.4826)
		(drill 0.20574)
		(layers "F.Cu" "B.Cu")
		(net "GND")
	)
	(via
		(at 70.736993 3.542005)
		(size 0.4826)
		(drill 0.20574)
		(layers "F.Cu" "B.Cu")
		(net "GND")
	)
	(via
		(at 78.650998 30.612994)
		(size 0.4572)
		(drill 0.20574)
		(layers "F.Cu" "B.Cu")
		(net "GND")
	)
	(via
		(at 20.193 40.9321)
		(size 0.508)
		(drill 0.25654)
		(layers "F.Cu" "B.Cu")
		(net "GND")
	)
	(via
		(at 56.736996 31.541999)
		(size 0.4826)
		(drill 0.20574)
		(layers "F.Cu" "B.Cu")
		(net "GND")
	)
	(via
		(at 31.115 39.37)
		(size 0.6096)
		(drill 0.25654)
		(layers "F.Cu" "B.Cu")
		(net "GND")
	)
	(via
		(at 70.612 44.958)
		(size 0.508)
		(drill 0.254)
		(layers "F.Cu" "B.Cu")
		(net "GND")
	)
	(via
		(at 44.736995 34.541993)
		(size 0.4826)
		(drill 0.20574)
		(layers "F.Cu" "B.Cu")
		(net "GND")
	)
	(via
		(at 49.73701 16.542004)
		(size 0.4826)
		(drill 0.20574)
		(layers "F.Cu" "B.Cu")
		(net "GND")
	)
	(via
		(at 46.736991 13.54201)
		(size 0.4826)
		(drill 0.20574)
		(layers "F.Cu" "B.Cu")
		(net "GND")
	)
	(via
		(at 10.5029 40.894)
		(size 0.508)
		(drill 0.25654)
		(layers "F.Cu" "B.Cu")
		(net "GND")
	)
	(via
		(at 67.736999 6.541999)
		(size 0.4826)
		(drill 0.20574)
		(layers "F.Cu" "B.Cu")
		(net "GND")
	)
	(via
		(at 53.737002 31.541999)
		(size 0.4826)
		(drill 0.20574)
		(layers "F.Cu" "B.Cu")
		(net "GND")
	)
	(via
		(at 46.736991 24.541988)
		(size 0.4826)
		(drill 0.20574)
		(layers "F.Cu" "B.Cu")
		(net "GND")
	)
	(via
		(at 45.736993 4.542003)
		(size 0.4826)
		(drill 0.20574)
		(layers "F.Cu" "B.Cu")
		(net "GND")
	)
	(via
		(at 52.737004 32.541997)
		(size 0.4826)
		(drill 0.20574)
		(layers "F.Cu" "B.Cu")
		(net "GND")
	)
	(via
		(at 7.7724 19.6469)
		(size 0.508)
		(drill 0.254)
		(layers "F.Cu" "B.Cu")
		(net "GND")
	)
	(via
		(at 14.1224 22.1869)
		(size 0.508)
		(drill 0.254)
		(layers "F.Cu" "B.Cu")
		(net "GND")
	)
	(via
		(at 80.2386 49.53)
		(size 0.508)
		(drill 0.25654)
		(layers "F.Cu" "B.Cu")
		(net "GND")
	)
	(via
		(at 52.737004 26.542009)
		(size 0.4826)
		(drill 0.20574)
		(layers "F.Cu" "B.Cu")
		(net "GND")
	)
	(via
		(at 12.8524 4.4069)
		(size 0.508)
		(drill 0.254)
		(layers "F.Cu" "B.Cu")
		(net "GND")
	)
	(via
		(at 81.050994 19.855993)
		(size 0.4572)
		(drill 0.20574)
		(layers "F.Cu" "B.Cu")
		(net "GND")
	)
	(via
		(at 35.4584 20.4724)
		(size 0.4572)
		(drill 0.20574)
		(layers "F.Cu" "B.Cu")
		(net "GND")
	)
	(via
		(at 51.737006 33.541995)
		(size 0.4826)
		(drill 0.20574)
		(layers "F.Cu" "B.Cu")
		(net "GND")
	)
	(via
		(at 56.736996 21.541994)
		(size 0.4826)
		(drill 0.20574)
		(layers "F.Cu" "B.Cu")
		(net "GND")
	)
	(via
		(at 55.736998 22.541992)
		(size 0.4826)
		(drill 0.20574)
		(layers "F.Cu" "B.Cu")
		(net "GND")
	)
	(via
		(at 29.845 36.83)
		(size 0.6096)
		(drill 0.25654)
		(layers "F.Cu" "B.Cu")
		(net "GND")
	)
	(via
		(at 69.736995 4.542003)
		(size 0.4826)
		(drill 0.20574)
		(layers "F.Cu" "B.Cu")
		(net "GND")
	)
	(via
		(at 38.737007 32.541997)
		(size 0.4826)
		(drill 0.20574)
		(layers "F.Cu" "B.Cu")
		(net "GND")
	)
	(via
		(at 37.084 5.08)
		(size 0.508)
		(drill 0.254)
		(layers "F.Cu" "B.Cu")
		(net "GND")
	)
	(via
		(at 57.736994 32.541997)
		(size 0.4826)
		(drill 0.20574)
		(layers "F.Cu" "B.Cu")
		(net "GND")
	)
	(via
		(at 16.8783 33.3375)
		(size 0.508)
		(drill 0.25654)
		(layers "F.Cu" "B.Cu")
		(net "GND")
	)
	(via
		(at 60.736988 14.542008)
		(size 0.4826)
		(drill 0.20574)
		(layers "F.Cu" "B.Cu")
		(net "GND")
	)
	(via
		(at 7.7724 5.6769)
		(size 0.508)
		(drill 0.254)
		(layers "F.Cu" "B.Cu")
		(net "GND")
	)
	(via
		(at 64.737005 34.541993)
		(size 0.4826)
		(drill 0.20574)
		(layers "F.Cu" "B.Cu")
		(net "GND")
	)
	(via
		(at 11.5824 18.3769)
		(size 0.508)
		(drill 0.254)
		(layers "F.Cu" "B.Cu")
		(net "GND")
	)
	(via
		(at 11.5824 23.4569)
		(size 0.508)
		(drill 0.254)
		(layers "F.Cu" "B.Cu")
		(net "GND")
	)
	(via
		(at 49.73701 23.54199)
		(size 0.4826)
		(drill 0.20574)
		(layers "F.Cu" "B.Cu")
		(net "GND")
	)
	(via
		(at 59.817 -0.508)
		(size 0.508)
		(drill 0.254)
		(layers "F.Cu" "B.Cu")
		(net "GND")
	)
	(via
		(at 58.736992 12.542012)
		(size 0.4826)
		(drill 0.20574)
		(layers "F.Cu" "B.Cu")
		(net "GND")
	)
	(via
		(at 58.736992 25.542011)
		(size 0.4826)
		(drill 0.20574)
		(layers "F.Cu" "B.Cu")
		(net "GND")
	)
	(via
		(at 16.6624 6.9469)
		(size 0.508)
		(drill 0.254)
		(layers "F.Cu" "B.Cu")
		(net "GND")
	)
	(via
		(at 61.737011 33.541995)
		(size 0.4826)
		(drill 0.20574)
		(layers "F.Cu" "B.Cu")
		(net "GND")
	)
	(via
		(at 55.736998 9.541993)
		(size 0.4826)
		(drill 0.20574)
		(layers "F.Cu" "B.Cu")
		(net "GND")
	)
	(via
		(at 84.201 47.117)
		(size 0.6096)
		(drill 0.25654)
		(layers "F.Cu" "B.Cu")
		(net "GND")
	)
	(via
		(at 51.737006 29.542003)
		(size 0.4826)
		(drill 0.20574)
		(layers "F.Cu" "B.Cu")
		(net "GND")
	)
	(via
		(at 48.737012 15.542006)
		(size 0.4826)
		(drill 0.20574)
		(layers "F.Cu" "B.Cu")
		(net "GND")
	)
	(via
		(at 74.651006 24.213007)
		(size 0.4572)
		(drill 0.20574)
		(layers "F.Cu" "B.Cu")
		(net "GND")
	)
	(via
		(at 48.737012 20.541996)
		(size 0.4826)
		(drill 0.20574)
		(layers "F.Cu" "B.Cu")
		(net "GND")
	)
	(via
		(at 56.736996 23.54199)
		(size 0.4826)
		(drill 0.20574)
		(layers "F.Cu" "B.Cu")
		(net "GND")
	)
	(via
		(at 40.737003 34.541993)
		(size 0.4826)
		(drill 0.20574)
		(layers "F.Cu" "B.Cu")
		(net "GND")
	)
	(via
		(at 84.250987 8.298993)
		(size 0.4572)
		(drill 0.20574)
		(layers "F.Cu" "B.Cu")
		(net "GND")
	)
	(via
		(at 14.1224 6.9469)
		(size 0.508)
		(drill 0.254)
		(layers "F.Cu" "B.Cu")
		(net "GND")
	)
	(via
		(at 51.737006 23.54199)
		(size 0.4826)
		(drill 0.20574)
		(layers "F.Cu" "B.Cu")
		(net "GND")
	)
	(via
		(at 51.737006 27.542007)
		(size 0.4826)
		(drill 0.20574)
		(layers "F.Cu" "B.Cu")
		(net "GND")
	)
	(via
		(at 57.912 -0.381)
		(size 0.508)
		(drill 0.254)
		(layers "F.Cu" "B.Cu")
		(net "GND")
	)
	(via
		(at 24.638 31.369)
		(size 0.508)
		(drill 0.254)
		(layers "F.Cu" "B.Cu")
		(net "GND")
	)
	(via
		(at 56.736996 7.541997)
		(size 0.4826)
		(drill 0.20574)
		(layers "F.Cu" "B.Cu")
		(net "GND")
	)
	(via
		(at 12.8524 14.5669)
		(size 0.508)
		(drill 0.254)
		(layers "F.Cu" "B.Cu")
		(net "GND")
	)
	(via
		(at 14.732 37.465)
		(size 0.508)
		(drill 0.25654)
		(layers "F.Cu" "B.Cu")
		(net "GND")
	)
	(via
		(at 48.737012 28.542005)
		(size 0.4826)
		(drill 0.20574)
		(layers "F.Cu" "B.Cu")
		(net "GND")
	)
	(via
		(at 48.471912 44.551651)
		(size 0.508)
		(drill 0.254)
		(layers "F.Cu" "B.Cu")
		(net "GND")
	)
	(via
		(at 52.737004 20.541996)
		(size 0.4826)
		(drill 0.20574)
		(layers "F.Cu" "B.Cu")
		(net "GND")
	)
	(via
		(at 45.736993 12.542012)
		(size 0.4826)
		(drill 0.20574)
		(layers "F.Cu" "B.Cu")
		(net "GND")
	)
	(via
		(at 52.737004 15.542006)
		(size 0.4826)
		(drill 0.20574)
		(layers "F.Cu" "B.Cu")
		(net "GND")
	)
	(via
		(at 76.251003 1.099007)
		(size 0.4572)
		(drill 0.20574)
		(layers "F.Cu" "B.Cu")
		(net "GND")
	)
	(via
		(at 60.736988 29.542003)
		(size 0.4826)
		(drill 0.20574)
		(layers "F.Cu" "B.Cu")
		(net "GND")
	)
	(via
		(at 63.737007 21.541994)
		(size 0.4826)
		(drill 0.20574)
		(layers "F.Cu" "B.Cu")
		(net "GND")
	)
	(via
		(at 39.737005 21.541994)
		(size 0.4826)
		(drill 0.20574)
		(layers "F.Cu" "B.Cu")
		(net "GND")
	)
	(via
		(at 59.73699 24.541988)
		(size 0.4826)
		(drill 0.20574)
		(layers "F.Cu" "B.Cu")
		(net "GND")
	)
	(via
		(at 55.736998 4.542003)
		(size 0.4826)
		(drill 0.20574)
		(layers "F.Cu" "B.Cu")
		(net "GND")
	)
	(via
		(at 11.43 48.9585)
		(size 0.508)
		(drill 0.25654)
		(layers "F.Cu" "B.Cu")
		(net "GND")
	)
	(via
		(at 82.1182 41.0464)
		(size 0.508)
		(drill 0.25654)
		(layers "F.Cu" "B.Cu")
		(net "GND")
	)
	(via
		(at 32.004 5.08)
		(size 0.6096)
		(drill 0.25654)
		(layers "F.Cu" "B.Cu")
		(net "GND")
	)
	(via
		(at 51.737006 14.542008)
		(size 0.4826)
		(drill 0.20574)
		(layers "F.Cu" "B.Cu")
		(net "GND")
	)
	(via
		(at 17.9324 18.3769)
		(size 0.508)
		(drill 0.254)
		(layers "F.Cu" "B.Cu")
		(net "GND")
	)
	(via
		(at 60.736988 12.542012)
		(size 0.4826)
		(drill 0.20574)
		(layers "F.Cu" "B.Cu")
		(net "GND")
	)
	(via
		(at 3.175 13.716)
		(size 0.6096)
		(drill 0.25654)
		(layers "F.Cu" "B.Cu")
		(net "GND")
	)
	(via
		(at 58.736992 21.541994)
		(size 0.4826)
		(drill 0.20574)
		(layers "F.Cu" "B.Cu")
		(net "GND")
	)
	(via
		(at 14.732 36.576)
		(size 0.508)
		(drill 0.25654)
		(layers "F.Cu" "B.Cu")
		(net "GND")
	)
	(via
		(at 52.197 44.45)
		(size 0.508)
		(drill 0.254)
		(layers "F.Cu" "B.Cu")
		(net "GND")
	)
	(via
		(at 62.992 49.276)
		(size 0.508)
		(drill 0.25654)
		(layers "F.Cu" "B.Cu")
		(net "GND")
	)
	(via
		(at 32.004 6.35)
		(size 0.6096)
		(drill 0.25654)
		(layers "F.Cu" "B.Cu")
		(net "GND")
	)
	(via
		(at 73.851008 12.656007)
		(size 0.4572)
		(drill 0.20574)
		(layers "F.Cu" "B.Cu")
		(net "GND")
	)
	(via
		(at 47.736989 12.542012)
		(size 0.4826)
		(drill 0.20574)
		(layers "F.Cu" "B.Cu")
		(net "GND")
	)
	(via
		(at 58.736992 7.541997)
		(size 0.4826)
		(drill 0.20574)
		(layers "F.Cu" "B.Cu")
		(net "GND")
	)
	(via
		(at 60.736988 21.541994)
		(size 0.4826)
		(drill 0.20574)
		(layers "F.Cu" "B.Cu")
		(net "GND")
	)
	(via
		(at 40.737003 6.541999)
		(size 0.4826)
		(drill 0.20574)
		(layers "F.Cu" "B.Cu")
		(net "GND")
	)
	(via
		(at 63.737007 12.542012)
		(size 0.4826)
		(drill 0.20574)
		(layers "F.Cu" "B.Cu")
		(net "GND")
	)
	(via
		(at 43.736997 24.541988)
		(size 0.4826)
		(drill 0.20574)
		(layers "F.Cu" "B.Cu")
		(net "GND")
	)
	(via
		(at 55.736998 5.542001)
		(size 0.4826)
		(drill 0.20574)
		(layers "F.Cu" "B.Cu")
		(net "GND")
	)
	(via
		(at 53.737002 19.541998)
		(size 0.4826)
		(drill 0.20574)
		(layers "F.Cu" "B.Cu")
		(net "GND")
	)
	(via
		(at 78.650998 7.498994)
		(size 0.4572)
		(drill 0.20574)
		(layers "F.Cu" "B.Cu")
		(net "GND")
	)
	(via
		(at 81.153 42.0116)
		(size 0.508)
		(drill 0.25654)
		(layers "F.Cu" "B.Cu")
		(net "GND")
	)
	(via
		(at 67.736999 4.542003)
		(size 0.4826)
		(drill 0.20574)
		(layers "F.Cu" "B.Cu")
		(net "GND")
	)
	(via
		(at 57.736994 5.542001)
		(size 0.4826)
		(drill 0.20574)
		(layers "F.Cu" "B.Cu")
		(net "GND")
	)
	(via
		(at 76.454 52.959)
		(size 0.508)
		(drill 0.25654)
		(layers "F.Cu" "B.Cu")
		(net "GND")
	)
	(via
		(at 21.971 32.893)
		(size 0.6096)
		(drill 0.25654)
		(layers "F.Cu" "B.Cu")
		(net "GND")
	)
	(via
		(at 50.673 53.3146)
		(size 0.508)
		(drill 0.254)
		(layers "F.Cu" "B.Cu")
		(net "GND")
	)
	(via
		(at 45.736993 25.542011)
		(size 0.4826)
		(drill 0.20574)
		(layers "F.Cu" "B.Cu")
		(net "GND")
	)
	(via
		(at 55.736998 15.542006)
		(size 0.4826)
		(drill 0.20574)
		(layers "F.Cu" "B.Cu")
		(net "GND")
	)
	(via
		(at 42.736999 16.542004)
		(size 0.4826)
		(drill 0.20574)
		(layers "F.Cu" "B.Cu")
		(net "GND")
	)
	(via
		(at 68.736997 16.542004)
		(size 0.4826)
		(drill 0.20574)
		(layers "F.Cu" "B.Cu")
		(net "GND")
	)
	(via
		(at 53.737002 21.541994)
		(size 0.4826)
		(drill 0.20574)
		(layers "F.Cu" "B.Cu")
		(net "GND")
	)
	(via
		(at 9.0424 5.6769)
		(size 0.508)
		(drill 0.254)
		(layers "F.Cu" "B.Cu")
		(net "GND")
	)
	(via
		(at 7.7724 9.4869)
		(size 0.508)
		(drill 0.254)
		(layers "F.Cu" "B.Cu")
		(net "GND")
	)
	(via
		(at 10.3124 5.6769)
		(size 0.508)
		(drill 0.254)
		(layers "F.Cu" "B.Cu")
		(net "GND")
	)
	(via
		(at 15.3924 10.7569)
		(size 0.508)
		(drill 0.254)
		(layers "F.Cu" "B.Cu")
		(net "GND")
	)
	(via
		(at 49.73701 14.542008)
		(size 0.4826)
		(drill 0.20574)
		(layers "F.Cu" "B.Cu")
		(net "GND")
	)
	(via
		(at 24.0538 26.67)
		(size 0.508)
		(drill 0.25654)
		(layers "F.Cu" "B.Cu")
		(net "GND")
	)
	(via
		(at 15.3924 24.7269)
		(size 0.508)
		(drill 0.254)
		(layers "F.Cu" "B.Cu")
		(net "GND")
	)
	(via
		(at 58.736992 33.541995)
		(size 0.4826)
		(drill 0.20574)
		(layers "F.Cu" "B.Cu")
		(net "GND")
	)
	(via
		(at 46.736991 15.542006)
		(size 0.4826)
		(drill 0.20574)
		(layers "F.Cu" "B.Cu")
		(net "GND")
	)
	(via
		(at 11.5824 13.2969)
		(size 0.508)
		(drill 0.254)
		(layers "F.Cu" "B.Cu")
		(net "GND")
	)
	(via
		(at 47.2186 51.816)
		(size 0.508)
		(drill 0.25654)
		(layers "F.Cu" "B.Cu")
		(net "GND")
	)
	(via
		(at 61.737011 9.541993)
		(size 0.4826)
		(drill 0.20574)
		(layers "F.Cu" "B.Cu")
		(net "GND")
	)
	(via
		(at 60.736988 23.54199)
		(size 0.4826)
		(drill 0.20574)
		(layers "F.Cu" "B.Cu")
		(net "GND")
	)
	(via
		(at 62.737009 4.542003)
		(size 0.4826)
		(drill 0.20574)
		(layers "F.Cu" "B.Cu")
		(net "GND")
	)
	(via
		(at 46.736991 22.541992)
		(size 0.4826)
		(drill 0.20574)
		(layers "F.Cu" "B.Cu")
		(net "GND")
	)
	(via
		(at 15.3924 15.8369)
		(size 0.508)
		(drill 0.254)
		(layers "F.Cu" "B.Cu")
		(net "GND")
	)
	(via
		(at 82.65099 31.412993)
		(size 0.4572)
		(drill 0.20574)
		(layers "F.Cu" "B.Cu")
		(net "GND")
	)
	(via
		(at 73.152 44.958)
		(size 0.508)
		(drill 0.254)
		(layers "F.Cu" "B.Cu")
		(net "GND")
	)
	(via
		(at 46.736991 32.541997)
		(size 0.4826)
		(drill 0.20574)
		(layers "F.Cu" "B.Cu")
		(net "GND")
	)
	(via
		(at 10.3124 13.2969)
		(size 0.508)
		(drill 0.254)
		(layers "F.Cu" "B.Cu")
		(net "GND")
	)
	(via
		(at 58.736992 23.54199)
		(size 0.4826)
		(drill 0.20574)
		(layers "F.Cu" "B.Cu")
		(net "GND")
	)
	(via
		(at 32.385 36.83)
		(size 0.6096)
		(drill 0.25654)
		(layers "F.Cu" "B.Cu")
		(net "GND")
	)
	(via
		(at 73.851008 19.055994)
		(size 0.4572)
		(drill 0.20574)
		(layers "F.Cu" "B.Cu")
		(net "GND")
	)
	(via
		(at 53.737002 33.541995)
		(size 0.4826)
		(drill 0.20574)
		(layers "F.Cu" "B.Cu")
		(net "GND")
	)
	(via
		(at 85.217 50.419)
		(size 0.508)
		(drill 0.254)
		(layers "F.Cu" "B.Cu")
		(net "GND")
	)
	(via
		(at 14.5796 35.8394)
		(size 0.508)
		(drill 0.254)
		(layers "F.Cu" "B.Cu")
		(net "GND")
	)
	(via
		(at 41.737001 22.541992)
		(size 0.4826)
		(drill 0.20574)
		(layers "F.Cu" "B.Cu")
		(net "GND")
	)
	(via
		(at 53.737002 12.542012)
		(size 0.4826)
		(drill 0.20574)
		(layers "F.Cu" "B.Cu")
		(net "GND")
	)
	(via
		(at 14.732 37.0205)
		(size 0.508)
		(drill 0.25654)
		(layers "F.Cu" "B.Cu")
		(net "GND")
	)
	(via
		(at 17.9324 17.1069)
		(size 0.508)
		(drill 0.254)
		(layers "F.Cu" "B.Cu")
		(net "GND")
	)
	(via
		(at 53.737002 23.54199)
		(size 0.4826)
		(drill 0.20574)
		(layers "F.Cu" "B.Cu")
		(net "GND")
	)
	(via
		(at 44.736995 26.542009)
		(size 0.4826)
		(drill 0.20574)
		(layers "F.Cu" "B.Cu")
		(net "GND")
	)
	(via
		(at 66.737001 34.541993)
		(size 0.4826)
		(drill 0.20574)
		(layers "F.Cu" "B.Cu")
		(net "GND")
	)
	(via
		(at 42.736999 2.542007)
		(size 0.4826)
		(drill 0.20574)
		(layers "F.Cu" "B.Cu")
		(net "GND")
	)
	(via
		(at 50.737008 13.54201)
		(size 0.4826)
		(drill 0.20574)
		(layers "F.Cu" "B.Cu")
		(net "GND")
	)
	(via
		(at 48.737012 32.541997)
		(size 0.4826)
		(drill 0.20574)
		(layers "F.Cu" "B.Cu")
		(net "GND")
	)
	(via
		(at 63.119 38.3159)
		(size 0.508)
		(drill 0.25654)
		(layers "F.Cu" "B.Cu")
		(net "GND")
	)
	(via
		(at 14.732 37.9095)
		(size 0.508)
		(drill 0.25654)
		(layers "F.Cu" "B.Cu")
		(net "GND")
	)
	(via
		(at 52.737004 5.542001)
		(size 0.4826)
		(drill 0.20574)
		(layers "F.Cu" "B.Cu")
		(net "GND")
	)
	(via
		(at 45.736993 19.541998)
		(size 0.4826)
		(drill 0.20574)
		(layers "F.Cu" "B.Cu")
		(net "GND")
	)
	(via
		(at 68.736997 6.541999)
		(size 0.4826)
		(drill 0.20574)
		(layers "F.Cu" "B.Cu")
		(net "GND")
	)
	(via
		(at 38.737007 3.542005)
		(size 0.4826)
		(drill 0.20574)
		(layers "F.Cu" "B.Cu")
		(net "GND")
	)
	(via
		(at 51.943 1.80086)
		(size 0.508)
		(drill 0.254)
		(layers "F.Cu" "B.Cu")
		(net "GND")
	)
	(via
		(at 60.736988 19.541998)
		(size 0.4826)
		(drill 0.20574)
		(layers "F.Cu" "B.Cu")
		(net "GND")
	)
	(via
		(at 62.737009 7.541997)
		(size 0.4826)
		(drill 0.20574)
		(layers "F.Cu" "B.Cu")
		(net "GND")
	)
	(via
		(at 78.650998 25.013006)
		(size 0.4572)
		(drill 0.20574)
		(layers "F.Cu" "B.Cu")
		(net "GND")
	)
	(via
		(at 55.736998 24.541988)
		(size 0.4826)
		(drill 0.20574)
		(layers "F.Cu" "B.Cu")
		(net "GND")
	)
	(via
		(at 7.7724 14.5669)
		(size 0.508)
		(drill 0.254)
		(layers "F.Cu" "B.Cu")
		(net "GND")
	)
	(via
		(at 58.736992 29.542003)
		(size 0.4826)
		(drill 0.20574)
		(layers "F.Cu" "B.Cu")
		(net "GND")
	)
	(via
		(at 10.3124 3.1369)
		(size 0.508)
		(drill 0.254)
		(layers "F.Cu" "B.Cu")
		(net "GND")
	)
	(via
		(at 58.736992 31.541999)
		(size 0.4826)
		(drill 0.20574)
		(layers "F.Cu" "B.Cu")
		(net "GND")
	)
	(via
		(at 53.34 43.307)
		(size 0.508)
		(drill 0.254)
		(layers "F.Cu" "B.Cu")
		(net "GND")
	)
	(via
		(at 12.8524 19.6469)
		(size 0.508)
		(drill 0.254)
		(layers "F.Cu" "B.Cu")
		(net "GND")
	)
	(via
		(at 31.115 36.83)
		(size 0.6096)
		(drill 0.25654)
		(layers "F.Cu" "B.Cu")
		(net "GND")
	)
	(via
		(at 76.073 44.4881)
		(size 0.508)
		(drill 0.25654)
		(layers "F.Cu" "B.Cu")
		(net "GND")
	)
	(via
		(at 68.736997 34.541993)
		(size 0.4826)
		(drill 0.20574)
		(layers "F.Cu" "B.Cu")
		(net "GND")
	)
	(via
		(at 53.34 44.45)
		(size 0.508)
		(drill 0.254)
		(layers "F.Cu" "B.Cu")
		(net "GND")
	)
	(via
		(at 10.3124 19.6469)
		(size 0.508)
		(drill 0.254)
		(layers "F.Cu" "B.Cu")
		(net "GND")
	)
	(via
		(at 57.736994 13.54201)
		(size 0.4826)
		(drill 0.20574)
		(layers "F.Cu" "B.Cu")
		(net "GND")
	)
	(via
		(at 76.4286 53.975)
		(size 0.508)
		(drill 0.25654)
		(layers "F.Cu" "B.Cu")
		(net "GND")
	)
	(via
		(at 40.737003 5.542001)
		(size 0.4826)
		(drill 0.20574)
		(layers "F.Cu" "B.Cu")
		(net "GND")
	)
	(via
		(at 55.736998 30.542001)
		(size 0.4826)
		(drill 0.20574)
		(layers "F.Cu" "B.Cu")
		(net "GND")
	)
	(via
		(at 46.736991 20.541996)
		(size 0.4826)
		(drill 0.20574)
		(layers "F.Cu" "B.Cu")
		(net "GND")
	)
	(via
		(at 44.736995 8.541995)
		(size 0.4826)
		(drill 0.20574)
		(layers "F.Cu" "B.Cu")
		(net "GND")
	)
	(via
		(at 41.737001 16.542004)
		(size 0.4826)
		(drill 0.20574)
		(layers "F.Cu" "B.Cu")
		(net "GND")
	)
	(via
		(at 59.73699 5.542001)
		(size 0.4826)
		(drill 0.20574)
		(layers "F.Cu" "B.Cu")
		(net "GND")
	)
	(via
		(at 16.6624 8.2169)
		(size 0.508)
		(drill 0.254)
		(layers "F.Cu" "B.Cu")
		(net "GND")
	)
	(via
		(at 48.737012 11.541989)
		(size 0.4826)
		(drill 0.20574)
		(layers "F.Cu" "B.Cu")
		(net "GND")
	)
	(via
		(at 46.736991 34.541993)
		(size 0.4826)
		(drill 0.20574)
		(layers "F.Cu" "B.Cu")
		(net "GND")
	)
	(via
		(at 51.737006 12.542012)
		(size 0.4826)
		(drill 0.20574)
		(layers "F.Cu" "B.Cu")
		(net "GND")
	)
	(via
		(at 83.185 47.117)
		(size 0.508)
		(drill 0.25654)
		(layers "F.Cu" "B.Cu")
		(net "GND")
	)
	(via
		(at 71.882 44.958)
		(size 0.508)
		(drill 0.254)
		(layers "F.Cu" "B.Cu")
		(net "GND")
	)
	(via
		(at 57.736994 34.541993)
		(size 0.4826)
		(drill 0.20574)
		(layers "F.Cu" "B.Cu")
		(net "GND")
	)
	(via
		(at 76.251003 8.298993)
		(size 0.4572)
		(drill 0.20574)
		(layers "F.Cu" "B.Cu")
		(net "GND")
	)
	(via
		(at 53.737002 29.542003)
		(size 0.4826)
		(drill 0.20574)
		(layers "F.Cu" "B.Cu")
		(net "GND")
	)
	(via
		(at 60.736988 9.541993)
		(size 0.4826)
		(drill 0.20574)
		(layers "F.Cu" "B.Cu")
		(net "GND")
	)
	(via
		(at 55.736998 11.541989)
		(size 0.4826)
		(drill 0.20574)
		(layers "F.Cu" "B.Cu")
		(net "GND")
	)
	(via
		(at 47.736989 21.541994)
		(size 0.4826)
		(drill 0.20574)
		(layers "F.Cu" "B.Cu")
		(net "GND")
	)
	(via
		(at 47.736989 25.542011)
		(size 0.4826)
		(drill 0.20574)
		(layers "F.Cu" "B.Cu")
		(net "GND")
	)
	(via
		(at 84.309509 24.154486)
		(size 0.4572)
		(drill 0.20574)
		(layers "F.Cu" "B.Cu")
		(net "GND")
	)
	(via
		(at 35.433 32.2199)
		(size 0.508)
		(drill 0.25654)
		(layers "F.Cu" "B.Cu")
		(net "GND")
	)
	(via
		(at 48.737012 22.541992)
		(size 0.4826)
		(drill 0.20574)
		(layers "F.Cu" "B.Cu")
		(net "GND")
	)
	(via
		(at 45.736993 23.54199)
		(size 0.4826)
		(drill 0.20574)
		(layers "F.Cu" "B.Cu")
		(net "GND")
	)
	(via
		(at 72.251011 1.099007)
		(size 0.4572)
		(drill 0.20574)
		(layers "F.Cu" "B.Cu")
		(net "GND")
	)
	(via
		(at 82.169 47.117)
		(size 0.6096)
		(drill 0.25654)
		(layers "F.Cu" "B.Cu")
		(net "GND")
	)
	(via
		(at 73.851008 1.099007)
		(size 0.4572)
		(drill 0.20574)
		(layers "F.Cu" "B.Cu")
		(net "GND")
	)
	(via
		(at 65.9384 38.6969)
		(size 0.6096)
		(drill 0.25654)
		(layers "F.Cu" "B.Cu")
		(net "GND")
	)
	(via
		(at 15.1765 36.576)
		(size 0.508)
		(drill 0.25654)
		(layers "F.Cu" "B.Cu")
		(net "GND")
	)
	(via
		(at 53.737002 10.541991)
		(size 0.4826)
		(drill 0.20574)
		(layers "F.Cu" "B.Cu")
		(net "GND")
	)
	(via
		(at 18.288 33.528)
		(size 0.508)
		(drill 0.25654)
		(layers "F.Cu" "B.Cu")
		(net "GND")
	)
	(via
		(at 14.1224 3.1369)
		(size 0.508)
		(drill 0.254)
		(layers "F.Cu" "B.Cu")
		(net "GND")
	)
	(via
		(at 62.737009 34.541993)
		(size 0.4826)
		(drill 0.20574)
		(layers "F.Cu" "B.Cu")
		(net "GND")
	)
	(via
		(at 78.650998 19.055994)
		(size 0.4572)
		(drill 0.20574)
		(layers "F.Cu" "B.Cu")
		(net "GND")
	)
	(via
		(at 43.736997 4.542003)
		(size 0.4826)
		(drill 0.20574)
		(layers "F.Cu" "B.Cu")
		(net "GND")
	)
	(via
		(at 50.673 48.26)
		(size 0.508)
		(drill 0.254)
		(layers "F.Cu" "B.Cu")
		(net "GND")
	)
	(via
		(at 65.737003 5.542001)
		(size 0.4826)
		(drill 0.20574)
		(layers "F.Cu" "B.Cu")
		(net "GND")
	)
	(via
		(at 0.635 33.02)
		(size 0.508)
		(drill 0.2667)
		(layers "F.Cu" "B.Cu")
		(net "GND")
	)
	(via
		(at 57.736994 22.541992)
		(size 0.4826)
		(drill 0.20574)
		(layers "F.Cu" "B.Cu")
		(net "GND")
	)
	(via
		(at 16.6624 20.9169)
		(size 0.508)
		(drill 0.254)
		(layers "F.Cu" "B.Cu")
		(net "GND")
	)
	(via
		(at 51.737006 19.541998)
		(size 0.4826)
		(drill 0.20574)
		(layers "F.Cu" "B.Cu")
		(net "GND")
	)
	(via
		(at 42.736999 5.542001)
		(size 0.4826)
		(drill 0.20574)
		(layers "F.Cu" "B.Cu")
		(net "GND")
	)
	(via
		(at 9.0424 17.1069)
		(size 0.508)
		(drill 0.254)
		(layers "F.Cu" "B.Cu")
		(net "GND")
	)
	(via
		(at 42.672 47.244)
		(size 0.508)
		(drill 0.254)
		(layers "F.Cu" "B.Cu")
		(net "GND")
	)
	(via
		(at 65.405 55.118)
		(size 0.508)
		(drill 0.25654)
		(layers "F.Cu" "B.Cu")
		(net "GND")
	)
	(via
		(at 39.737005 10.541991)
		(size 0.4826)
		(drill 0.20574)
		(layers "F.Cu" "B.Cu")
		(net "GND")
	)
	(via
		(at 76.454 55.118)
		(size 0.508)
		(drill 0.25654)
		(layers "F.Cu" "B.Cu")
		(net "GND")
	)
	(via
		(at 68.736997 5.542001)
		(size 0.4826)
		(drill 0.20574)
		(layers "F.Cu" "B.Cu")
		(net "GND")
	)
	(via
		(at 47.736989 33.541995)
		(size 0.4826)
		(drill 0.20574)
		(layers "F.Cu" "B.Cu")
		(net "GND")
	)
	(via
		(at 33.274 6.35)
		(size 0.6096)
		(drill 0.25654)
		(layers "F.Cu" "B.Cu")
		(net "GND")
	)
	(via
		(at 52.737004 22.541992)
		(size 0.4826)
		(drill 0.20574)
		(layers "F.Cu" "B.Cu")
		(net "GND")
	)
	(via
		(at 24.384 12.319)
		(size 0.508)
		(drill 0.254)
		(layers "F.Cu" "B.Cu")
		(net "GND")
	)
	(via
		(at 49.73701 21.541994)
		(size 0.4826)
		(drill 0.20574)
		(layers "F.Cu" "B.Cu")
		(net "GND")
	)
	(via
		(at 60.736988 33.541995)
		(size 0.4826)
		(drill 0.20574)
		(layers "F.Cu" "B.Cu")
		(net "GND")
	)
	(via
		(at 52.197 43.307)
		(size 0.508)
		(drill 0.254)
		(layers "F.Cu" "B.Cu")
		(net "GND")
	)
	(via
		(at 61.737011 30.542001)
		(size 0.4826)
		(drill 0.20574)
		(layers "F.Cu" "B.Cu")
		(net "GND")
	)
	(via
		(at 60.736988 7.541997)
		(size 0.4826)
		(drill 0.20574)
		(layers "F.Cu" "B.Cu")
		(net "GND")
	)
	(via
		(at 76.251003 12.656007)
		(size 0.4572)
		(drill 0.20574)
		(layers "F.Cu" "B.Cu")
		(net "GND")
	)
	(via
		(at 75.159006 22.041993)
		(size 0.4572)
		(drill 0.20574)
		(layers "F.Cu" "B.Cu")
		(net "GND")
	)
	(via
		(at 68.736997 3.542005)
		(size 0.4826)
		(drill 0.20574)
		(layers "F.Cu" "B.Cu")
		(net "GND")
	)
	(via
		(at 31.115 38.1)
		(size 0.6096)
		(drill 0.25654)
		(layers "F.Cu" "B.Cu")
		(net "GND")
	)
	(via
		(at 51.737006 21.541994)
		(size 0.4826)
		(drill 0.20574)
		(layers "F.Cu" "B.Cu")
		(net "GND")
	)
	(via
		(at 41.737001 11.541989)
		(size 0.4826)
		(drill 0.20574)
		(layers "F.Cu" "B.Cu")
		(net "GND")
	)
	(via
		(at 44.736995 5.542001)
		(size 0.4826)
		(drill 0.20574)
		(layers "F.Cu" "B.Cu")
		(net "GND")
	)
	(via
		(at 52.737004 30.542001)
		(size 0.4826)
		(drill 0.20574)
		(layers "F.Cu" "B.Cu")
		(net "GND")
	)
	(via
		(at 20.066 12.192)
		(size 0.508)
		(drill 0.254)
		(layers "F.Cu" "B.Cu")
		(net "GND")
	)
	(via
		(at 46.736991 5.542001)
		(size 0.4826)
		(drill 0.20574)
		(layers "F.Cu" "B.Cu")
		(net "GND")
	)
	(via
		(at 9.0424 6.9469)
		(size 0.508)
		(drill 0.254)
		(layers "F.Cu" "B.Cu")
		(net "GND")
	)
	(via
		(at 69.736995 5.542001)
		(size 0.4826)
		(drill 0.20574)
		(layers "F.Cu" "B.Cu")
		(net "GND")
	)
	(via
		(at 58.736992 10.541991)
		(size 0.4826)
		(drill 0.20574)
		(layers "F.Cu" "B.Cu")
		(net "GND")
	)
	(via
		(at 11.5824 27.2669)
		(size 0.508)
		(drill 0.254)
		(layers "F.Cu" "B.Cu")
		(net "GND")
	)
	(via
		(at 61.737011 31.541999)
		(size 0.4826)
		(drill 0.20574)
		(layers "F.Cu" "B.Cu")
		(net "GND")
	)
	(via
		(at 45.736993 16.542004)
		(size 0.4826)
		(drill 0.20574)
		(layers "F.Cu" "B.Cu")
		(net "GND")
	)
	(via
		(at 15.1765 37.465)
		(size 0.508)
		(drill 0.25654)
		(layers "F.Cu" "B.Cu")
		(net "GND")
	)
	(via
		(at 55.736998 28.542005)
		(size 0.4826)
		(drill 0.20574)
		(layers "F.Cu" "B.Cu")
		(net "GND")
	)
	(via
		(at 82.65099 19.855993)
		(size 0.4572)
		(drill 0.20574)
		(layers "F.Cu" "B.Cu")
		(net "GND")
	)
	(via
		(at 84.250987 12.656007)
		(size 0.4572)
		(drill 0.20574)
		(layers "F.Cu" "B.Cu")
		(net "GND")
	)
	(via
		(at 44.736995 32.541997)
		(size 0.4826)
		(drill 0.20574)
		(layers "F.Cu" "B.Cu")
		(net "GND")
	)
	(via
		(at 18.8595 40.894)
		(size 0.508)
		(drill 0.25654)
		(layers "F.Cu" "B.Cu")
		(net "GND")
	)
	(via
		(at 52.737004 2.542007)
		(size 0.4826)
		(drill 0.20574)
		(layers "F.Cu" "B.Cu")
		(net "GND")
	)
	(via
		(at 23.241 32.893)
		(size 0.6096)
		(drill 0.25654)
		(layers "F.Cu" "B.Cu")
		(net "GND")
	)
	(via
		(at 48.736987 7.541997)
		(size 0.4826)
		(drill 0.20574)
		(layers "F.Cu" "B.Cu")
		(net "GND")
	)
	(via
		(at 64.008 50.292)
		(size 0.508)
		(drill 0.25654)
		(layers "F.Cu" "B.Cu")
		(net "GND")
	)
	(via
		(at 60.736988 16.542004)
		(size 0.4826)
		(drill 0.20574)
		(layers "F.Cu" "B.Cu")
		(net "GND")
	)
	(via
		(at 47.736989 31.541999)
		(size 0.4826)
		(drill 0.20574)
		(layers "F.Cu" "B.Cu")
		(net "GND")
	)
	(via
		(at 72.251011 19.855993)
		(size 0.4572)
		(drill 0.20574)
		(layers "F.Cu" "B.Cu")
		(net "GND")
	)
	(via
		(at 52.737004 13.54201)
		(size 0.4826)
		(drill 0.20574)
		(layers "F.Cu" "B.Cu")
		(net "GND")
	)
	(via
		(at 13.843 37.465)
		(size 0.508)
		(drill 0.25654)
		(layers "F.Cu" "B.Cu")
		(net "GND")
	)
	(via
		(at 75.451005 8.298993)
		(size 0.4572)
		(drill 0.20574)
		(layers "F.Cu" "B.Cu")
		(net "GND")
	)
	(via
		(at 74.651006 25.013006)
		(size 0.4572)
		(drill 0.20574)
		(layers "F.Cu" "B.Cu")
		(net "GND")
	)
	(via
		(at 61.722 -0.381)
		(size 0.508)
		(drill 0.254)
		(layers "F.Cu" "B.Cu")
		(net "GND")
	)
	(via
		(at 45.736993 14.542008)
		(size 0.4826)
		(drill 0.20574)
		(layers "F.Cu" "B.Cu")
		(net "GND")
	)
	(via
		(at 76.251003 19.055994)
		(size 0.4572)
		(drill 0.20574)
		(layers "F.Cu" "B.Cu")
		(net "GND")
	)
	(via
		(at 58.736992 19.541998)
		(size 0.4826)
		(drill 0.20574)
		(layers "F.Cu" "B.Cu")
		(net "GND")
	)
	(via
		(at 68.072 44.958)
		(size 0.508)
		(drill 0.254)
		(layers "F.Cu" "B.Cu")
		(net "GND")
	)
	(via
		(at 68.736997 8.541995)
		(size 0.4826)
		(drill 0.20574)
		(layers "F.Cu" "B.Cu")
		(net "GND")
	)
	(via
		(at 10.3124 25.9969)
		(size 0.508)
		(drill 0.254)
		(layers "F.Cu" "B.Cu")
		(net "GND")
	)
	(via
		(at 39.737005 29.542003)
		(size 0.4826)
		(drill 0.20574)
		(layers "F.Cu" "B.Cu")
		(net "GND")
	)
	(via
		(at 47.201912 44.551651)
		(size 0.508)
		(drill 0.254)
		(layers "F.Cu" "B.Cu")
		(net "GND")
	)
	(via
		(at 78.4479 28.321)
		(size 0.4572)
		(drill 0.20574)
		(layers "F.Cu" "B.Cu")
		(net "GND")
	)
	(via
		(at 26.67 44.7675)
		(size 0.508)
		(drill 0.25654)
		(layers "F.Cu" "B.Cu")
		(net "GND")
	)
	(via
		(at 62.737009 33.541995)
		(size 0.4826)
		(drill 0.20574)
		(layers "F.Cu" "B.Cu")
		(net "GND")
	)
	(via
		(at 58.736992 16.542004)
		(size 0.4826)
		(drill 0.20574)
		(layers "F.Cu" "B.Cu")
		(net "GND")
	)
	(via
		(at 51.737006 25.542011)
		(size 0.4826)
		(drill 0.20574)
		(layers "F.Cu" "B.Cu")
		(net "GND")
	)
	(via
		(at 82.65099 8.298993)
		(size 0.4572)
		(drill 0.20574)
		(layers "F.Cu" "B.Cu")
		(net "GND")
	)
	(via
		(at 11.0109 33.528)
		(size 0.508)
		(drill 0.25654)
		(layers "F.Cu" "B.Cu")
		(net "GND")
	)
	(via
		(at 61.737011 5.542001)
		(size 0.4826)
		(drill 0.20574)
		(layers "F.Cu" "B.Cu")
		(net "GND")
	)
	(via
		(at 50.737008 2.542007)
		(size 0.4826)
		(drill 0.20574)
		(layers "F.Cu" "B.Cu")
		(net "GND")
	)
	(via
		(at 18.8849 5.207)
		(size 0.508)
		(drill 0.25654)
		(layers "F.Cu" "B.Cu")
		(net "GND")
	)
	(via
		(at 60.736988 27.542007)
		(size 0.4826)
		(drill 0.20574)
		(layers "F.Cu" "B.Cu")
		(net "GND")
	)
	(via
		(at 29.845 38.1)
		(size 0.6096)
		(drill 0.25654)
		(layers "F.Cu" "B.Cu")
		(net "GND")
	)
	(via
		(at 10.3124 9.4869)
		(size 0.508)
		(drill 0.254)
		(layers "F.Cu" "B.Cu")
		(net "GND")
	)
	(via
		(at 47.736989 4.542003)
		(size 0.4826)
		(drill 0.20574)
		(layers "F.Cu" "B.Cu")
		(net "GND")
	)
	(via
		(at 43.736997 7.541997)
		(size 0.4826)
		(drill 0.20574)
		(layers "F.Cu" "B.Cu")
		(net "GND")
	)
	(via
		(at 18.542 2.159)
		(size 0.508)
		(drill 0.254)
		(layers "F.Cu" "B.Cu")
		(net "GND")
	)
	(via
		(at 70.736993 4.542003)
		(size 0.4826)
		(drill 0.20574)
		(layers "F.Cu" "B.Cu")
		(net "GND")
	)
	(via
		(at 7.7724 20.9169)
		(size 0.508)
		(drill 0.254)
		(layers "F.Cu" "B.Cu")
		(net "GND")
	)
	(via
		(at 60.736988 25.542011)
		(size 0.4826)
		(drill 0.20574)
		(layers "F.Cu" "B.Cu")
		(net "GND")
	)
	(via
		(at 49.780774 1.870558)
		(size 0.508)
		(drill 0.254)
		(layers "F.Cu" "B.Cu")
		(net "GND")
	)
	(via
		(at 78.650998 13.456006)
		(size 0.4572)
		(drill 0.20574)
		(layers "F.Cu" "B.Cu")
		(net "GND")
	)
	(via
		(at 45.736993 27.542007)
		(size 0.4826)
		(drill 0.20574)
		(layers "F.Cu" "B.Cu")
		(net "GND")
	)
	(via
		(at 57.736994 30.542001)
		(size 0.4826)
		(drill 0.20574)
		(layers "F.Cu" "B.Cu")
		(net "GND")
	)
	(via
		(at 25.4381 37.719)
		(size 0.508)
		(drill 0.25654)
		(layers "F.Cu" "B.Cu")
		(net "GND")
	)
	(via
		(at 83.185 48.133)
		(size 0.6096)
		(drill 0.25654)
		(layers "F.Cu" "B.Cu")
		(net "GND")
	)
	(via
		(at 15.1765 37.9095)
		(size 0.508)
		(drill 0.25654)
		(layers "F.Cu" "B.Cu")
		(net "GND")
	)
	(via
		(at 14.1224 8.2169)
		(size 0.508)
		(drill 0.254)
		(layers "F.Cu" "B.Cu")
		(net "GND")
	)
	(via
		(at 84.36803 31.471514)
		(size 0.4572)
		(drill 0.20574)
		(layers "F.Cu" "B.Cu")
		(net "GND")
	)
	(via
		(at 39.737005 3.542005)
		(size 0.4826)
		(drill 0.20574)
		(layers "F.Cu" "B.Cu")
		(net "GND")
	)
	(via
		(at 59.73699 13.54201)
		(size 0.4826)
		(drill 0.20574)
		(layers "F.Cu" "B.Cu")
		(net "GND")
	)
	(via
		(at 60.736988 8.541995)
		(size 0.4826)
		(drill 0.20574)
		(layers "F.Cu" "B.Cu")
		(net "GND")
	)
	(via
		(at 16.6624 12.0269)
		(size 0.508)
		(drill 0.254)
		(layers "F.Cu" "B.Cu")
		(net "GND")
	)
	(via
		(at 61.737011 8.541995)
		(size 0.4826)
		(drill 0.20574)
		(layers "F.Cu" "B.Cu")
		(net "GND")
	)
	(via
		(at 57.736994 28.542005)
		(size 0.4826)
		(drill 0.20574)
		(layers "F.Cu" "B.Cu")
		(net "GND")
	)
	(via
		(at 50.737008 26.542009)
		(size 0.4826)
		(drill 0.20574)
		(layers "F.Cu" "B.Cu")
		(net "GND")
	)
	(via
		(at 41.737001 5.542001)
		(size 0.4826)
		(drill 0.20574)
		(layers "F.Cu" "B.Cu")
		(net "GND")
	)
	(via
		(at 15.3924 19.6469)
		(size 0.508)
		(drill 0.254)
		(layers "F.Cu" "B.Cu")
		(net "GND")
	)
	(via
		(at 37.465 31.75)
		(size 0.508)
		(drill 0.25654)
		(layers "F.Cu" "B.Cu")
		(net "GND")
	)
	(via
		(at 14.2875 36.576)
		(size 0.508)
		(drill 0.25654)
		(layers "F.Cu" "B.Cu")
		(net "GND")
	)
	(via
		(at 76.251003 7.498994)
		(size 0.4572)
		(drill 0.20574)
		(layers "F.Cu" "B.Cu")
		(net "GND")
	)
	(via
		(at 81.050994 23.368)
		(size 0.4572)
		(drill 0.20574)
		(layers "F.Cu" "B.Cu")
		(net "GND")
	)
	(via
		(at 60.8076 52.705)
		(size 0.508)
		(drill 0.25654)
		(layers "F.Cu" "B.Cu")
		(net "GND")
	)
	(via
		(at 47.736989 16.542004)
		(size 0.4826)
		(drill 0.20574)
		(layers "F.Cu" "B.Cu")
		(net "GND")
	)
	(via
		(at 73.851008 7.498994)
		(size 0.4572)
		(drill 0.20574)
		(layers "F.Cu" "B.Cu")
		(net "GND")
	)
	(via
		(at 43.307 52.2351)
		(size 0.508)
		(drill 0.25654)
		(layers "F.Cu" "B.Cu")
		(net "GND")
	)
	(via
		(at 81.153 41.0464)
		(size 0.508)
		(drill 0.25654)
		(layers "F.Cu" "B.Cu")
		(net "GND")
	)
	(via
		(at 52.737004 28.542005)
		(size 0.4826)
		(drill 0.20574)
		(layers "F.Cu" "B.Cu")
		(net "GND")
	)
	(via
		(at 74.803 5.588)
		(size 0.508)
		(drill 0.254)
		(layers "F.Cu" "B.Cu")
		(net "GND")
	)
	(via
		(at 38.737007 4.542003)
		(size 0.4826)
		(drill 0.20574)
		(layers "F.Cu" "B.Cu")
		(net "GND")
	)
	(via
		(at 82.169 48.133)
		(size 0.508)
		(drill 0.25654)
		(layers "F.Cu" "B.Cu")
		(net "GND")
	)
	(via
		(at 59.73699 22.541992)
		(size 0.4826)
		(drill 0.20574)
		(layers "F.Cu" "B.Cu")
		(net "GND")
	)
	(via
		(at 68.736997 25.542011)
		(size 0.4826)
		(drill 0.20574)
		(layers "F.Cu" "B.Cu")
		(net "GND")
	)
	(via
		(at 61.737011 10.541991)
		(size 0.4826)
		(drill 0.20574)
		(layers "F.Cu" "B.Cu")
		(net "GND")
	)
	(via
		(at 68.736997 2.542007)
		(size 0.4826)
		(drill 0.20574)
		(layers "F.Cu" "B.Cu")
		(net "GND")
	)
	(via
		(at 53.975 1.7907)
		(size 0.508)
		(drill 0.254)
		(layers "F.Cu" "B.Cu")
		(net "GND")
	)
	(via
		(at 52.737004 17.542002)
		(size 0.4826)
		(drill 0.20574)
		(layers "F.Cu" "B.Cu")
		(net "GND")
	)
	(via
		(at 19.812 16.51)
		(size 0.508)
		(drill 0.254)
		(layers "F.Cu" "B.Cu")
		(net "GND")
	)
	(via
		(at 59.3725 46.1899)
		(size 0.508)
		(drill 0.25654)
		(layers "F.Cu" "B.Cu")
		(net "GND")
	)
	(via
		(at 46.736991 2.542007)
		(size 0.4826)
		(drill 0.20574)
		(layers "F.Cu" "B.Cu")
		(net "GND")
	)
	(via
		(at 82.65099 1.099007)
		(size 0.4572)
		(drill 0.20574)
		(layers "F.Cu" "B.Cu")
		(net "GND")
	)
	(via
		(at 57.736994 11.541989)
		(size 0.4826)
		(drill 0.20574)
		(layers "F.Cu" "B.Cu")
		(net "GND")
	)
	(via
		(at 12.8524 20.9169)
		(size 0.508)
		(drill 0.254)
		(layers "F.Cu" "B.Cu")
		(net "GND")
	)
	(via
		(at 14.2875 37.0205)
		(size 0.508)
		(drill 0.25654)
		(layers "F.Cu" "B.Cu")
		(net "GND")
	)
	(via
		(at 53.737002 7.541997)
		(size 0.4826)
		(drill 0.20574)
		(layers "F.Cu" "B.Cu")
		(net "GND")
	)
	(via
		(at 27.432 32.2199)
		(size 0.508)
		(drill 0.25654)
		(layers "F.Cu" "B.Cu")
		(net "GND")
	)
	(via
		(at 54.483 43.307)
		(size 0.508)
		(drill 0.254)
		(layers "F.Cu" "B.Cu")
		(net "GND")
	)
	(via
		(at 72.251011 12.656007)
		(size 0.4572)
		(drill 0.20574)
		(layers "F.Cu" "B.Cu")
		(net "GND")
	)
	(via
		(at 24.511 21.336)
		(size 0.508)
		(drill 0.254)
		(layers "F.Cu" "B.Cu")
		(net "GND")
	)
	(via
		(at 69.736995 12.542012)
		(size 0.4826)
		(drill 0.20574)
		(layers "F.Cu" "B.Cu")
		(net "GND")
	)
	(via
		(at 15.3924 9.4869)
		(size 0.508)
		(drill 0.254)
		(layers "F.Cu" "B.Cu")
		(net "GND")
	)
	(via
		(at 65.737003 8.541995)
		(size 0.4826)
		(drill 0.20574)
		(layers "F.Cu" "B.Cu")
		(net "GND")
	)
	(via
		(at 59.73699 9.541993)
		(size 0.4826)
		(drill 0.20574)
		(layers "F.Cu" "B.Cu")
		(net "GND")
	)
	(via
		(at 30.099 32.2199)
		(size 0.508)
		(drill 0.25654)
		(layers "F.Cu" "B.Cu")
		(net "GND")
	)
	(via
		(at 69.736995 34.541993)
		(size 0.4826)
		(drill 0.20574)
		(layers "F.Cu" "B.Cu")
		(net "GND")
	)
	(via
		(at 12.8524 24.7269)
		(size 0.508)
		(drill 0.254)
		(layers "F.Cu" "B.Cu")
		(net "GND")
	)
	(via
		(at 44.736995 20.541996)
		(size 0.4826)
		(drill 0.20574)
		(layers "F.Cu" "B.Cu")
		(net "GND")
	)
	(via
		(at 9.0424 8.2169)
		(size 0.508)
		(drill 0.254)
		(layers "F.Cu" "B.Cu")
		(net "GND")
	)
	(via
		(at 9.0424 22.1869)
		(size 0.508)
		(drill 0.254)
		(layers "F.Cu" "B.Cu")
		(net "GND")
	)
	(via
		(at 75.451005 31.412993)
		(size 0.4572)
		(drill 0.20574)
		(layers "F.Cu" "B.Cu")
		(net "GND")
	)
	(via
		(at 65.737003 16.542004)
		(size 0.4826)
		(drill 0.20574)
		(layers "F.Cu" "B.Cu")
		(net "GND")
	)
	(via
		(at 82.1182 42.0116)
		(size 0.508)
		(drill 0.25654)
		(layers "F.Cu" "B.Cu")
		(net "GND")
	)
	(via
		(at 63.737007 34.541993)
		(size 0.4826)
		(drill 0.20574)
		(layers "F.Cu" "B.Cu")
		(net "GND")
	)
	(via
		(at 43.5229 38.3159)
		(size 0.508)
		(drill 0.25654)
		(layers "F.Cu" "B.Cu")
		(net "GND")
	)
	(via
		(at 57.736994 17.542002)
		(size 0.4826)
		(drill 0.20574)
		(layers "F.Cu" "B.Cu")
		(net "GND")
	)
	(via
		(at 60.736988 10.541991)
		(size 0.4826)
		(drill 0.20574)
		(layers "F.Cu" "B.Cu")
		(net "GND")
	)
	(via
		(at 47.736989 27.542007)
		(size 0.4826)
		(drill 0.20574)
		(layers "F.Cu" "B.Cu")
		(net "GND")
	)
	(via
		(at 71.882 43.688)
		(size 0.508)
		(drill 0.254)
		(layers "F.Cu" "B.Cu")
		(net "GND")
	)
	(via
		(at 55.736998 17.542002)
		(size 0.4826)
		(drill 0.20574)
		(layers "F.Cu" "B.Cu")
		(net "GND")
	)
	(via
		(at 50.737008 15.542006)
		(size 0.4826)
		(drill 0.20574)
		(layers "F.Cu" "B.Cu")
		(net "GND")
	)
	(via
		(at 15.3924 14.5669)
		(size 0.508)
		(drill 0.254)
		(layers "F.Cu" "B.Cu")
		(net "GND")
	)
	(via
		(at 12.8524 9.4869)
		(size 0.508)
		(drill 0.254)
		(layers "F.Cu" "B.Cu")
		(net "GND")
	)
	(via
		(at 45.736993 21.541994)
		(size 0.4826)
		(drill 0.20574)
		(layers "F.Cu" "B.Cu")
		(net "GND")
	)
	(via
		(at 52.737004 8.541995)
		(size 0.4826)
		(drill 0.20574)
		(layers "F.Cu" "B.Cu")
		(net "GND")
	)
	(via
		(at 62.992 50.292)
		(size 0.508)
		(drill 0.25654)
		(layers "F.Cu" "B.Cu")
		(net "GND")
	)
	(via
		(at 53.737002 25.542011)
		(size 0.4826)
		(drill 0.20574)
		(layers "F.Cu" "B.Cu")
		(net "GND")
	)
	(via
		(at 14.97965 34.2392)
		(size 0.508)
		(drill 0.254)
		(layers "F.Cu" "B.Cu")
		(net "GND")
	)
	(via
		(at 10.3124 15.8369)
		(size 0.508)
		(drill 0.254)
		(layers "F.Cu" "B.Cu")
		(net "GND")
	)
	(via
		(at 44.736995 24.541988)
		(size 0.4826)
		(drill 0.20574)
		(layers "F.Cu" "B.Cu")
		(net "GND")
	)
	(via
		(at 11.5824 8.2169)
		(size 0.508)
		(drill 0.254)
		(layers "F.Cu" "B.Cu")
		(net "GND")
	)
	(via
		(at 82.65099 12.656007)
		(size 0.4572)
		(drill 0.20574)
		(layers "F.Cu" "B.Cu")
		(net "GND")
	)
	(via
		(at 55.736998 34.541993)
		(size 0.4826)
		(drill 0.20574)
		(layers "F.Cu" "B.Cu")
		(net "GND")
	)
	(via
		(at 11.5824 22.1869)
		(size 0.508)
		(drill 0.254)
		(layers "F.Cu" "B.Cu")
		(net "GND")
	)
	(via
		(at 48.737012 24.541988)
		(size 0.4826)
		(drill 0.20574)
		(layers "F.Cu" "B.Cu")
		(net "GND")
	)
	(via
		(at 41.737001 2.542007)
		(size 0.4826)
		(drill 0.20574)
		(layers "F.Cu" "B.Cu")
		(net "GND")
	)
	(via
		(at 51.054 44.45)
		(size 0.508)
		(drill 0.254)
		(layers "F.Cu" "B.Cu")
		(net "GND")
	)
	(via
		(at 59.73699 11.541989)
		(size 0.4826)
		(drill 0.20574)
		(layers "F.Cu" "B.Cu")
		(net "GND")
	)
	(via
		(at 15.621 41.91)
		(size 0.508)
		(drill 0.25654)
		(layers "F.Cu" "B.Cu")
		(net "GND")
	)
	(via
		(at 46.736991 17.542002)
		(size 0.4826)
		(drill 0.20574)
		(layers "F.Cu" "B.Cu")
		(net "GND")
	)
	(via
		(at 53.737002 16.542004)
		(size 0.4826)
		(drill 0.20574)
		(layers "F.Cu" "B.Cu")
		(net "GND")
	)
	(via
		(at 42.736999 19.541998)
		(size 0.4826)
		(drill 0.20574)
		(layers "F.Cu" "B.Cu")
		(net "GND")
	)
	(via
		(at 73.851008 24.213007)
		(size 0.4572)
		(drill 0.20574)
		(layers "F.Cu" "B.Cu")
		(net "GND")
	)
	(via
		(at 9.0424 23.4569)
		(size 0.508)
		(drill 0.254)
		(layers "F.Cu" "B.Cu")
		(net "GND")
	)
	(via
		(at 43.736997 21.541994)
		(size 0.4826)
		(drill 0.20574)
		(layers "F.Cu" "B.Cu")
		(net "GND")
	)
	(via
		(at 30.3022 20.2946)
		(size 0.4572)
		(drill 0.20574)
		(layers "F.Cu" "B.Cu")
		(net "GND")
	)
	(via
		(at 14.1224 12.0269)
		(size 0.508)
		(drill 0.254)
		(layers "F.Cu" "B.Cu")
		(net "GND")
	)
	(via
		(at 14.1224 17.1069)
		(size 0.508)
		(drill 0.254)
		(layers "F.Cu" "B.Cu")
		(net "GND")
	)
	(via
		(at 10.3124 12.0269)
		(size 0.508)
		(drill 0.254)
		(layers "F.Cu" "B.Cu")
		(net "GND")
	)
	(via
		(at 9.0551 40.7162)
		(size 0.508)
		(drill 0.25654)
		(layers "F.Cu" "B.Cu")
		(net "GND")
	)
	(via
		(at 74.651006 7.498994)
		(size 0.4572)
		(drill 0.20574)
		(layers "F.Cu" "B.Cu")
		(net "GND")
	)
	(via
		(at 49.73701 19.541998)
		(size 0.4826)
		(drill 0.20574)
		(layers "F.Cu" "B.Cu")
		(net "GND")
	)
	(via
		(at 12.8524 15.8369)
		(size 0.508)
		(drill 0.254)
		(layers "F.Cu" "B.Cu")
		(net "GND")
	)
	(via
		(at 49.73701 27.542007)
		(size 0.4826)
		(drill 0.20574)
		(layers "F.Cu" "B.Cu")
		(net "GND")
	)
	(via
		(at 61.737011 34.541993)
		(size 0.4826)
		(drill 0.20574)
		(layers "F.Cu" "B.Cu")
		(net "GND")
	)
	(via
		(at 47.736989 10.541991)
		(size 0.4826)
		(drill 0.20574)
		(layers "F.Cu" "B.Cu")
		(net "GND")
	)
	(via
		(at 33.274 5.08)
		(size 0.6096)
		(drill 0.25654)
		(layers "F.Cu" "B.Cu")
		(net "GND")
	)
	(via
		(at 40.737003 4.542003)
		(size 0.4826)
		(drill 0.20574)
		(layers "F.Cu" "B.Cu")
		(net "GND")
	)
	(via
		(at 66.737001 33.541995)
		(size 0.4826)
		(drill 0.20574)
		(layers "F.Cu" "B.Cu")
		(net "GND")
	)
	(via
		(at 21.59 37.592)
		(size 0.508)
		(drill 0.25654)
		(layers "F.Cu" "B.Cu")
		(net "GND")
	)
	(via
		(at 32.385 38.1)
		(size 0.6096)
		(drill 0.25654)
		(layers "F.Cu" "B.Cu")
		(net "GND")
	)
	(via
		(at 76.251003 30.612994)
		(size 0.4572)
		(drill 0.20574)
		(layers "F.Cu" "B.Cu")
		(net "GND")
	)
	(via
		(at 56.736996 12.542012)
		(size 0.4826)
		(drill 0.20574)
		(layers "F.Cu" "B.Cu")
		(net "GND")
	)
	(via
		(at 13.843 37.9095)
		(size 0.508)
		(drill 0.25654)
		(layers "F.Cu" "B.Cu")
		(net "GND")
	)
	(via
		(at 51.737006 4.542003)
		(size 0.4826)
		(drill 0.20574)
		(layers "F.Cu" "B.Cu")
		(net "GND")
	)
	(via
		(at 81.050994 1.099007)
		(size 0.4572)
		(drill 0.20574)
		(layers "F.Cu" "B.Cu")
		(net "GND")
	)
	(via
		(at 51.737006 31.541999)
		(size 0.4826)
		(drill 0.20574)
		(layers "F.Cu" "B.Cu")
		(net "GND")
	)
	(via
		(at 11.5824 6.9469)
		(size 0.508)
		(drill 0.254)
		(layers "F.Cu" "B.Cu")
		(net "GND")
	)
	(via
		(at 50.737008 24.541988)
		(size 0.4826)
		(drill 0.20574)
		(layers "F.Cu" "B.Cu")
		(net "GND")
	)
	(via
		(at 50.737008 5.542001)
		(size 0.4826)
		(drill 0.20574)
		(layers "F.Cu" "B.Cu")
		(net "GND")
	)
	(via
		(at 43.736997 9.541993)
		(size 0.4826)
		(drill 0.20574)
		(layers "F.Cu" "B.Cu")
		(net "GND")
	)
	(via
		(at 69.736995 2.542007)
		(size 0.4826)
		(drill 0.25654)
		(layers "F.Cu" "B.Cu")
		(net "GND")
	)
	(via
		(at 49.73701 31.541999)
		(size 0.4826)
		(drill 0.20574)
		(layers "F.Cu" "B.Cu")
		(net "GND")
	)
	(via
		(at 49.73701 10.541991)
		(size 0.4826)
		(drill 0.20574)
		(layers "F.Cu" "B.Cu")
		(net "GND")
	)
	(via
		(at 39.737005 2.542007)
		(size 0.4826)
		(drill 0.20574)
		(layers "F.Cu" "B.Cu")
		(net "GND")
	)
	(via
		(at 76.251003 21.787993)
		(size 0.4572)
		(drill 0.20574)
		(layers "F.Cu" "B.Cu")
		(net "GND")
	)
	(via
		(at 70.736993 5.542001)
		(size 0.4826)
		(drill 0.20574)
		(layers "F.Cu" "B.Cu")
		(net "GND")
	)
	(via
		(at 46.3423 39.6875)
		(size 0.6096)
		(drill 0.25654)
		(layers "F.Cu" "B.Cu")
		(net "GND")
	)
	(via
		(at 46.736991 30.542001)
		(size 0.4826)
		(drill 0.20574)
		(layers "F.Cu" "B.Cu")
		(net "GND")
	)
	(via
		(at 70.736993 32.541997)
		(size 0.4826)
		(drill 0.20574)
		(layers "F.Cu" "B.Cu")
		(net "GND")
	)
	(via
		(at 46.3423 38.6969)
		(size 0.6096)
		(drill 0.25654)
		(layers "F.Cu" "B.Cu")
		(net "GND")
	)
	(via
		(at 41.737001 4.542003)
		(size 0.4826)
		(drill 0.20574)
		(layers "F.Cu" "B.Cu")
		(net "GND")
	)
	(via
		(at 44.736995 30.542001)
		(size 0.4826)
		(drill 0.20574)
		(layers "F.Cu" "B.Cu")
		(net "GND")
	)
	(via
		(at 45.736993 10.541991)
		(size 0.4826)
		(drill 0.20574)
		(layers "F.Cu" "B.Cu")
		(net "GND")
	)
	(via
		(at 60.736988 4.542003)
		(size 0.4826)
		(drill 0.20574)
		(layers "F.Cu" "B.Cu")
		(net "GND")
	)
	(via
		(at 53.737002 4.542003)
		(size 0.4826)
		(drill 0.20574)
		(layers "F.Cu" "B.Cu")
		(net "GND")
	)
	(via
		(at 48.737012 13.54201)
		(size 0.4826)
		(drill 0.20574)
		(layers "F.Cu" "B.Cu")
		(net "GND")
	)
	(via
		(at 9.0424 27.2669)
		(size 0.508)
		(drill 0.254)
		(layers "F.Cu" "B.Cu")
		(net "GND")
	)
	(via
		(at 56.736996 25.542011)
		(size 0.4826)
		(drill 0.20574)
		(layers "F.Cu" "B.Cu")
		(net "GND")
	)
	(via
		(at 56.736996 16.542004)
		(size 0.4826)
		(drill 0.20574)
		(layers "F.Cu" "B.Cu")
		(net "GND")
	)
	(via
		(at 81.050994 12.656007)
		(size 0.4572)
		(drill 0.20574)
		(layers "F.Cu" "B.Cu")
		(net "GND")
	)
	(via
		(at 69.736995 21.541994)
		(size 0.4826)
		(drill 0.20574)
		(layers "F.Cu" "B.Cu")
		(net "GND")
	)
	(via
		(at 73.152 43.688)
		(size 0.508)
		(drill 0.254)
		(layers "F.Cu" "B.Cu")
		(net "GND")
	)
	(via
		(at 67.736999 3.542005)
		(size 0.4826)
		(drill 0.20574)
		(layers "F.Cu" "B.Cu")
		(net "GND")
	)
	(via
		(at 61.737011 2.542007)
		(size 0.4826)
		(drill 0.20574)
		(layers "F.Cu" "B.Cu")
		(net "GND")
	)
	(via
		(at 42.736999 31.541999)
		(size 0.4826)
		(drill 0.20574)
		(layers "F.Cu" "B.Cu")
		(net "GND")
	)
	(via
		(at 38.737007 33.541995)
		(size 0.4826)
		(drill 0.20574)
		(layers "F.Cu" "B.Cu")
		(net "GND")
	)
	(via
		(at 7.7724 10.7569)
		(size 0.508)
		(drill 0.254)
		(layers "F.Cu" "B.Cu")
		(net "GND")
	)
	(via
		(at 65.737003 34.541993)
		(size 0.4826)
		(drill 0.20574)
		(layers "F.Cu" "B.Cu")
		(net "GND")
	)
	(via
		(at 50.737008 11.541989)
		(size 0.4826)
		(drill 0.20574)
		(layers "F.Cu" "B.Cu")
		(net "GND")
	)
	(via
		(at 72.251011 31.412993)
		(size 0.4572)
		(drill 0.20574)
		(layers "F.Cu" "B.Cu")
		(net "GND")
	)
	(via
		(at 82.65099 24.213007)
		(size 0.4572)
		(drill 0.20574)
		(layers "F.Cu" "B.Cu")
		(net "GND")
	)
	(via
		(at 44.736995 2.542007)
		(size 0.4826)
		(drill 0.20574)
		(layers "F.Cu" "B.Cu")
		(net "GND")
	)
	(via
		(at 16.6624 22.1869)
		(size 0.508)
		(drill 0.254)
		(layers "F.Cu" "B.Cu")
		(net "GND")
	)
	(via
		(at 49.73701 12.542012)
		(size 0.4826)
		(drill 0.20574)
		(layers "F.Cu" "B.Cu")
		(net "GND")
	)
	(via
		(at 65.737003 2.542007)
		(size 0.4826)
		(drill 0.20574)
		(layers "F.Cu" "B.Cu")
		(net "GND")
	)
	(via
		(at 40.386 36.195)
		(size 0.508)
		(drill 0.254)
		(layers "F.Cu" "B.Cu")
		(net "GND")
	)
	(via
		(at 52.737004 9.541993)
		(size 0.4826)
		(drill 0.20574)
		(layers "F.Cu" "B.Cu")
		(net "GND")
	)
	(via
		(at 65.9384 39.6875)
		(size 0.6096)
		(drill 0.25654)
		(layers "F.Cu" "B.Cu")
		(net "GND")
	)
	(via
		(at 67.31 39.6875)
		(size 0.6096)
		(drill 0.25654)
		(layers "F.Cu" "B.Cu")
		(net "GND")
	)
	(via
		(at 72.251011 24.213007)
		(size 0.4572)
		(drill 0.20574)
		(layers "F.Cu" "B.Cu")
		(net "GND")
	)
	(via
		(at 66.737001 21.541994)
		(size 0.4826)
		(drill 0.20574)
		(layers "F.Cu" "B.Cu")
		(net "GND")
	)
	(via
		(at 51.943 53.3146)
		(size 0.508)
		(drill 0.254)
		(layers "F.Cu" "B.Cu")
		(net "GND")
	)
	(via
		(at 46.736991 8.541995)
		(size 0.4826)
		(drill 0.20574)
		(layers "F.Cu" "B.Cu")
		(net "GND")
	)
	(via
		(at 67.736999 5.542001)
		(size 0.4826)
		(drill 0.20574)
		(layers "F.Cu" "B.Cu")
		(net "GND")
	)
	(via
		(at 51.737006 7.541997)
		(size 0.4826)
		(drill 0.20574)
		(layers "F.Cu" "B.Cu")
		(net "GND")
	)
	(via
		(at 67.736999 8.541995)
		(size 0.4826)
		(drill 0.20574)
		(layers "F.Cu" "B.Cu")
		(net "GND")
	)
	(via
		(at 51.737006 10.541991)
		(size 0.4826)
		(drill 0.20574)
		(layers "F.Cu" "B.Cu")
		(net "GND")
	)
	(via
		(at 14.1224 23.4569)
		(size 0.508)
		(drill 0.254)
		(layers "F.Cu" "B.Cu")
		(net "GND")
	)
	(via
		(at 39.737005 20.541996)
		(size 0.4826)
		(drill 0.20574)
		(layers "F.Cu" "B.Cu")
		(net "GND")
	)
	(via
		(at 7.7724 15.8369)
		(size 0.508)
		(drill 0.254)
		(layers "F.Cu" "B.Cu")
		(net "GND")
	)
	(via
		(at 50.737008 20.541996)
		(size 0.4826)
		(drill 0.20574)
		(layers "F.Cu" "B.Cu")
		(net "GND")
	)
	(via
		(at 16.6624 3.1369)
		(size 0.508)
		(drill 0.254)
		(layers "F.Cu" "B.Cu")
		(net "GND")
	)
	(via
		(at 57.736994 20.541996)
		(size 0.4826)
		(drill 0.20574)
		(layers "F.Cu" "B.Cu")
		(net "GND")
	)
	(via
		(at 59.73699 34.541993)
		(size 0.4826)
		(drill 0.20574)
		(layers "F.Cu" "B.Cu")
		(net "GND")
	)
	(via
		(at 13.843 37.0205)
		(size 0.508)
		(drill 0.25654)
		(layers "F.Cu" "B.Cu")
		(net "GND")
	)
	(via
		(at 67.736999 2.542007)
		(size 0.4826)
		(drill 0.20574)
		(layers "F.Cu" "B.Cu")
		(net "GND")
	)
	(via
		(at 47.7139 38.6969)
		(size 0.6096)
		(drill 0.25654)
		(layers "F.Cu" "B.Cu")
		(net "GND")
	)
	(via
		(at 78.74 44.4881)
		(size 0.508)
		(drill 0.25654)
		(layers "F.Cu" "B.Cu")
		(net "GND")
	)
	(via
		(at 66.737001 4.542003)
		(size 0.4826)
		(drill 0.20574)
		(layers "F.Cu" "B.Cu")
		(net "GND")
	)
	(via
		(at 72.251011 8.298993)
		(size 0.4572)
		(drill 0.20574)
		(layers "F.Cu" "B.Cu")
		(net "GND")
	)
	(via
		(at 68.736997 33.541995)
		(size 0.4826)
		(drill 0.20574)
		(layers "F.Cu" "B.Cu")
		(net "GND")
	)
	(via
		(at 84.201 48.133)
		(size 0.508)
		(drill 0.25654)
		(layers "F.Cu" "B.Cu")
		(net "GND")
	)
	(via
		(at 26.24328 41.275)
		(size 0.508)
		(drill 0.25654)
		(layers "F.Cu" "B.Cu")
		(net "GND")
	)
	(via
		(at 45.212 50.292)
		(size 0.508)
		(drill 0.254)
		(layers "F.Cu" "B.Cu")
		(net "GND")
	)
	(via
		(at 45.736993 7.541997)
		(size 0.4826)
		(drill 0.20574)
		(layers "F.Cu" "B.Cu")
		(net "GND")
	)
	(via
		(at 56.736996 19.541998)
		(size 0.4826)
		(drill 0.20574)
		(layers "F.Cu" "B.Cu")
		(net "GND")
	)
	(via
		(at 56.736996 29.542003)
		(size 0.4826)
		(drill 0.20574)
		(layers "F.Cu" "B.Cu")
		(net "GND")
	)
	(via
		(at 14.1224 13.2969)
		(size 0.508)
		(drill 0.254)
		(layers "F.Cu" "B.Cu")
		(net "GND")
	)
	(via
		(at 59.73699 2.542007)
		(size 0.4826)
		(drill 0.20574)
		(layers "F.Cu" "B.Cu")
		(net "GND")
	)
	(via
		(at 49.73701 33.541995)
		(size 0.4826)
		(drill 0.20574)
		(layers "F.Cu" "B.Cu")
		(net "GND")
	)
	(via
		(at 66.737001 5.542001)
		(size 0.4826)
		(drill 0.20574)
		(layers "F.Cu" "B.Cu")
		(net "GND")
	)
	(via
		(at 59.73699 26.542009)
		(size 0.4826)
		(drill 0.20574)
		(layers "F.Cu" "B.Cu")
		(net "GND")
	)
	(via
		(at 3.937 6.096)
		(size 0.508)
		(drill 0.254)
		(layers "F.Cu" "B.Cu")
		(net "GND")
	)
	(via
		(at 44.736995 28.542005)
		(size 0.4826)
		(drill 0.20574)
		(layers "F.Cu" "B.Cu")
		(net "GND")
	)
	(via
		(at 63.737007 8.541995)
		(size 0.4826)
		(drill 0.20574)
		(layers "F.Cu" "B.Cu")
		(net "GND")
	)
	(via
		(at 75.451005 19.855993)
		(size 0.4572)
		(drill 0.20574)
		(layers "F.Cu" "B.Cu")
		(net "GND")
	)
	(via
		(at 77.343 44.4881)
		(size 0.508)
		(drill 0.25654)
		(layers "F.Cu" "B.Cu")
		(net "GND")
	)
	(via
		(at 57.736994 15.542006)
		(size 0.4826)
		(drill 0.20574)
		(layers "F.Cu" "B.Cu")
		(net "GND")
	)
	(via
		(at 15.3924 4.4069)
		(size 0.508)
		(drill 0.254)
		(layers "F.Cu" "B.Cu")
		(net "GND")
	)
	(via
		(at 56.736996 33.541995)
		(size 0.4826)
		(drill 0.20574)
		(layers "F.Cu" "B.Cu")
		(net "GND")
	)
	(via
		(at 31.3309 42.545)
		(size 0.508)
		(drill 0.25654)
		(layers "F.Cu" "B.Cu")
		(net "GND")
	)
	(via
		(at 66.802 44.958)
		(size 0.508)
		(drill 0.254)
		(layers "F.Cu" "B.Cu")
		(net "GND")
	)
	(via
		(at 74.651006 1.099007)
		(size 0.4572)
		(drill 0.20574)
		(layers "F.Cu" "B.Cu")
		(net "GND")
	)
	(via
		(at 55.736998 26.542009)
		(size 0.4826)
		(drill 0.20574)
		(layers "F.Cu" "B.Cu")
		(net "GND")
	)
	(via
		(at 70.736993 33.541995)
		(size 0.4826)
		(drill 0.20574)
		(layers "F.Cu" "B.Cu")
		(net "GND")
	)
	(via
		(at 43.736997 14.542008)
		(size 0.4826)
		(drill 0.20574)
		(layers "F.Cu" "B.Cu")
		(net "GND")
	)
	(via
		(at 9.0424 18.3769)
		(size 0.508)
		(drill 0.254)
		(layers "F.Cu" "B.Cu")
		(net "GND")
	)
	(via
		(at 25.527 28.8925)
		(size 0.508)
		(drill 0.25654)
		(layers "F.Cu" "B.Cu")
		(net "GND")
	)
	(via
		(at 59.73699 17.542002)
		(size 0.4826)
		(drill 0.20574)
		(layers "F.Cu" "B.Cu")
		(net "GND")
	)
	(via
		(at 46.736991 28.542005)
		(size 0.4826)
		(drill 0.20574)
		(layers "F.Cu" "B.Cu")
		(net "GND")
	)
	(via
		(at 15.1765 37.0205)
		(size 0.508)
		(drill 0.25654)
		(layers "F.Cu" "B.Cu")
		(net "GND")
	)
	(via
		(at 52.737004 24.541988)
		(size 0.4826)
		(drill 0.20574)
		(layers "F.Cu" "B.Cu")
		(net "GND")
	)
	(via
		(at 49.53 47.8409)
		(size 0.508)
		(drill 0.25654)
		(layers "F.Cu" "B.Cu")
		(net "GND")
	)
	(via
		(at 41.737001 7.541997)
		(size 0.4826)
		(drill 0.20574)
		(layers "F.Cu" "B.Cu")
		(net "GND")
	)
	(via
		(at 33.274 7.62)
		(size 0.6096)
		(drill 0.25654)
		(layers "F.Cu" "B.Cu")
		(net "GND")
	)
	(via
		(at 73.851008 30.612994)
		(size 0.4572)
		(drill 0.20574)
		(layers "F.Cu" "B.Cu")
		(net "GND")
	)
	(via
		(at 47.7139 39.6875)
		(size 0.6096)
		(drill 0.25654)
		(layers "F.Cu" "B.Cu")
		(net "GND")
	)
	(via
		(at 74.651006 13.456006)
		(size 0.4572)
		(drill 0.20574)
		(layers "F.Cu" "B.Cu")
		(net "GND")
	)
	(via
		(at 30.4038 26.8986)
		(size 0.4572)
		(drill 0.20574)
		(layers "F.Cu" "B.Cu")
		(net "GND")
	)
	(via
		(at 47.736989 23.54199)
		(size 0.4826)
		(drill 0.20574)
		(layers "F.Cu" "B.Cu")
		(net "GND")
	)
	(via
		(at 60.8076 54.737)
		(size 0.508)
		(drill 0.25654)
		(layers "F.Cu" "B.Cu")
		(net "GND")
	)
	(via
		(at 10.3124 20.9169)
		(size 0.508)
		(drill 0.254)
		(layers "F.Cu" "B.Cu")
		(net "GND")
	)
	(via
		(at 76.251003 19.855993)
		(size 0.4572)
		(drill 0.20574)
		(layers "F.Cu" "B.Cu")
		(net "GND")
	)
	(via
		(at 50.737008 9.541993)
		(size 0.4826)
		(drill 0.20574)
		(layers "F.Cu" "B.Cu")
		(net "GND")
	)
	(via
		(at 48.737012 26.542009)
		(size 0.4826)
		(drill 0.20574)
		(layers "F.Cu" "B.Cu")
		(net "GND")
	)
	(via
		(at 51.943 50.8)
		(size 0.508)
		(drill 0.2667)
		(layers "F.Cu" "B.Cu")
		(net "GND")
	)
	(via
		(at 36.5125 34.925)
		(size 0.508)
		(drill 0.25654)
		(layers "F.Cu" "B.Cu")
		(net "GND")
	)
	(via
		(at 60.736988 31.541999)
		(size 0.4826)
		(drill 0.20574)
		(layers "F.Cu" "B.Cu")
		(net "GND")
	)
	(via
		(at 67.736999 29.542003)
		(size 0.4826)
		(drill 0.20574)
		(layers "F.Cu" "B.Cu")
		(net "GND")
	)
	(via
		(at 52.737004 34.541993)
		(size 0.4826)
		(drill 0.20574)
		(layers "F.Cu" "B.Cu")
		(net "GND")
	)
	(via
		(at 48.737012 34.541993)
		(size 0.4826)
		(drill 0.20574)
		(layers "F.Cu" "B.Cu")
		(net "GND")
	)
	(via
		(at 14.1224 18.3769)
		(size 0.508)
		(drill 0.254)
		(layers "F.Cu" "B.Cu")
		(net "GND")
	)
	(via
		(at 28.702 18.5039)
		(size 0.508)
		(drill 0.25654)
		(layers "F.Cu" "B.Cu")
		(net "GND")
	)
	(via
		(at 50.737008 28.542005)
		(size 0.4826)
		(drill 0.20574)
		(layers "F.Cu" "B.Cu")
		(net "GND")
	)
	(via
		(at 47.736989 5.542001)
		(size 0.4826)
		(drill 0.20574)
		(layers "F.Cu" "B.Cu")
		(net "GND")
	)
	(via
		(at 63.737007 2.542007)
		(size 0.4826)
		(drill 0.20574)
		(layers "F.Cu" "B.Cu")
		(net "GND")
	)
	(via
		(at 64.737005 33.541995)
		(size 0.4826)
		(drill 0.20574)
		(layers "F.Cu" "B.Cu")
		(net "GND")
	)
	(via
		(at 16.51 48.7045)
		(size 0.508)
		(drill 0.25654)
		(layers "F.Cu" "B.Cu")
		(net "GND")
	)
	(via
		(at 67.736999 34.541993)
		(size 0.4826)
		(drill 0.20574)
		(layers "F.Cu" "B.Cu")
		(net "GND")
	)
	(via
		(at 10.3124 10.7569)
		(size 0.508)
		(drill 0.254)
		(layers "F.Cu" "B.Cu")
		(net "GND")
	)
	(via
		(at 58.736992 14.542008)
		(size 0.4826)
		(drill 0.20574)
		(layers "F.Cu" "B.Cu")
		(net "GND")
	)
	(via
		(at 56.736996 2.542007)
		(size 0.4826)
		(drill 0.20574)
		(layers "F.Cu" "B.Cu")
		(net "GND")
	)
	(via
		(at 49.73701 25.542011)
		(size 0.4826)
		(drill 0.20574)
		(layers "F.Cu" "B.Cu")
		(net "GND")
	)
	(via
		(at 54.737 2.542007)
		(size 0.4826)
		(drill 0.20574)
		(layers "F.Cu" "B.Cu")
		(net "GND")
	)
	(via
		(at 12.8524 25.9969)
		(size 0.508)
		(drill 0.254)
		(layers "F.Cu" "B.Cu")
		(net "GND")
	)
	(via
		(at 62.737009 8.541995)
		(size 0.4826)
		(drill 0.20574)
		(layers "F.Cu" "B.Cu")
		(net "GND")
	)
	(via
		(at 57.736994 26.542009)
		(size 0.4826)
		(drill 0.20574)
		(layers "F.Cu" "B.Cu")
		(net "GND")
	)
	(via
		(at 74.651006 1.899006)
		(size 0.4572)
		(drill 0.20574)
		(layers "F.Cu" "B.Cu")
		(net "GND")
	)
	(via
		(at 44.736995 22.541992)
		(size 0.4826)
		(drill 0.20574)
		(layers "F.Cu" "B.Cu")
		(net "GND")
	)
	(via
		(at 84.250987 19.855993)
		(size 0.4572)
		(drill 0.20574)
		(layers "F.Cu" "B.Cu")
		(net "GND")
	)
	(via
		(at 66.737001 12.542012)
		(size 0.4826)
		(drill 0.20574)
		(layers "F.Cu" "B.Cu")
		(net "GND")
	)
	(via
		(at 48.737012 30.542001)
		(size 0.4826)
		(drill 0.20574)
		(layers "F.Cu" "B.Cu")
		(net "GND")
	)
	(via
		(at 59.73699 32.541997)
		(size 0.4826)
		(drill 0.20574)
		(layers "F.Cu" "B.Cu")
		(net "GND")
	)
	(via
		(at 40.737003 15.542006)
		(size 0.4826)
		(drill 0.20574)
		(layers "F.Cu" "B.Cu")
		(net "GND")
	)
	(via
		(at 46.736991 26.542009)
		(size 0.4826)
		(drill 0.20574)
		(layers "F.Cu" "B.Cu")
		(net "GND")
	)
	(via
		(at 50.737008 30.542001)
		(size 0.4826)
		(drill 0.20574)
		(layers "F.Cu" "B.Cu")
		(net "GND")
	)
	(via
		(at 76.251003 31.412993)
		(size 0.4572)
		(drill 0.20574)
		(layers "F.Cu" "B.Cu")
		(net "GND")
	)
	(via
		(at 12.8524 10.7569)
		(size 0.508)
		(drill 0.254)
		(layers "F.Cu" "B.Cu")
		(net "GND")
	)
	(via
		(at 16.6624 13.2969)
		(size 0.508)
		(drill 0.254)
		(layers "F.Cu" "B.Cu")
		(net "GND")
	)
	(via
		(at 53.737002 14.542008)
		(size 0.4826)
		(drill 0.20574)
		(layers "F.Cu" "B.Cu")
		(net "GND")
	)
	(via
		(at 47.736989 19.541998)
		(size 0.4826)
		(drill 0.20574)
		(layers "F.Cu" "B.Cu")
		(net "GND")
	)
	(via
		(at 63.737007 5.542001)
		(size 0.4826)
		(drill 0.20574)
		(layers "F.Cu" "B.Cu")
		(net "GND")
	)
	(via
		(at 40.737003 3.542005)
		(size 0.4826)
		(drill 0.20574)
		(layers "F.Cu" "B.Cu")
		(net "GND")
	)
	(via
		(at 48.737012 2.542007)
		(size 0.4826)
		(drill 0.20574)
		(layers "F.Cu" "B.Cu")
		(net "GND")
	)
	(via
		(at 45.736993 29.542003)
		(size 0.4826)
		(drill 0.20574)
		(layers "F.Cu" "B.Cu")
		(net "GND")
	)
	(via
		(at 51.943 48.26)
		(size 0.508)
		(drill 0.254)
		(layers "F.Cu" "B.Cu")
		(net "GND")
	)
	(via
		(at 56.736996 10.541991)
		(size 0.4826)
		(drill 0.20574)
		(layers "F.Cu" "B.Cu")
		(net "GND")
	)
	(via
		(at 59.73699 20.541996)
		(size 0.4826)
		(drill 0.20574)
		(layers "F.Cu" "B.Cu")
		(net "GND")
	)
	(via
		(at 20.066 7.747)
		(size 0.508)
		(drill 0.254)
		(layers "F.Cu" "B.Cu")
		(net "GND")
	)
	(via
		(at 73.05101 3.499002)
		(size 0.4572)
		(drill 0.20574)
		(layers "F.Cu" "B.Cu")
		(net "GND")
	)
	(via
		(at 72.251011 25.813004)
		(size 0.4572)
		(drill 0.20574)
		(layers "F.Cu" "B.Cu")
		(net "GND")
	)
	(via
		(at 69.342 44.958)
		(size 0.508)
		(drill 0.254)
		(layers "F.Cu" "B.Cu")
		(net "GND")
	)
	(via
		(at 42.545 54.737)
		(size 0.508)
		(drill 0.25654)
		(layers "F.Cu" "B.Cu")
		(net "GND")
	)
	(via
		(at 44.736995 16.542004)
		(size 0.4826)
		(drill 0.20574)
		(layers "F.Cu" "B.Cu")
		(net "GND")
	)
	(via
		(at 67.31 38.6969)
		(size 0.6096)
		(drill 0.25654)
		(layers "F.Cu" "B.Cu")
		(net "GND")
	)
	(via
		(at 55.736998 13.54201)
		(size 0.4826)
		(drill 0.20574)
		(layers "F.Cu" "B.Cu")
		(net "GND")
	)
	(via
		(at 32.385 39.37)
		(size 0.6096)
		(drill 0.25654)
		(layers "F.Cu" "B.Cu")
		(net "GND")
	)
	(via
		(at 39.737005 34.541993)
		(size 0.4826)
		(drill 0.20574)
		(layers "F.Cu" "B.Cu")
		(net "GND")
	)
	(via
		(at 29.845 39.37)
		(size 0.6096)
		(drill 0.25654)
		(layers "F.Cu" "B.Cu")
		(net "GND")
	)
	(via
		(at 49.73701 7.541997)
		(size 0.4826)
		(drill 0.20574)
		(layers "F.Cu" "B.Cu")
		(net "GND")
	)
	(via
		(at 11.5824 17.1069)
		(size 0.508)
		(drill 0.254)
		(layers "F.Cu" "B.Cu")
		(net "GND")
	)
	(via
		(at 57.736994 24.541988)
		(size 0.4826)
		(drill 0.20574)
		(layers "F.Cu" "B.Cu")
		(net "GND")
	)
	(via
		(at 49.73701 29.542003)
		(size 0.4826)
		(drill 0.20574)
		(layers "F.Cu" "B.Cu")
		(net "GND")
	)
	(via
		(at 53.737002 27.542007)
		(size 0.4826)
		(drill 0.20574)
		(layers "F.Cu" "B.Cu")
		(net "GND")
	)
	(via
		(at 15.5321 40.894)
		(size 0.508)
		(drill 0.25654)
		(layers "F.Cu" "B.Cu")
		(net "GND")
	)
	(via
		(at 32.766 32.2199)
		(size 0.508)
		(drill 0.25654)
		(layers "F.Cu" "B.Cu")
		(net "GND")
	)
	(via
		(at 61.737011 29.542003)
		(size 0.4826)
		(drill 0.20574)
		(layers "F.Cu" "B.Cu")
		(net "GND")
	)
	(via
		(at 15.3924 5.6769)
		(size 0.508)
		(drill 0.254)
		(layers "F.Cu" "B.Cu")
		(net "GND")
	)
	(via
		(at 64.737005 4.542003)
		(size 0.4826)
		(drill 0.20574)
		(layers "F.Cu" "B.Cu")
		(net "GND")
	)
	(via
		(at 74.651006 30.612994)
		(size 0.4572)
		(drill 0.20574)
		(layers "F.Cu" "B.Cu")
		(net "GND")
	)
	(via
		(at 74.651006 12.656007)
		(size 0.4572)
		(drill 0.20574)
		(layers "F.Cu" "B.Cu")
		(net "GND")
	)
	(via
		(at 49.73701 4.542003)
		(size 0.4826)
		(drill 0.20574)
		(layers "F.Cu" "B.Cu")
		(net "GND")
	)
	(via
		(at 64.008 49.276)
		(size 0.508)
		(drill 0.25654)
		(layers "F.Cu" "B.Cu")
		(net "GND")
	)
	(via
		(at 45.736993 31.541999)
		(size 0.4826)
		(drill 0.20574)
		(layers "F.Cu" "B.Cu")
		(net "GND")
	)
	(via
		(at 59.73699 30.542001)
		(size 0.4826)
		(drill 0.20574)
		(layers "F.Cu" "B.Cu")
		(net "GND")
	)
	(via
		(at 31.877 29.7434)
		(size 0.4572)
		(drill 0.20574)
		(layers "F.Cu" "B.Cu")
		(net "GND")
	)
	(via
		(at 68.736997 7.541997)
		(size 0.4826)
		(drill 0.20574)
		(layers "F.Cu" "B.Cu")
		(net "GND")
	)
	(via
		(at 32.004 7.62)
		(size 0.6096)
		(drill 0.25654)
		(layers "F.Cu" "B.Cu")
		(net "GND")
	)
	(via
		(at 64.9351 52.07)
		(size 0.508)
		(drill 0.25654)
		(layers "F.Cu" "B.Cu")
		(net "GND")
	)
	(via
		(at 62.737009 5.542001)
		(size 0.4826)
		(drill 0.20574)
		(layers "F.Cu" "B.Cu")
		(net "GND")
	)
	(via
		(at 3.937 19.812)
		(size 0.508)
		(drill 0.254)
		(layers "F.Cu" "B.Cu")
		(net "GND")
	)
	(via
		(at 14.2875 37.9095)
		(size 0.508)
		(drill 0.25654)
		(layers "F.Cu" "B.Cu")
		(net "GND")
	)
	(via
		(at 21.717 3.937)
		(size 0.6096)
		(drill 0.25654)
		(layers "F.Cu" "B.Cu")
		(net "GND")
	)
	(via
		(at 3.937 21.082)
		(size 0.508)
		(drill 0.254)
		(layers "F.Cu" "B.Cu")
		(net "GND")
	)
	(via
		(at 44.736995 11.541989)
		(size 0.4826)
		(drill 0.20574)
		(layers "F.Cu" "B.Cu")
		(net "GND")
	)
	(via
		(at 66.737001 7.541997)
		(size 0.4826)
		(drill 0.20574)
		(layers "F.Cu" "B.Cu")
		(net "GND")
	)
	(via
		(at 78.650998 1.899006)
		(size 0.4572)
		(drill 0.20574)
		(layers "F.Cu" "B.Cu")
		(net "GND")
	)
	(via
		(at 13.843 36.576)
		(size 0.508)
		(drill 0.25654)
		(layers "F.Cu" "B.Cu")
		(net "GND")
	)
	(via
		(at 10.3124 24.7269)
		(size 0.508)
		(drill 0.254)
		(layers "F.Cu" "B.Cu")
		(net "GND")
	)
	(via
		(at 61.737011 32.541997)
		(size 0.4826)
		(drill 0.20574)
		(layers "F.Cu" "B.Cu")
		(net "GND")
	)
	(via
		(at 44.736995 13.54201)
		(size 0.4826)
		(drill 0.20574)
		(layers "F.Cu" "B.Cu")
		(net "GND")
	)
	(via
		(at 23.2537 39.5986)
		(size 0.508)
		(drill 0.25654)
		(layers "F.Cu" "B.Cu")
		(net "GND")
	)
	(via
		(at 55.736998 32.541997)
		(size 0.4826)
		(drill 0.20574)
		(layers "F.Cu" "B.Cu")
		(net "GND")
	)
	(via
		(at 12.8524 5.6769)
		(size 0.508)
		(drill 0.254)
		(layers "F.Cu" "B.Cu")
		(net "GND")
	)
	(via
		(at 50.737008 32.541997)
		(size 0.4826)
		(drill 0.20574)
		(layers "F.Cu" "B.Cu")
		(net "GND")
	)
	(via
		(at 51.737006 16.542004)
		(size 0.4826)
		(drill 0.20574)
		(layers "F.Cu" "B.Cu")
		(net "GND")
	)
	(via
		(at 49.1236 51.816)
		(size 0.508)
		(drill 0.25654)
		(layers "F.Cu" "B.Cu")
		(net "GND")
	)
	(via
		(at 50.737008 22.541992)
		(size 0.4826)
		(drill 0.20574)
		(layers "F.Cu" "B.Cu")
		(net "GND")
	)
	(via
		(at 84.250987 1.099007)
		(size 0.4572)
		(drill 0.20574)
		(layers "F.Cu" "B.Cu")
		(net "GND")
	)
	(via
		(at 65.737003 25.542011)
		(size 0.4826)
		(drill 0.20574)
		(layers "F.Cu" "B.Cu")
		(net "GND")
	)
	(via
		(at 55.736998 20.541996)
		(size 0.4826)
		(drill 0.20574)
		(layers "F.Cu" "B.Cu")
		(net "GND")
	)
	(via
		(at 33.5788 20.2946)
		(size 0.4572)
		(drill 0.20574)
		(layers "F.Cu" "B.Cu")
		(net "GND")
	)
	(via
		(at 61.737011 28.542005)
		(size 0.4826)
		(drill 0.20574)
		(layers "F.Cu" "B.Cu")
		(net "GND")
	)
	(via
		(at 58.736992 27.542007)
		(size 0.4826)
		(drill 0.20574)
		(layers "F.Cu" "B.Cu")
		(net "GND")
	)
	(via
		(at 56.736996 27.542007)
		(size 0.4826)
		(drill 0.20574)
		(layers "F.Cu" "B.Cu")
		(net "GND")
	)
	(via
		(at 59.73699 15.542006)
		(size 0.4826)
		(drill 0.20574)
		(layers "F.Cu" "B.Cu")
		(net "GND")
	)
	(via
		(at 10.3124 14.5669)
		(size 0.508)
		(drill 0.254)
		(layers "F.Cu" "B.Cu")
		(net "GND")
	)
	(via
		(at 50.673 50.8)
		(size 0.508)
		(drill 0.254)
		(layers "F.Cu" "B.Cu")
		(net "GND")
	)
	(via
		(at 81.050994 8.298993)
		(size 0.4572)
		(drill 0.20574)
		(layers "F.Cu" "B.Cu")
		(net "GND")
	)
	(via
		(at 47.736989 29.542003)
		(size 0.4826)
		(drill 0.20574)
		(layers "F.Cu" "B.Cu")
		(net "GND")
	)
	(via
		(at 65.405 53.213)
		(size 0.508)
		(drill 0.25654)
		(layers "F.Cu" "B.Cu")
		(net "GND")
	)
	(via
		(at 43.736997 29.542003)
		(size 0.4826)
		(drill 0.20574)
		(layers "F.Cu" "B.Cu")
		(net "GND")
	)
	(via
		(at 58.736992 4.542003)
		(size 0.4826)
		(drill 0.20574)
		(layers "F.Cu" "B.Cu")
		(net "GND")
	)
	(via
		(at 76.251003 24.213007)
		(size 0.4572)
		(drill 0.20574)
		(layers "F.Cu" "B.Cu")
		(net "GND")
	)
	(via
		(at 45.736993 33.541995)
		(size 0.4826)
		(drill 0.20574)
		(layers "F.Cu" "B.Cu")
		(net "GND")
	)
	(via
		(at 14.2875 37.465)
		(size 0.508)
		(drill 0.25654)
		(layers "F.Cu" "B.Cu")
		(net "GND")
	)
	(via
		(at 43.736997 15.542006)
		(size 0.4826)
		(drill 0.20574)
		(layers "F.Cu" "B.Cu")
		(net "GND")
	)
	(via
		(at 11.5824 12.0269)
		(size 0.508)
		(drill 0.254)
		(layers "F.Cu" "B.Cu")
		(net "GND")
	)
	(via
		(at 59.73699 28.542005)
		(size 0.4826)
		(drill 0.20574)
		(layers "F.Cu" "B.Cu")
		(net "GND")
	)
	(via
		(at 81.050994 31.412993)
		(size 0.4572)
		(drill 0.20574)
		(layers "F.Cu" "B.Cu")
		(net "GND")
	)
	(via
		(at 64.737005 7.541997)
		(size 0.4826)
		(drill 0.20574)
		(layers "F.Cu" "B.Cu")
		(net "GND")
	)
	(via
		(at 74.651006 19.055994)
		(size 0.4572)
		(drill 0.20574)
		(layers "F.Cu" "B.Cu")
		(net "GND")
	)
	(via
		(at 49.73701 5.542001)
		(size 0.4826)
		(drill 0.20574)
		(layers "F.Cu" "B.Cu")
		(net "GND")
	)
	(via
		(at 56.736996 14.542008)
		(size 0.4826)
		(drill 0.20574)
		(layers "F.Cu" "B.Cu")
		(net "GND")
	)
	(via
		(at 9.7155 33.6169)
		(size 0.508)
		(drill 0.25654)
		(layers "F.Cu" "B.Cu")
		(net "GND")
	)
	(via
		(at 39.737005 25.542011)
		(size 0.4826)
		(drill 0.20574)
		(layers "F.Cu" "B.Cu")
		(net "GND")
	)
	(via
		(at 22.987 3.937)
		(size 0.6096)
		(drill 0.25654)
		(layers "F.Cu" "B.Cu")
		(net "GND")
	)
	(via
		(at 7.7724 24.7269)
		(size 0.508)
		(drill 0.254)
		(layers "F.Cu" "B.Cu")
		(net "GND")
	)
	(via
		(at 80.264 50.8)
		(size 0.508)
		(drill 0.254)
		(layers "F.Cu" "B.Cu")
		(net "GND")
	)
	(via
		(at 43.736997 27.542007)
		(size 0.4826)
		(drill 0.20574)
		(layers "F.Cu" "B.Cu")
		(net "GND")
	)
	(via
		(at 63.737007 29.542003)
		(size 0.4826)
		(drill 0.20574)
		(layers "F.Cu" "B.Cu")
		(net "GND")
	)
	(via
		(at 73.05101 15.056002)
		(size 0.4572)
		(drill 0.20574)
		(layers "F.Cu" "B.Cu")
		(net "GND")
	)
	(via
		(at 3.937 7.366)
		(size 0.508)
		(drill 0.254)
		(layers "F.Cu" "B.Cu")
		(net "GND")
	)
	(via
		(at 48.737012 17.542002)
		(size 0.4826)
		(drill 0.20574)
		(layers "F.Cu" "B.Cu")
		(net "GND")
	)
	(segment
		(start 47.236761 12.04214)
		(end 47.237117 12.04214)
		(width 0.254)
		(layer "B.Cu")
		(net "GND")
	)
	(segment
		(start 47.236964 31.041975)
		(end 47.736989 31.541999)
		(width 0.254)
		(layer "B.Cu")
		(net "GND")
	)
	(segment
		(start 65.737003 16.542004)
		(end 66.236875 17.041876)
		(width 0.254)
		(layer "B.Cu")
		(net "GND")
	)
	(segment
		(start 13.4874 20.2819)
		(end 12.8524 19.6469)
		(width 0.254)
		(layer "B.Cu")
		(net "GND")
	)
	(segment
		(start 76.651002 30.212995)
		(end 76.251003 30.612994)
		(width 0.254)
		(layer "B.Cu")
		(net "GND")
	)
	(segment
		(start 14.7574 12.6619)
		(end 14.1224 12.0269)
		(width 0.254)
		(layer "B.Cu")
		(net "GND")
	)
	(segment
		(start 60.563887 19.177)
		(end 59.928887 18.542)
		(width 0.254)
		(layer "B.Cu")
		(net "GND")
	)
	(segment
		(start 13.4874 21.5519)
		(end 12.8524 20.9169)
		(width 0.254)
		(layer "B.Cu")
		(net "GND")
	)
	(segment
		(start 10.9474 15.2019)
		(end 10.3124 14.5669)
		(width 0.254)
		(layer "B.Cu")
		(net "GND")
	)
	(segment
		(start 72.65101 14.656003)
		(end 73.05101 15.056002)
		(width 0.254)
		(layer "B.Cu")
		(net "GND")
	)
	(segment
		(start 1.654988 13.966012)
		(end 0.8382 13.966012)
		(width 0.2032)
		(layer "B.Cu")
		(net "GND")
	)
	(segment
		(start 44.736995 11.541989)
		(end 44.237021 11.042015)
		(width 0.254)
		(layer "B.Cu")
		(net "GND")
	)
	(segment
		(start 46.1899 35.089084)
		(end 46.736991 34.541993)
		(width 0.254)
		(layer "B.Cu")
		(net "GND")
	)
	(segment
		(start 61.4553 34.823705)
		(end 61.737011 34.541993)
		(width 0.508)
		(layer "B.Cu")
		(net "GND")
	)
	(segment
		(start 28.321 24.892)
		(end 28.6131 24.5999)
		(width 0.2032)
		(layer "B.Cu")
		(net "GND")
	)
	(segment
		(start 5.7531 10.7569)
		(end 7.7724 10.7569)
		(width 0.2032)
		(layer "B.Cu")
		(net "GND")
	)
	(segment
		(start 75.051006 13.856005)
		(end 74.651006 13.456006)
		(width 0.254)
		(layer "B.Cu")
		(net "GND")
	)
	(segment
		(start 61.737011 9.541993)
		(end 61.237114 10.04189)
		(width 0.254)
		(layer "B.Cu")
		(net "GND")
	)
	(segment
		(start 57.23702 8.042021)
		(end 56.736996 7.541997)
		(width 0.254)
		(layer "B.Cu")
		(net "GND")
	)
	(segment
		(start 8.4074 20.2819)
		(end 7.7724 19.6469)
		(width 0.254)
		(layer "B.Cu")
		(net "GND")
	)
	(segment
		(start 24.638 32.2199)
		(end 24.638 31.369)
		(width 0.508)
		(layer "B.Cu")
		(net "GND")
	)
	(segment
		(start 60.236989 13.042011)
		(end 60.236862 13.042011)
		(width 0.254)
		(layer "B.Cu")
		(net "GND")
	)
	(segment
		(start 30.7213 20.7137)
		(end 30.7213 21.281034)
		(width 0.127)
		(layer "B.Cu")
		(net "GND")
	)
	(segment
		(start 52.237132 10.041865)
		(end 52.237132 10.042017)
		(width 0.254)
		(layer "B.Cu")
		(net "GND")
	)
	(segment
		(start 13.4874 26.6319)
		(end 12.8524 25.9969)
		(width 0.254)
		(layer "B.Cu")
		(net "GND")
	)
	(segment
		(start 45.236994 16.042005)
		(end 45.237146 16.042005)
		(width 0.254)
		(layer "B.Cu")
		(net "GND")
	)
	(segment
		(start 67.567988 44.297651)
		(end 67.567988 43.5864)
		(width 0.254)
		(layer "B.Cu")
		(net "GND")
	)
	(segment
		(start 72.65101 19.455994)
		(end 72.251011 19.855993)
		(width 0.254)
		(layer "B.Cu")
		(net "GND")
	)
	(segment
		(start 39.237031 15.042134)
		(end 40.237029 15.042134)
		(width 0.254)
		(layer "B.Cu")
		(net "GND")
	)
	(segment
		(start 27.432 32.2199)
		(end 27.432 30.9499)
		(width 0.254)
		(layer "B.Cu")
		(net "GND")
	)
	(segment
		(start 40.237131 15.042134)
		(end 40.237029 15.042134)
		(width 0.254)
		(layer "B.Cu")
		(net "GND")
	)
	(segment
		(start 69.736995 5.542001)
		(end 69.237098 6.041898)
		(width 0.254)
		(layer "B.Cu")
		(net "GND")
	)
	(segment
		(start 65.2526 24.2316)
		(end 64.262 24.2316)
		(width 0.508)
		(layer "B.Cu")
		(net "GND")
	)
	(segment
		(start 10.9474 26.6319)
		(end 10.3124 25.9969)
		(width 0.254)
		(layer "B.Cu")
		(net "GND")
	)
	(segment
		(start 61.23686 15.04188)
		(end 61.23686 15.042007)
		(width 0.254)
		(layer "B.Cu")
		(net "GND")
	)
	(segment
		(start 65.737003 24.716003)
		(end 65.2526 24.2316)
		(width 0.508)
		(layer "B.Cu")
		(net "GND")
	)
	(segment
		(start 78.250999 2.299005)
		(end 78.650998 1.899006)
		(width 0.254)
		(layer "B.Cu")
		(net "GND")
	)
	(segment
		(start 30.988 5.1689)
		(end 31.9151 5.1689)
		(width 0.508)
		(layer "B.Cu")
		(net "GND")
	)
	(segment
		(start 69.568009 44.297651)
		(end 69.568009 43.5864)
		(width 0.254)
		(layer "B.Cu")
		(net "GND")
	)
	(segment
		(start 68.237125 17.041876)
		(end 68.236973 17.041876)
		(width 0.254)
		(layer "B.Cu")
		(net "GND")
	)
	(segment
		(start 61.236987 34.041994)
		(end 61.236987 34.042096)
		(width 0.254)
		(layer "B.Cu")
		(net "GND")
	)
	(segment
		(start 45.736993 14.542008)
		(end 45.237146 15.041855)
		(width 0.254)
		(layer "B.Cu")
		(net "GND")
	)
	(segment
		(start 48.237013 30.042028)
		(end 48.237013 30.042104)
		(width 0.254)
		(layer "B.Cu")
		(net "GND")
	)
	(segment
		(start 49.47191 44.297651)
		(end 49.47191 43.5864)
		(width 0.254)
		(layer "B.Cu")
		(net "GND")
	)
	(segment
		(start 58.736992 12.542012)
		(end 59.236864 12.04214)
		(width 0.254)
		(layer "B.Cu")
		(net "GND")
	)
	(segment
		(start 76.651002 24.613006)
		(end 76.251003 24.213007)
		(width 0.254)
		(layer "B.Cu")
		(net "GND")
	)
	(segment
		(start 50.237009 10.041992)
		(end 50.237009 10.042144)
		(width 0.254)
		(layer "B.Cu")
		(net "GND")
	)
	(segment
		(start 27.6606 26.8986)
		(end 27.432 26.67)
		(width 0.2032)
		(layer "B.Cu")
		(net "GND")
	)
	(segment
		(start 12.2174 24.0919)
		(end 11.5824 23.4569)
		(width 0.254)
		(layer "B.Cu")
		(net "GND")
	)
	(segment
		(start 46.736991 8.541995)
		(end 46.237093 9.041892)
		(width 0.254)
		(layer "B.Cu")
		(net "GND")
	)
	(segment
		(start 64.236879 13.041884)
		(end 64.236981 13.041884)
		(width 0.254)
		(layer "B.Cu")
		(net "GND")
	)
	(segment
		(start 17.2974 19.0119)
		(end 17.9324 18.3769)
		(width 0.254)
		(layer "B.Cu")
		(net "GND")
	)
	(segment
		(start 27.686 17.1831)
		(end 28.702 18.1991)
		(width 0.508)
		(layer "B.Cu")
		(net "GND")
	)
	(segment
		(start 44.237021 9.041968)
		(end 44.237021 9.041892)
		(width 0.254)
		(layer "B.Cu")
		(net "GND")
	)
	(segment
		(start 69.237098 6.041898)
		(end 69.236971 6.041898)
		(width 0.254)
		(layer "B.Cu")
		(net "GND")
	)
	(segment
		(start 60.736988 27.542007)
		(end 60.236989 28.042006)
		(width 0.254)
		(layer "B.Cu")
		(net "GND")
	)
	(segment
		(start 20.955 7.7089)
		(end 20.066 7.747)
		(width 0.254)
		(layer "B.Cu")
		(net "GND")
	)
	(segment
		(start 9.6774 6.3119)
		(end 9.0424 5.6769)
		(width 0.254)
		(layer "B.Cu")
		(net "GND")
	)
	(segment
		(start 75.051006 2.299005)
		(end 74.651006 1.899006)
		(width 0.254)
		(layer "B.Cu")
		(net "GND")
	)
	(segment
		(start 70.7644 43.334559)
		(end 70.7644 42.890008)
		(width 0.254)
		(layer "B.Cu")
		(net "GND")
	)
	(segment
		(start 47.971888 37.6936)
		(end 47.971888 38.438912)
		(width 0.254)
		(layer "B.Cu")
		(net "GND")
	)
	(segment
		(start 10.9474 25.3619)
		(end 10.3124 24.7269)
		(width 0.254)
		(layer "B.Cu")
		(net "GND")
	)
	(segment
		(start 53.23713 5.042027)
		(end 53.23713 5.041875)
		(width 0.254)
		(layer "B.Cu")
		(net "GND")
	)
	(segment
		(start 81.1149 41.0845)
		(end 81.153 41.0464)
		(width 0.254)
		(layer "B.Cu")
		(net "GND")
	)
	(segment
		(start 63.2841 2.994914)
		(end 63.2841 3.556)
		(width 0.254)
		(layer "B.Cu")
		(net "GND")
	)
	(segment
		(start 45.236892 34.042096)
		(end 45.237019 34.042096)
		(width 0.254)
		(layer "B.Cu")
		(net "GND")
	)
	(segment
		(start 75.051006 1.499006)
		(end 74.651006 1.099007)
		(width 0.254)
		(layer "B.Cu")
		(net "GND")
	)
	(segment
		(start 12.2174 12.6619)
		(end 11.5824 12.0269)
		(width 0.254)
		(layer "B.Cu")
		(net "GND")
	)
	(segment
		(start 5.715 16.256)
		(end 6.1341 15.8369)
		(width 0.254)
		(layer "B.Cu")
		(net "GND")
	)
	(segment
		(start 41.2369 7.041896)
		(end 41.237027 7.041896)
		(width 0.254)
		(layer "B.Cu")
		(net "GND")
	)
	(segment
		(start 60.236989 10.041992)
		(end 60.236989 10.042144)
		(width 0.254)
		(layer "B.Cu")
		(net "GND")
	)
	(segment
		(start 47.0789 35.2933)
		(end 47.0789 34.950806)
		(width 0.254)
		(layer "B.Cu")
		(net "GND")
	)
	(segment
		(start 14.7574 24.0919)
		(end 14.1224 23.4569)
		(width 0.254)
		(layer "B.Cu")
		(net "GND")
	)
	(segment
		(start 47.236761 13.042138)
		(end 47.236761 13.04224)
		(width 0.254)
		(layer "B.Cu")
		(net "GND")
	)
	(segment
		(start 60.736988 7.541997)
		(end 60.236989 7.041998)
		(width 0.254)
		(layer "B.Cu")
		(net "GND")
	)
	(segment
		(start 62.737009 8.541995)
		(end 63.236907 9.041892)
		(width 0.254)
		(layer "B.Cu")
		(net "GND")
	)
	(segment
		(start 20.701 16.4719)
		(end 20.2819 16.4719)
		(width 0.2032)
		(layer "B.Cu")
		(net "GND")
	)
	(segment
		(start 28.702 18.1991)
		(end 28.702 18.5039)
		(width 0.508)
		(layer "B.Cu")
		(net "GND")
	)
	(segment
		(start 26.8859 19.2024)
		(end 26.8859 20.1168)
		(width 0.254)
		(layer "B.Cu")
		(net "GND")
	)
	(segment
		(start 13.4874 16.4719)
		(end 12.8524 15.8369)
		(width 0.254)
		(layer "B.Cu")
		(net "GND")
	)
	(segment
		(start 63.23711 13.042011)
		(end 63.23711 13.041909)
		(width 0.254)
		(layer "B.Cu")
		(net "GND")
	)
	(segment
		(start 49.236884 13.042138)
		(end 48.737012 13.54201)
		(width 0.254)
		(layer "B.Cu")
		(net "GND")
	)
	(segment
		(start 58.736992 27.542007)
		(end 58.237095 27.04211)
		(width 0.254)
		(layer "B.Cu")
		(net "GND")
	)
	(segment
		(start 14.7574 17.7419)
		(end 14.1224 17.1069)
		(width 0.254)
		(layer "B.Cu")
		(net "GND")
	)
	(segment
		(start 57.237122 6.041873)
		(end 57.237122 6.042025)
		(width 0.254)
		(layer "B.Cu")
		(net "GND")
	)
	(segment
		(start 40.737003 15.542006)
		(end 40.237131 15.042134)
		(width 0.254)
		(layer "B.Cu")
		(net "GND")
	)
	(segment
		(start 66.675 35.2171)
		(end 66.675 34.603995)
		(width 0.254)
		(layer "B.Cu")
		(net "GND")
	)
	(segment
		(start 45.236994 20.041997)
		(end 45.237146 20.041997)
		(width 0.254)
		(layer "B.Cu")
		(net "GND")
	)
	(segment
		(start 48.471912 44.297651)
		(end 48.471912 43.5864)
		(width 0.254)
		(layer "B.Cu")
		(net "GND")
	)
	(segment
		(start 47.736989 18.722111)
		(end 47.736989 19.541998)
		(width 0.254)
		(layer "B.Cu")
		(net "GND")
	)
	(segment
		(start 41.737001 22.541992)
		(end 41.237154 23.041839)
		(width 0.254)
		(layer "B.Cu")
		(net "GND")
	)
	(segment
		(start 30.3022 20.2946)
		(end 30.7213 20.7137)
		(width 0.127)
		(layer "B.Cu")
		(net "GND")
	)
	(segment
		(start 16.0274 20.2819)
		(end 15.3924 19.6469)
		(width 0.254)
		(layer "B.Cu")
		(net "GND")
	)
	(segment
		(start 9.6774 12.6619)
		(end 10.3124 12.0269)
		(width 0.254)
		(layer "B.Cu")
		(net "GND")
	)
	(segment
		(start 60.736988 12.542012)
		(end 60.236989 13.042011)
		(width 0.254)
		(layer "B.Cu")
		(net "GND")
	)
	(segment
		(start 47.236761 13.04224)
		(end 46.736991 13.54201)
		(width 0.254)
		(layer "B.Cu")
		(net "GND")
	)
	(segment
		(start 83.850988 31.012994)
		(end 84.36803 31.471514)
		(width 0.254)
		(layer "B.Cu")
		(net "GND")
	)
	(segment
		(start 51.237109 27.04211)
		(end 51.237007 27.04211)
		(width 0.254)
		(layer "B.Cu")
		(net "GND")
	)
	(segment
		(start 76.651002 13.056006)
		(end 76.251003 12.656007)
		(width 0.254)
		(layer "B.Cu")
		(net "GND")
	)
	(segment
		(start 74.251007 1.499006)
		(end 73.851008 1.099007)
		(width 0.254)
		(layer "B.Cu")
		(net "GND")
	)
	(segment
		(start 10.9474 11.3919)
		(end 10.3124 10.7569)
		(width 0.254)
		(layer "B.Cu")
		(net "GND")
	)
	(segment
		(start 62.236985 10.042017)
		(end 62.236985 10.04189)
		(width 0.254)
		(layer "B.Cu")
		(net "GND")
	)
	(segment
		(start 45.736993 16.542004)
		(end 46.236992 17.042003)
		(width 0.254)
		(layer "B.Cu")
		(net "GND")
	)
	(segment
		(start 83.2739 42.9006)
		(end 83.566 42.5069)
		(width 0.2032)
		(layer "B.Cu")
		(net "GND")
	)
	(segment
		(start 56.736996 14.542008)
		(end 57.236868 14.042136)
		(width 0.254)
		(layer "B.Cu")
		(net "GND")
	)
	(segment
		(start 74.251007 30.212995)
		(end 73.851008 30.612994)
		(width 0.254)
		(layer "B.Cu")
		(net "GND")
	)
	(segment
		(start 53.23713 12.04214)
		(end 53.237003 12.04214)
		(width 0.254)
		(layer "B.Cu")
		(net "GND")
	)
	(segment
		(start 53.737002 27.542007)
		(end 54.284093 27.542007)
		(width 0.254)
		(layer "B.Cu")
		(net "GND")
	)
	(segment
		(start 60.236862 17.04213)
		(end 60.236862 17.042003)
		(width 0.254)
		(layer "B.Cu")
		(net "GND")
	)
	(segment
		(start 10.9474 6.3119)
		(end 10.3124 5.6769)
		(width 0.254)
		(layer "B.Cu")
		(net "GND")
	)
	(segment
		(start 45.236994 13.042011)
		(end 45.237146 13.042011)
		(width 0.254)
		(layer "B.Cu")
		(net "GND")
	)
	(segment
		(start 44.736995 16.542004)
		(end 45.236994 16.042005)
		(width 0.254)
		(layer "B.Cu")
		(net "GND")
	)
	(segment
		(start 61.23686 25.041987)
		(end 61.23686 25.042139)
		(width 0.254)
		(layer "B.Cu")
		(net "GND")
	)
	(segment
		(start 5.334 11.176)
		(end 5.7531 10.7569)
		(width 0.2032)
		(layer "B.Cu")
		(net "GND")
	)
	(segment
		(start 10.9474 21.5519)
		(end 10.3124 20.9169)
		(width 0.254)
		(layer "B.Cu")
		(net "GND")
	)
	(segment
		(start 46.1899 35.2171)
		(end 46.1899 35.089084)
		(width 0.254)
		(layer "B.Cu")
		(net "GND")
	)
	(segment
		(start 43.736997 14.542008)
		(end 44.236894 14.042111)
		(width 0.254)
		(layer "B.Cu")
		(net "GND")
	)
	(segment
		(start 61.737011 10.541991)
		(end 62.236985 10.042017)
		(width 0.254)
		(layer "B.Cu")
		(net "GND")
	)
	(segment
		(start 74.251007 18.655995)
		(end 73.851008 19.055994)
		(width 0.254)
		(layer "B.Cu")
		(net "GND")
	)
	(segment
		(start 26.924 21.8567)
		(end 26.8859 21.8059)
		(width 0.14732)
		(layer "B.Cu")
		(net "GND")
	)
	(segment
		(start 50.237136 11.042117)
		(end 50.737008 11.541989)
		(width 0.254)
		(layer "B.Cu")
		(net "GND")
	)
	(segment
		(start 75.051006 7.098995)
		(end 74.651006 7.498994)
		(width 0.254)
		(layer "B.Cu")
		(net "GND")
	)
	(segment
		(start 50.9016 18.542)
		(end 51.276377 18.916777)
		(width 0.254)
		(layer "B.Cu")
		(net "GND")
	)
	(segment
		(start 67.567988 38.438912)
		(end 67.31 38.6969)
		(width 0.254)
		(layer "B.Cu")
		(net "GND")
	)
	(segment
		(start 50.237136 11.042015)
		(end 50.237136 11.042117)
		(width 0.254)
		(layer "B.Cu")
		(net "GND")
	)
	(segment
		(start 53.737002 31.541999)
		(end 54.643299 31.541999)
		(width 0.254)
		(layer "B.Cu")
		(net "GND")
	)
	(segment
		(start 3.9751 10.16)
		(end 4.23418 10.41908)
		(width 0.2032)
		(layer "B.Cu")
		(net "GND")
	)
	(segment
		(start 52.237005 14.042009)
		(end 52.237005 14.042136)
		(width 0.254)
		(layer "B.Cu")
		(net "GND")
	)
	(segment
		(start 72.65101 3.099003)
		(end 73.05101 3.499002)
		(width 0.254)
		(layer "B.Cu")
		(net "GND")
	)
	(segment
		(start 44.736995 13.54201)
		(end 45.236994 13.042011)
		(width 0.254)
		(layer "B.Cu")
		(net "GND")
	)
	(segment
		(start 30.734 21.293734)
		(end 30.734 21.8059)
		(width 0.127)
		(layer "B.Cu")
		(net "GND")
	)
	(segment
		(start 47.237015 11.041964)
		(end 47.237015 11.042142)
		(width 0.254)
		(layer "B.Cu")
		(net "GND")
	)
	(segment
		(start 58.236993 7.041998)
		(end 58.736992 7.541997)
		(width 0.254)
		(layer "B.Cu")
		(net "GND")
	)
	(segment
		(start 44.237148 22.041993)
		(end 44.236996 22.041993)
		(width 0.254)
		(layer "B.Cu")
		(net "GND")
	)
	(segment
		(start 59.73699 32.541997)
		(end 59.237093 32.0421)
		(width 0.254)
		(layer "B.Cu")
		(net "GND")
	)
	(segment
		(start 56.236997 10.041992)
		(end 55.736998 9.541993)
		(width 0.254)
		(layer "B.Cu")
		(net "GND")
	)
	(segment
		(start 26.416 21.336)
		(end 26.416 20.6121)
		(width 0.14732)
		(layer "B.Cu")
		(net "GND")
	)
	(segment
		(start 16.0274 15.2019)
		(end 15.3924 14.5669)
		(width 0.254)
		(layer "B.Cu")
		(net "GND")
	)
	(segment
		(start 76.651002 18.655995)
		(end 76.251003 19.055994)
		(width 0.254)
		(layer "B.Cu")
		(net "GND")
	)
	(segment
		(start 5.334 14.9987)
		(end 7.3406 14.9987)
		(width 0.254)
		(layer "B.Cu")
		(net "GND")
	)
	(segment
		(start 17.2974 13.9319)
		(end 16.6624 13.2969)
		(width 0.254)
		(layer "B.Cu")
		(net "GND")
	)
	(segment
		(start 13.4874 5.0419)
		(end 12.8524 4.4069)
		(width 0.254)
		(layer "B.Cu")
		(net "GND")
	)
	(segment
		(start 4.572 17.8689)
		(end 5.334 17.8181)
		(width 0.254)
		(layer "B.Cu")
		(net "GND")
	)
	(segment
		(start 28.6131 24.5999)
		(end 28.6131 24.003)
		(width 0.2032)
		(layer "B.Cu")
		(net "GND")
	)
	(segment
		(start 46.97189 44.297651)
		(end 46.97189 43.5864)
		(width 0.254)
		(layer "B.Cu")
		(net "GND")
	)
	(segment
		(start 80.650994 7.898994)
		(end 81.050994 8.298993)
		(width 0.254)
		(layer "B.Cu")
		(net "GND")
	)
	(segment
		(start 13.4874 25.3619)
		(end 12.8524 24.7269)
		(width 0.254)
		(layer "B.Cu")
		(net "GND")
	)
	(segment
		(start 75.051006 18.655995)
		(end 74.651006 19.055994)
		(width 0.254)
		(layer "B.Cu")
		(net "GND")
	)
	(segment
		(start 58.236993 7.041896)
		(end 58.236993 7.041998)
		(width 0.254)
		(layer "B.Cu")
		(net "GND")
	)
	(segment
		(start 63.737007 12.542012)
		(end 64.236879 13.041884)
		(width 0.254)
		(layer "B.Cu")
		(net "GND")
	)
	(segment
		(start 48.736987 7.541997)
		(end 48.236886 8.041894)
		(width 0.254)
		(layer "B.Cu")
		(net "GND")
	)
	(segment
		(start 20.32 13.1699)
		(end 20.32 12.446)
		(width 0.2032)
		(layer "B.Cu")
		(net "GND")
	)
	(segment
		(start 30.4038 26.8986)
		(end 27.6606 26.8986)
		(width 0.2032)
		(layer "B.Cu")
		(net "GND")
	)
	(segment
		(start 65.735911 39.889989)
		(end 65.9384 39.6875)
		(width 0.254)
		(layer "B.Cu")
		(net "GND")
	)
	(segment
		(start 82.250991 1.499006)
		(end 82.65099 1.099007)
		(width 0.254)
		(layer "B.Cu")
		(net "GND")
	)
	(segment
		(start 58.736992 7.541997)
		(end 59.236991 7.041998)
		(width 0.254)
		(layer "B.Cu")
		(net "GND")
	)
	(segment
		(start 60.236989 28.042006)
		(end 60.236989 28.042108)
		(width 0.254)
		(layer "B.Cu")
		(net "GND")
	)
	(segment
		(start 49.664112 7.469099)
		(end 49.73701 7.541997)
		(width 0.508)
		(layer "B.Cu")
		(net "GND")
	)
	(segment
		(start 51.276377 18.916777)
		(end 51.276377 19.081369)
		(width 0.254)
		(layer "B.Cu")
		(net "GND")
	)
	(segment
		(start 53.237003 19.041999)
		(end 53.737002 19.541998)
		(width 0.254)
		(layer "B.Cu")
		(net "GND")
	)
	(segment
		(start 55.736998 34.541993)
		(end 55.696891 34.5821)
		(width 0.254)
		(layer "B.Cu")
		(net "GND")
	)
	(segment
		(start 60.095511 34.900514)
		(end 59.73699 34.541993)
		(width 0.254)
		(layer "B.Cu")
		(net "GND")
	)
	(segment
		(start 69.06801 44.297651)
		(end 69.06801 43.5864)
		(width 0.254)
		(layer "B.Cu")
		(net "GND")
	)
	(segment
		(start 35.7251 29.083)
		(end 36.378388 29.736288)
		(width 0.254)
		(layer "B.Cu")
		(net "GND")
	)
	(segment
		(start 8.4074 21.5519)
		(end 7.7724 20.9169)
		(width 0.254)
		(layer "B.Cu")
		(net "GND")
	)
	(segment
		(start 57.736994 32.541997)
		(end 57.237097 32.0421)
		(width 0.254)
		(layer "B.Cu")
		(net "GND")
	)
	(segment
		(start 67.5132 32.004)
		(end 68.736997 33.278597)
		(width 0.508)
		(layer "B.Cu")
		(net "GND")
	)
	(segment
		(start 78.250999 13.856005)
		(end 78.650998 13.456006)
		(width 0.254)
		(layer "B.Cu")
		(net "GND")
	)
	(segment
		(start 9.6774 7.5819)
		(end 9.0424 6.9469)
		(width 0.254)
		(layer "B.Cu")
		(net "GND")
	)
	(segment
		(start 78.250999 18.655995)
		(end 78.650998 19.055994)
		(width 0.254)
		(layer "B.Cu")
		(net "GND")
	)
	(segment
		(start 78.250999 7.098995)
		(end 78.650998 7.498994)
		(width 0.254)
		(layer "B.Cu")
		(net "GND")
	)
	(segment
		(start 46.982609 34.854515)
		(end 46.982609 34.787611)
		(width 0.254)
		(layer "B.Cu")
		(net "GND")
	)
	(segment
		(start 5.334 17.8181)
		(end 5.715 17.4371)
		(width 0.254)
		(layer "B.Cu")
		(net "GND")
	)
	(segment
		(start 8.4074 6.3119)
		(end 7.7724 5.6769)
		(width 0.254)
		(layer "B.Cu")
		(net "GND")
	)
	(segment
		(start 14.7574 8.8519)
		(end 14.1224 8.2169)
		(width 0.254)
		(layer "B.Cu")
		(net "GND")
	)
	(segment
		(start 67.236975 12.042038)
		(end 66.737001 12.542012)
		(width 0.254)
		(layer "B.Cu")
		(net "GND")
	)
	(segment
		(start 39.737005 25.542011)
		(end 39.237107 25.042114)
		(width 0.254)
		(layer "B.Cu")
		(net "GND")
	)
	(segment
		(start 44.237021 11.042015)
		(end 44.237021 11.041888)
		(width 0.254)
		(layer "B.Cu")
		(net "GND")
	)
	(segment
		(start 36.378388 29.736288)
		(end 36.378388 30.550917)
		(width 0.254)
		(layer "B.Cu")
		(net "GND")
	)
	(segment
		(start 83.850988 1.499006)
		(end 84.250987 1.099007)
		(width 0.254)
		(layer "B.Cu")
		(net "GND")
	)
	(segment
		(start 7.7724 14.5669)
		(end 8.4074 15.2019)
		(width 0.254)
		(layer "B.Cu")
		(net "GND")
	)
	(segment
		(start 67.567988 37.6936)
		(end 67.567988 38.438912)
		(width 0.254)
		(layer "B.Cu")
		(net "GND")
	)
	(segment
		(start 82.1817 41.1099)
		(end 82.1182 41.0464)
		(width 0.2032)
		(layer "B.Cu")
		(net "GND")
	)
	(segment
		(start 74.251007 13.056006)
		(end 73.851008 12.656007)
		(width 0.254)
		(layer "B.Cu")
		(net "GND")
	)
	(segment
		(start 44.237148 23.041839)
		(end 44.736995 22.541992)
		(width 0.254)
		(layer "B.Cu")
		(net "GND")
	)
	(segment
		(start 30.988 7.9121)
		(end 31.7119 7.9121)
		(width 0.508)
		(layer "B.Cu")
		(net "GND")
	)
	(segment
		(start 9.6774 3.7719)
		(end 10.3124 3.1369)
		(width 0.254)
		(layer "B.Cu")
		(net "GND")
	)
	(segment
		(start 69.236971 13.041884)
		(end 69.237123 13.041884)
		(width 0.254)
		(layer "B.Cu")
		(net "GND")
	)
	(segment
		(start 81.5213 42.799)
		(end 81.8134 42.5069)
		(width 0.2032)
		(layer "B.Cu")
		(net "GND")
	)
	(segment
		(start 48.236886 8.041894)
		(end 48.237013 8.041894)
		(width 0.254)
		(layer "B.Cu")
		(net "GND")
	)
	(segment
		(start 58.237095 27.04211)
		(end 58.236993 27.04211)
		(width 0.254)
		(layer "B.Cu")
		(net "GND")
	)
	(segment
		(start 47.237117 12.04214)
		(end 47.736989 12.542012)
		(width 0.254)
		(layer "B.Cu")
		(net "GND")
	)
	(segment
		(start 59.237093 32.0421)
		(end 59.236991 32.0421)
		(width 0.254)
		(layer "B.Cu")
		(net "GND")
	)
	(segment
		(start 80.650994 23.767999)
		(end 81.050994 23.368)
		(width 0.254)
		(layer "B.Cu")
		(net "GND")
	)
	(segment
		(start 70.7644 42.890008)
		(end 71.475651 42.890008)
		(width 0.254)
		(layer "B.Cu")
		(net "GND")
	)
	(segment
		(start 47.736989 29.542003)
		(end 48.237013 30.042028)
		(width 0.254)
		(layer "B.Cu")
		(net "GND")
	)
	(segment
		(start 68.736997 33.278597)
		(end 68.736997 33.541995)
		(width 0.508)
		(layer "B.Cu")
		(net "GND")
	)
	(segment
		(start 41.737001 11.541989)
		(end 42.237025 12.042013)
		(width 0.2032)
		(layer "B.Cu")
		(net "GND")
	)
	(segment
		(start 83.185 43.9039)
		(end 83.2739 43.815)
		(width 0.2032)
		(layer "B.Cu")
		(net "GND")
	)
	(segment
		(start 51.1683 40.890012)
		(end 51.879551 40.890012)
		(width 0.254)
		(layer "B.Cu")
		(net "GND")
	)
	(segment
		(start 52.737004 9.541993)
		(end 52.237132 10.041865)
		(width 0.254)
		(layer "B.Cu")
		(net "GND")
	)
	(segment
		(start 52.237132 9.041867)
		(end 52.237132 9.042019)
		(width 0.254)
		(layer "B.Cu")
		(net "GND")
	)
	(segment
		(start 49.73701 10.541991)
		(end 49.237163 10.042144)
		(width 0.254)
		(layer "B.Cu")
		(net "GND")
	)
	(segment
		(start 53.237003 19.041872)
		(end 53.237003 19.041999)
		(width 0.254)
		(layer "B.Cu")
		(net "GND")
	)
	(segment
		(start 61.23686 16.042132)
		(end 61.23686 16.042005)
		(width 0.254)
		(layer "B.Cu")
		(net "GND")
	)
	(segment
		(start 72.65101 26.213003)
		(end 72.251011 25.813004)
		(width 0.254)
		(layer "B.Cu")
		(net "GND")
	)
	(segment
		(start 57.23697 7.042023)
		(end 57.237122 7.042023)
		(width 0.254)
		(layer "B.Cu")
		(net "GND")
	)
	(segment
		(start 8.4074 11.3919)
		(end 7.7724 10.7569)
		(width 0.254)
		(layer "B.Cu")
		(net "GND")
	)
	(segment
		(start 75.336349 44.4881)
		(end 76.073 44.4881)
		(width 0.254)
		(layer "B.Cu")
		(net "GND")
	)
	(segment
		(start 31.877 22.6441)
		(end 31.5722 22.6441)
		(width 0.127)
		(layer "B.Cu")
		(net "GND")
	)
	(segment
		(start 52.237005 34.041994)
		(end 52.237005 34.042096)
		(width 0.254)
		(layer "B.Cu")
		(net "GND")
	)
	(segment
		(start 14.7574 7.5819)
		(end 14.1224 6.9469)
		(width 0.254)
		(layer "B.Cu")
		(net "GND")
	)
	(segment
		(start 51.737006 27.542007)
		(end 51.237109 27.04211)
		(width 0.254)
		(layer "B.Cu")
		(net "GND")
	)
	(segment
		(start 30.7721 27.2669)
		(end 30.4038 26.8986)
		(width 0.254)
		(layer "B.Cu")
		(net "GND")
	)
	(segment
		(start 10.9474 20.2819)
		(end 10.3124 19.6469)
		(width 0.254)
		(layer "B.Cu")
		(net "GND")
	)
	(segment
		(start 49.237011 13.042138)
		(end 49.236884 13.042138)
		(width 0.254)
		(layer "B.Cu")
		(net "GND")
	)
	(segment
		(start 54.7624 24.2189)
		(end 55.41391 24.2189)
		(width 0.254)
		(layer "B.Cu")
		(net "GND")
	)
	(segment
		(start 44.236996 25.041987)
		(end 43.736997 24.541988)
		(width 0.254)
		(layer "B.Cu")
		(net "GND")
	)
	(segment
		(start 9.6774 24.0919)
		(end 9.0424 23.4569)
		(width 0.254)
		(layer "B.Cu")
		(net "GND")
	)
	(segment
		(start 26.8859 18.9611)
		(end 26.8859 19.2024)
		(width 0.254)
		(layer "B.Cu")
		(net "GND")
	)
	(segment
		(start 48.971911 44.297651)
		(end 48.971911 43.5864)
		(width 0.254)
		(layer "B.Cu")
		(net "GND")
	)
	(segment
		(start 8.4074 10.1219)
		(end 7.7724 9.4869)
		(width 0.254)
		(layer "B.Cu")
		(net "GND")
	)
	(segment
		(start 44.236894 14.042111)
		(end 44.236894 14.042009)
		(width 0.254)
		(layer "B.Cu")
		(net "GND")
	)
	(segment
		(start 17.2974 22.8219)
		(end 16.6624 22.1869)
		(width 0.254)
		(layer "B.Cu")
		(net "GND")
	)
	(segment
		(start 49.73701 31.541999)
		(end 50.237009 32.041998)
		(width 0.254)
		(layer "B.Cu")
		(net "GND")
	)
	(segment
		(start 7.3406 14.9987)
		(end 7.7724 14.5669)
		(width 0.254)
		(layer "B.Cu")
		(net "GND")
	)
	(segment
		(start 51.1683 41.89001)
		(end 51.879551 41.89001)
		(width 0.254)
		(layer "B.Cu")
		(net "GND")
	)
	(segment
		(start 80.01 41.0845)
		(end 81.1149 41.0845)
		(width 0.254)
		(layer "B.Cu")
		(net "GND")
	)
	(segment
		(start 31.9151 5.1689)
		(end 32.004 5.08)
		(width 0.508)
		(layer "B.Cu")
		(net "GND")
	)
	(segment
		(start 45.236994 12.042013)
		(end 45.236892 12.042013)
		(width 0.254)
		(layer "B.Cu")
		(net "GND")
	)
	(segment
		(start 68.2371 6.041898)
		(end 68.736997 5.542001)
		(width 0.254)
		(layer "B.Cu")
		(net "GND")
	)
	(segment
		(start 83.850988 13.056006)
		(end 84.250987 12.656007)
		(width 0.254)
		(layer "B.Cu")
		(net "GND")
	)
	(segment
		(start 12.2174 17.7419)
		(end 11.5824 17.1069)
		(width 0.254)
		(layer "B.Cu")
		(net "GND")
	)
	(segment
		(start 61.4553 36.6141)
		(end 61.4553 34.823705)
		(width 0.508)
		(layer "B.Cu")
		(net "GND")
	)
	(segment
		(start 83.2739 43.815)
		(end 83.2739 42.9006)
		(width 0.2032)
		(layer "B.Cu")
		(net "GND")
	)
	(segment
		(start 42.736999 19.541998)
		(end 43.236871 19.042126)
		(width 0.254)
		(layer "B.Cu")
		(net "GND")
	)
	(segment
		(start 50.471908 43.5864)
		(end 50.916459 43.5864)
		(width 0.254)
		(layer "B.Cu")
		(net "GND")
	)
	(segment
		(start 70.7644 41.89001)
		(end 71.475651 41.89001)
		(width 0.254)
		(layer "B.Cu")
		(net "GND")
	)
	(segment
		(start 70.7644 40.890012)
		(end 71.475651 40.890012)
		(width 0.254)
		(layer "B.Cu")
		(net "GND")
	)
	(segment
		(start 61.23686 25.042139)
		(end 60.736988 25.542011)
		(width 0.254)
		(layer "B.Cu")
		(net "GND")
	)
	(segment
		(start 16.0274 16.4719)
		(end 15.3924 15.8369)
		(width 0.254)
		(layer "B.Cu")
		(net "GND")
	)
	(segment
		(start 55.696891 34.5821)
		(end 54.737 34.5821)
		(width 0.254)
		(layer "B.Cu")
		(net "GND")
	)
	(segment
		(start 1.905 13.716)
		(end 1.654988 13.966012)
		(width 0.2032)
		(layer "B.Cu")
		(net "GND")
	)
	(segment
		(start 45.236892 30.042104)
		(end 45.237019 30.042104)
		(width 0.254)
		(layer "B.Cu")
		(net "GND")
	)
	(segment
		(start 68.068012 44.297651)
		(end 68.068012 43.5864)
		(width 0.254)
		(layer "B.Cu")
		(net "GND")
	)
	(segment
		(start 77.343 45.275551)
		(end 77.343 44.4881)
		(width 0.254)
		(layer "B.Cu")
		(net "GND")
	)
	(segment
		(start 75.051006 13.056006)
		(end 74.651006 12.656007)
		(width 0.254)
		(layer "B.Cu")
		(net "GND")
	)
	(segment
		(start 36.378388 30.550917)
		(end 37.348871 31.5214)
		(width 0.254)
		(layer "B.Cu")
		(net "GND")
	)
	(segment
		(start 42.237025 7.041896)
		(end 42.237025 7.041972)
		(width 0.254)
		(layer "B.Cu")
		(net "GND")
	)
	(segment
		(start 31.5722 22.6441)
		(end 30.734 21.8059)
		(width 0.127)
		(layer "B.Cu")
		(net "GND")
	)
	(segment
		(start 13.4874 6.3119)
		(end 12.8524 5.6769)
		(width 0.254)
		(layer "B.Cu")
		(net "GND")
	)
	(segment
		(start 56.236997 28.042006)
		(end 56.236997 28.042108)
		(width 0.254)
		(layer "B.Cu")
		(net "GND")
	)
	(segment
		(start 54.643299 31.541999)
		(end 54.737 31.6357)
		(width 0.254)
		(layer "B.Cu")
		(net "GND")
	)
	(segment
		(start 30.7213 21.281034)
		(end 30.734 21.293734)
		(width 0.127)
		(layer "B.Cu")
		(net "GND")
	)
	(segment
		(start 70.7644 41.390011)
		(end 71.475651 41.390011)
		(width 0.254)
		(layer "B.Cu")
		(net "GND")
	)
	(segment
		(start 82.250991 13.056006)
		(end 82.65099 12.656007)
		(width 0.254)
		(layer "B.Cu")
		(net "GND")
	)
	(segment
		(start 76.651002 7.098995)
		(end 76.251003 7.498994)
		(width 0.254)
		(layer "B.Cu")
		(net "GND")
	)
	(segment
		(start 52.737004 13.54201)
		(end 52.237005 14.042009)
		(width 0.254)
		(layer "B.Cu")
		(net "GND")
	)
	(segment
		(start 47.236761 31.041975)
		(end 47.236964 31.041975)
		(width 0.254)
		(layer "B.Cu")
		(net "GND")
	)
	(segment
		(start 20.2819 16.4719)
		(end 19.812 16.51)
		(width 0.2032)
		(layer "B.Cu")
		(net "GND")
	)
	(segment
		(start 9.6774 13.9319)
		(end 10.3124 13.2969)
		(width 0.254)
		(layer "B.Cu")
		(net "GND")
	)
	(segment
		(start 51.236905 30.042104)
		(end 51.237007 30.042104)
		(width 0.254)
		(layer "B.Cu")
		(net "GND")
	)
	(segment
		(start 49.237163 10.042144)
		(end 49.237011 10.042144)
		(width 0.254)
		(layer "B.Cu")
		(net "GND")
	)
	(segment
		(start 26.416 20.6121)
		(end 26.924 20.1041)
		(width 0.14732)
		(layer "B.Cu")
		(net "GND")
	)
	(segment
		(start 57.736994 5.542001)
		(end 57.237122 6.041873)
		(width 0.254)
		(layer "B.Cu")
		(net "GND")
	)
	(segment
		(start 60.736988 33.541995)
		(end 61.236987 34.041994)
		(width 0.254)
		(layer "B.Cu")
		(net "GND")
	)
	(segment
		(start 71.851012 31.012994)
		(end 72.251011 31.412993)
		(width 0.254)
		(layer "B.Cu")
		(net "GND")
	)
	(segment
		(start 55.736998 35.251898)
		(end 56.0451 35.56)
		(width 0.254)
		(layer "B.Cu")
		(net "GND")
	)
	(segment
		(start 60.736988 14.542008)
		(end 61.23686 15.04188)
		(width 0.254)
		(layer "B.Cu")
		(net "GND")
	)
	(segment
		(start 68.568011 44.297651)
		(end 68.568011 43.5864)
		(width 0.254)
		(layer "B.Cu")
		(net "GND")
	)
	(segment
		(start 45.237146 15.041855)
		(end 45.237146 15.042007)
		(width 0.254)
		(layer "B.Cu")
		(net "GND")
	)
	(segment
		(start 74.251007 24.613006)
		(end 73.851008 24.213007)
		(width 0.254)
		(layer "B.Cu")
		(net "GND")
	)
	(segment
		(start 22.3139 32.5501)
		(end 22.3139 31.75)
		(width 0.2032)
		(layer "B.Cu")
		(net "GND")
	)
	(segment
		(start 46.237093 9.041892)
		(end 46.237017 9.041892)
		(width 0.254)
		(layer "B.Cu")
		(net "GND")
	)
	(segment
		(start 68.736997 16.542004)
		(end 68.237125 17.041876)
		(width 0.254)
		(layer "B.Cu")
		(net "GND")
	)
	(segment
		(start 65.737003 25.542011)
		(end 65.737003 24.716003)
		(width 0.508)
		(layer "B.Cu")
		(net "GND")
	)
	(segment
		(start 80.650994 24.613006)
		(end 80.650994 23.767999)
		(width 0.254)
		(layer "B.Cu")
		(net "GND")
	)
	(segment
		(start 48.768 2.572995)
		(end 48.768 3.6449)
		(width 0.508)
		(layer "B.Cu")
		(net "GND")
	)
	(segment
		(start 53.23713 5.041875)
		(end 53.737002 4.542003)
		(width 0.254)
		(layer "B.Cu")
		(net "GND")
	)
	(segment
		(start 58.736992 29.542003)
		(end 58.236993 30.042002)
		(width 0.254)
		(layer "B.Cu")
		(net "GND")
	)
	(segment
		(start 54.737 24.1427)
		(end 54.7624 24.2189)
		(width 0.254)
		(layer "B.Cu")
		(net "GND")
	)
	(segment
		(start 10.9474 10.1219)
		(end 10.3124 9.4869)
		(width 0.254)
		(layer "B.Cu")
		(net "GND")
	)
	(segment
		(start 14.7574 13.9319)
		(end 14.1224 13.2969)
		(width 0.254)
		(layer "B.Cu")
		(net "GND")
	)
	(segment
		(start 51.1683 43.334559)
		(end 51.1683 42.890008)
		(width 0.254)
		(layer "B.Cu")
		(net "GND")
	)
	(segment
		(start 53.23713 6.042025)
		(end 53.237028 6.042025)
		(width 0.254)
		(layer "B.Cu")
		(net "GND")
	)
	(segment
		(start 4.597476 10.7569)
		(end 4.9149 10.7569)
		(width 0.2032)
		(layer "B.Cu")
		(net "GND")
	)
	(segment
		(start 70.068008 44.297651)
		(end 70.068008 43.5864)
		(width 0.254)
		(layer "B.Cu")
		(net "GND")
	)
	(segment
		(start 66.236875 17.041876)
		(end 66.236977 17.041876)
		(width 0.254)
		(layer "B.Cu")
		(net "GND")
	)
	(segment
		(start 78.74 45.275551)
		(end 78.74 44.4881)
		(width 0.254)
		(layer "B.Cu")
		(net "GND")
	)
	(segment
		(start 57.237122 8.042021)
		(end 57.23702 8.042021)
		(width 0.254)
		(layer "B.Cu")
		(net "GND")
	)
	(segment
		(start 60.736988 16.542004)
		(end 61.23686 16.042132)
		(width 0.254)
		(layer "B.Cu")
		(net "GND")
	)
	(segment
		(start 74.251007 7.098995)
		(end 73.851008 7.498994)
		(width 0.254)
		(layer "B.Cu")
		(net "GND")
	)
	(segment
		(start 44.736995 20.541996)
		(end 45.236994 20.041997)
		(width 0.254)
		(layer "B.Cu")
		(net "GND")
	)
	(segment
		(start 57.237097 32.0421)
		(end 57.236995 32.0421)
		(width 0.254)
		(layer "B.Cu")
		(net "GND")
	)
	(segment
		(start 75.051006 24.613006)
		(end 74.651006 24.213007)
		(width 0.254)
		(layer "B.Cu")
		(net "GND")
	)
	(segment
		(start 76.073 45.275551)
		(end 76.073 44.4881)
		(width 0.254)
		(layer "B.Cu")
		(net "GND")
	)
	(segment
		(start 43.236871 19.042126)
		(end 43.237023 19.042126)
		(width 0.254)
		(layer "B.Cu")
		(net "GND")
	)
	(segment
		(start 37.348871 31.5214)
		(end 37.5285 31.5214)
		(width 0.254)
		(layer "B.Cu")
		(net "GND")
	)
	(segment
		(start 51.1683 42.390009)
		(end 51.879551 42.390009)
		(width 0.254)
		(layer "B.Cu")
		(net "GND")
	)
	(segment
		(start 16.0274 11.3919)
		(end 15.3924 10.7569)
		(width 0.254)
		(layer "B.Cu")
		(net "GND")
	)
	(segment
		(start 63.23711 13.041909)
		(end 63.737007 12.542012)
		(width 0.254)
		(layer "B.Cu")
		(net "GND")
	)
	(segment
		(start 66.56799 44.297651)
		(end 66.56799 43.5864)
		(width 0.254)
		(layer "B.Cu")
		(net "GND")
	)
	(segment
		(start 60.736988 21.541994)
		(end 61.23686 22.041866)
		(width 0.254)
		(layer "B.Cu")
		(net "GND")
	)
	(segment
		(start 53.737002 12.542012)
		(end 53.23713 12.04214)
		(width 0.254)
		(layer "B.Cu")
		(net "GND")
	)
	(segment
		(start 47.971888 44.297651)
		(end 47.971888 43.5864)
		(width 0.254)
		(layer "B.Cu")
		(net "GND")
	)
	(segment
		(start 83.850988 24.613006)
		(end 84.309509 24.154486)
		(width 0.254)
		(layer "B.Cu")
		(net "GND")
	)
	(segment
		(start 39.237031 26.041985)
		(end 39.737005 25.542011)
		(width 0.254)
		(layer "B.Cu")
		(net "GND")
	)
	(segment
		(start 62.237137 9.042019)
		(end 62.236985 9.042019)
		(width 0.254)
		(layer "B.Cu")
		(net "GND")
	)
	(segment
		(start 4.259656 10.41908)
		(end 4.597476 10.7569)
		(width 0.2032)
		(layer "B.Cu")
		(net "GND")
	)
	(segment
		(start 8.4074 25.3619)
		(end 7.7724 24.7269)
		(width 0.254)
		(layer "B.Cu")
		(net "GND")
	)
	(segment
		(start 12.2174 7.5819)
		(end 11.5824 6.9469)
		(width 0.254)
		(layer "B.Cu")
		(net "GND")
	)
	(segment
		(start 42.237025 12.042013)
		(end 42.237152 12.042013)
		(width 0.2032)
		(layer "B.Cu")
		(net "GND")
	)
	(segment
		(start 53.237028 6.042025)
		(end 52.737004 5.542001)
		(width 0.254)
		(layer "B.Cu")
		(net "GND")
	)
	(segment
		(start 51.276377 19.081369)
		(end 51.737006 19.541998)
		(width 0.254)
		(layer "B.Cu")
		(net "GND")
	)
	(segment
		(start 53.23713 7.042125)
		(end 53.737002 7.541997)
		(width 0.254)
		(layer "B.Cu")
		(net "GND")
	)
	(segment
		(start 53.737002 16.542004)
		(end 53.743098 16.5481)
		(width 0.254)
		(layer "B.Cu")
		(net "GND")
	)
	(segment
		(start 78.250999 25.413005)
		(end 78.650998 25.013006)
		(width 0.254)
		(layer "B.Cu")
		(net "GND")
	)
	(segment
		(start 12.2174 8.8519)
		(end 11.5824 8.2169)
		(width 0.254)
		(layer "B.Cu")
		(net "GND")
	)
	(segment
		(start 41.237154 23.041839)
		(end 41.237154 23.041991)
		(width 0.254)
		(layer "B.Cu")
		(net "GND")
	)
	(segment
		(start 50.737008 30.542001)
		(end 51.236905 30.042104)
		(width 0.254)
		(layer "B.Cu")
		(net "GND")
	)
	(segment
		(start 69.237123 13.041884)
		(end 69.736995 12.542012)
		(width 0.254)
		(layer "B.Cu")
		(net "GND")
	)
	(segment
		(start 17.2974 7.5819)
		(end 16.6624 6.9469)
		(width 0.254)
		(layer "B.Cu")
		(net "GND")
	)
	(segment
		(start 9.6774 27.9019)
		(end 9.0424 27.2669)
		(width 0.254)
		(layer "B.Cu")
		(net "GND")
	)
	(segment
		(start 60.736988 9.541993)
		(end 60.236989 10.041992)
		(width 0.254)
		(layer "B.Cu")
		(net "GND")
	)
	(segment
		(start 55.736998 34.541993)
		(end 55.736998 35.251898)
		(width 0.254)
		(layer "B.Cu")
		(net "GND")
	)
	(segment
		(start 16.0274 5.0419)
		(end 15.3924 4.4069)
		(width 0.254)
		(layer "B.Cu")
		(net "GND")
	)
	(segment
		(start 63.1571 6.121908)
		(end 63.1571 6.604)
		(width 0.254)
		(layer "B.Cu")
		(net "GND")
	)
	(segment
		(start 80.650994 13.056006)
		(end 81.050994 12.656007)
		(width 0.254)
		(layer "B.Cu")
		(net "GND")
	)
	(segment
		(start 60.5917 35.56)
		(end 60.095511 35.063811)
		(width 0.254)
		(layer "B.Cu")
		(net "GND")
	)
	(segment
		(start 12.2174 27.9019)
		(end 11.5824 27.2669)
		(width 0.254)
		(layer "B.Cu")
		(net "GND")
	)
	(segment
		(start 14.7574 19.0119)
		(end 14.1224 18.3769)
		(width 0.254)
		(layer "B.Cu")
		(net "GND")
	)
	(segment
		(start 40.030908 29.2481)
		(end 39.737005 29.542003)
		(width 0.254)
		(layer "B.Cu")
		(net "GND")
	)
	(segment
		(start 49.971909 44.297651)
		(end 49.971909 43.5864)
		(width 0.254)
		(layer "B.Cu")
		(net "GND")
	)
	(segment
		(start 12.2174 13.9319)
		(end 11.5824 13.2969)
		(width 0.254)
		(layer "B.Cu")
		(net "GND")
	)
	(segment
		(start 45.237146 19.042151)
		(end 45.237146 19.041999)
		(width 0.254)
		(layer "B.Cu")
		(net "GND")
	)
	(segment
		(start 39.237031 26.042112)
		(end 39.237031 26.041985)
		(width 0.254)
		(layer "B.Cu")
		(net "GND")
	)
	(segment
		(start 50.737008 9.541993)
		(end 50.237009 10.041992)
		(width 0.254)
		(layer "B.Cu")
		(net "GND")
	)
	(segment
		(start 8.4074 16.4719)
		(end 7.7724 15.8369)
		(width 0.254)
		(layer "B.Cu")
		(net "GND")
	)
	(segment
		(start 67.236975 12.041886)
		(end 67.236975 12.042038)
		(width 0.254)
		(layer "B.Cu")
		(net "GND")
	)
	(segment
		(start 44.736995 30.542001)
		(end 45.236892 30.042104)
		(width 0.254)
		(layer "B.Cu")
		(net "GND")
	)
	(segment
		(start 40.737003 6.541999)
		(end 41.2369 7.041896)
		(width 0.254)
		(layer "B.Cu")
		(net "GND")
	)
	(segment
		(start 53.23713 7.042023)
		(end 53.23713 7.042125)
		(width 0.254)
		(layer "B.Cu")
		(net "GND")
	)
	(segment
		(start 47.971888 38.438912)
		(end 47.7139 38.6969)
		(width 0.254)
		(layer "B.Cu")
		(net "GND")
	)
	(segment
		(start 68.236973 6.041898)
		(end 68.2371 6.041898)
		(width 0.254)
		(layer "B.Cu")
		(net "GND")
	)
	(segment
		(start 44.736995 34.541993)
		(end 45.236892 34.042096)
		(width 0.254)
		(layer "B.Cu")
		(net "GND")
	)
	(segment
		(start 51.737006 33.541995)
		(end 52.237005 34.041994)
		(width 0.254)
		(layer "B.Cu")
		(net "GND")
	)
	(segment
		(start 29.083 40.513)
		(end 29.845 39.37)
		(width 0.2032)
		(layer "B.Cu")
		(net "GND")
	)
	(segment
		(start 9.6774 8.8519)
		(end 9.0424 8.2169)
		(width 0.254)
		(layer "B.Cu")
		(net "GND")
	)
	(segment
		(start 6.1341 15.8369)
		(end 7.7724 15.8369)
		(width 0.254)
		(layer "B.Cu")
		(net "GND")
	)
	(segment
		(start 27.178 18.669)
		(end 26.8859 18.9611)
		(width 0.254)
		(layer "B.Cu")
		(net "GND")
	)
	(segment
		(start 72.65101 13.056006)
		(end 72.251011 12.656007)
		(width 0.254)
		(layer "B.Cu")
		(net "GND")
	)
	(segment
		(start 43.736997 9.541993)
		(end 44.237021 9.041968)
		(width 0.254)
		(layer "B.Cu")
		(net "GND")
	)
	(segment
		(start 65.786 35.2171)
		(end 65.786 34.59099)
		(width 0.254)
		(layer "B.Cu")
		(net "GND")
	)
	(segment
		(start 16.8783 33.3375)
		(end 16.8783 32.2453)
		(width 0.254)
		(layer "B.Cu")
		(net "GND")
	)
	(segment
		(start 66.675 34.603995)
		(end 66.737001 34.541993)
		(width 0.254)
		(layer "B.Cu")
		(net "GND")
	)
	(segment
		(start 12.2174 22.8219)
		(end 11.5824 22.1869)
		(width 0.254)
		(layer "B.Cu")
		(net "GND")
	)
	(segment
		(start 9.6774 17.7419)
		(end 9.0424 17.1069)
		(width 0.254)
		(layer "B.Cu")
		(net "GND")
	)
	(segment
		(start 16.0274 6.3119)
		(end 15.3924 5.6769)
		(width 0.254)
		(layer "B.Cu")
		(net "GND")
	)
	(segment
		(start 27.432 25.146)
		(end 27.686 24.892)
		(width 0.2032)
		(layer "B.Cu")
		(net "GND")
	)
	(segment
		(start 60.6044 37.465)
		(end 61.4553 36.6141)
		(width 0.508)
		(layer "B.Cu")
		(net "GND")
	)
	(segment
		(start 46.139811 39.889989)
		(end 46.3423 39.6875)
		(width 0.254)
		(layer "B.Cu")
		(net "GND")
	)
	(segment
		(start 75.851004 7.898994)
		(end 75.451005 8.298993)
		(width 0.254)
		(layer "B.Cu")
		(net "GND")
	)
	(segment
		(start 80.650994 1.499006)
		(end 81.050994 1.099007)
		(width 0.254)
		(layer "B.Cu")
		(net "GND")
	)
	(segment
		(start 66.095118 25.900126)
		(end 65.737003 25.542011)
		(width 0.254)
		(layer "B.Cu")
		(net "GND")
	)
	(segment
		(start 65.786 34.59099)
		(end 65.737003 34.541993)
		(width 0.254)
		(layer "B.Cu")
		(net "GND")
	)
	(segment
		(start 66.802 25.900126)
		(end 66.095118 25.900126)
		(width 0.254)
		(layer "B.Cu")
		(net "GND")
	)
	(segment
		(start 13.4874 11.3919)
		(end 12.8524 10.7569)
		(width 0.254)
		(layer "B.Cu")
		(net "GND")
	)
	(segment
		(start 27.686 24.892)
		(end 28.321 24.892)
		(width 0.2032)
		(layer "B.Cu")
		(net "GND")
	)
	(segment
		(start 12.2174 19.0119)
		(end 11.5824 18.3769)
		(width 0.254)
		(layer "B.Cu")
		(net "GND")
	)
	(segment
		(start 76.651002 7.898994)
		(end 76.251003 8.298993)
		(width 0.254)
		(layer "B.Cu")
		(net "GND")
	)
	(segment
		(start 45.2755 39.889989)
		(end 46.139811 39.889989)
		(width 0.254)
		(layer "B.Cu")
		(net "GND")
	)
	(segment
		(start 28.6131 24.003)
		(end 28.6131 23.5712)
		(width 0.2032)
		(layer "B.Cu")
		(net "GND")
	)
	(segment
		(start 63.236907 9.041892)
		(end 63.236983 9.041892)
		(width 0.254)
		(layer "B.Cu")
		(net "GND")
	)
	(segment
		(start 9.6774 19.0119)
		(end 9.0424 18.3769)
		(width 0.254)
		(layer "B.Cu")
		(net "GND")
	)
	(segment
		(start 44.237148 25.041987)
		(end 44.236996 25.041987)
		(width 0.254)
		(layer "B.Cu")
		(net "GND")
	)
	(segment
		(start 16.8783 32.2453)
		(end 16.764 32.131)
		(width 0.254)
		(layer "B.Cu")
		(net "GND")
	)
	(segment
		(start 16.0274 21.5519)
		(end 16.6624 20.9169)
		(width 0.254)
		(layer "B.Cu")
		(net "GND")
	)
	(segment
		(start 75.851004 31.012994)
		(end 75.451005 31.412993)
		(width 0.254)
		(layer "B.Cu")
		(net "GND")
	)
	(segment
		(start 62.236985 9.042019)
		(end 61.737011 9.541993)
		(width 0.254)
		(layer "B.Cu")
		(net "GND")
	)
	(segment
		(start 56.23687 11.042015)
		(end 56.236972 11.042015)
		(width 0.254)
		(layer "B.Cu")
		(net "GND")
	)
	(segment
		(start 28.5369 18.669)
		(end 27.178 18.669)
		(width 0.254)
		(layer "B.Cu")
		(net "GND")
	)
	(segment
		(start 31.7119 7.9121)
		(end 32.004 7.62)
		(width 0.508)
		(layer "B.Cu")
		(net "GND")
	)
	(segment
		(start 82.250991 31.012994)
		(end 82.65099 31.412993)
		(width 0.254)
		(layer "B.Cu")
		(net "GND")
	)
	(segment
		(start 63.737007 2.542007)
		(end 63.2841 2.994914)
		(width 0.254)
		(layer "B.Cu")
		(net "GND")
	)
	(segment
		(start 53.743098 16.5481)
		(end 54.737 16.5481)
		(width 0.254)
		(layer "B.Cu")
		(net "GND")
	)
	(segment
		(start 60.095511 35.063811)
		(end 60.095511 34.900514)
		(width 0.254)
		(layer "B.Cu")
		(net "GND")
	)
	(segment
		(start 17.2974 12.6619)
		(end 16.6624 12.0269)
		(width 0.254)
		(layer "B.Cu")
		(net "GND")
	)
	(segment
		(start 76.651002 31.012994)
		(end 76.251003 31.412993)
		(width 0.254)
		(layer "B.Cu")
		(net "GND")
	)
	(segment
		(start 51.237007 13.042138)
		(end 51.237007 13.042011)
		(width 0.254)
		(layer "B.Cu")
		(net "GND")
	)
	(segment
		(start 16.0274 25.3619)
		(end 15.3924 24.7269)
		(width 0.254)
		(layer "B.Cu")
		(net "GND")
	)
	(segment
		(start 59.73699 17.542002)
		(end 60.236862 17.04213)
		(width 0.254)
		(layer "B.Cu")
		(net "GND")
	)
	(segment
		(start 83.850988 7.898994)
		(end 84.250987 8.298993)
		(width 0.254)
		(layer "B.Cu")
		(net "GND")
	)
	(segment
		(start 13.4874 10.1219)
		(end 12.8524 9.4869)
		(width 0.254)
		(layer "B.Cu")
		(net "GND")
	)
	(segment
		(start 14.7574 3.7719)
		(end 14.1224 3.1369)
		(width 0.254)
		(layer "B.Cu")
		(net "GND")
	)
	(segment
		(start 28.702 18.5039)
		(end 28.5369 18.669)
		(width 0.254)
		(layer "B.Cu")
		(net "GND")
	)
	(segment
		(start 63.737007 5.542001)
		(end 63.1571 6.121908)
		(width 0.254)
		(layer "B.Cu")
		(net "GND")
	)
	(segment
		(start 80.650994 19.455994)
		(end 81.050994 19.855993)
		(width 0.254)
		(layer "B.Cu")
		(net "GND")
	)
	(segment
		(start 58.236993 30.042002)
		(end 58.236993 30.042104)
		(width 0.254)
		(layer "B.Cu")
		(net "GND")
	)
	(segment
		(start 5.334 12.4079)
		(end 5.334 11.176)
		(width 0.2032)
		(layer "B.Cu")
		(net "GND")
	)
	(segment
		(start 9.6774 22.8219)
		(end 9.0424 22.1869)
		(width 0.254)
		(layer "B.Cu")
		(net "GND")
	)
	(segment
		(start 59.236864 12.04214)
		(end 59.236991 12.04214)
		(width 0.254)
		(layer "B.Cu")
		(net "GND")
	)
	(segment
		(start 72.65101 24.613006)
		(end 72.251011 24.213007)
		(width 0.254)
		(layer "B.Cu")
		(net "GND")
	)
	(segment
		(start 83.566 41.656)
		(end 83.0199 41.1099)
		(width 0.2032)
		(layer "B.Cu")
		(net "GND")
	)
	(segment
		(start 50.471908 44.297651)
		(end 50.471908 43.5864)
		(width 0.254)
		(layer "B.Cu")
		(net "GND")
	)
	(segment
		(start 46.982609 34.787611)
		(end 46.736991 34.541993)
		(width 0.254)
		(layer "B.Cu")
		(net "GND")
	)
	(segment
		(start 59.236991 7.041998)
		(end 59.236991 7.041896)
		(width 0.254)
		(layer "B.Cu")
		(net "GND")
	)
	(segment
		(start 82.250991 24.613006)
		(end 82.65099 24.213007)
		(width 0.254)
		(layer "B.Cu")
		(net "GND")
	)
	(segment
		(start 52.737004 8.541995)
		(end 52.237132 9.041867)
		(width 0.254)
		(layer "B.Cu")
		(net "GND")
	)
	(segment
		(start 67.067989 44.297651)
		(end 67.067989 43.5864)
		(width 0.254)
		(layer "B.Cu")
		(net "GND")
	)
	(segment
		(start 70.068008 43.5864)
		(end 70.512559 43.5864)
		(width 0.254)
		(layer "B.Cu")
		(net "GND")
	)
	(segment
		(start 20.32 12.446)
		(end 20.066 12.192)
		(width 0.2032)
		(layer "B.Cu")
		(net "GND")
	)
	(segment
		(start 78.250999 30.212995)
		(end 78.650998 30.612994)
		(width 0.254)
		(layer "B.Cu")
		(net "GND")
	)
	(segment
		(start 27.432 30.9499)
		(end 27.9019 30.48)
		(width 0.254)
		(layer "B.Cu")
		(net "GND")
	)
	(segment
		(start 14.7574 22.8219)
		(end 14.1224 22.1869)
		(width 0.254)
		(layer "B.Cu")
		(net "GND")
	)
	(segment
		(start 51.1683 42.890008)
		(end 51.879551 42.890008)
		(width 0.254)
		(layer "B.Cu")
		(net "GND")
	)
	(segment
		(start 56.236997 10.042144)
		(end 56.236997 10.041992)
		(width 0.254)
		(layer "B.Cu")
		(net "GND")
	)
	(segment
		(start 56.736996 27.542007)
		(end 56.236997 28.042006)
		(width 0.254)
		(layer "B.Cu")
		(net "GND")
	)
	(segment
		(start 82.250991 7.898994)
		(end 82.65099 8.298993)
		(width 0.254)
		(layer "B.Cu")
		(net "GND")
	)
	(segment
		(start 48.737012 2.542007)
		(end 48.768 2.572995)
		(width 0.508)
		(layer "B.Cu")
		(net "GND")
	)
	(segment
		(start 72.65101 7.898994)
		(end 72.251011 8.298993)
		(width 0.254)
		(layer "B.Cu")
		(net "GND")
	)
	(segment
		(start 26.8859 21.8059)
		(end 26.416 21.336)
		(width 0.14732)
		(layer "B.Cu")
		(net "GND")
	)
	(segment
		(start 49.73701 25.542011)
		(end 49.237011 25.042012)
		(width 0.254)
		(layer "B.Cu")
		(net "GND")
	)
	(segment
		(start 56.236972 11.042015)
		(end 56.736996 10.541991)
		(width 0.254)
		(layer "B.Cu")
		(net "GND")
	)
	(segment
		(start 44.236996 22.041993)
		(end 43.736997 21.541994)
		(width 0.254)
		(layer "B.Cu")
		(net "GND")
	)
	(segment
		(start 45.736993 19.541998)
		(end 45.237146 19.042151)
		(width 0.254)
		(layer "B.Cu")
		(net "GND")
	)
	(segment
		(start 83.850988 19.455994)
		(end 84.250987 19.855993)
		(width 0.254)
		(layer "B.Cu")
		(net "GND")
	)
	(segment
		(start 76.651002 19.455994)
		(end 76.251003 19.855993)
		(width 0.254)
		(layer "B.Cu")
		(net "GND")
	)
	(segment
		(start 83.0199 41.1099)
		(end 82.931 41.1607)
		(width 0.2032)
		(layer "B.Cu")
		(net "GND")
	)
	(segment
		(start 21.971 32.893)
		(end 22.3139 32.5501)
		(width 0.2032)
		(layer "B.Cu")
		(net "GND")
	)
	(segment
		(start 9.6774 5.0419)
		(end 9.0424 5.6769)
		(width 0.254)
		(layer "B.Cu")
		(net "GND")
	)
	(segment
		(start 47.736989 10.541991)
		(end 47.237015 11.041964)
		(width 0.254)
		(layer "B.Cu")
		(net "GND")
	)
	(segment
		(start 81.8134 42.5069)
		(end 81.8134 42.3164)
		(width 0.2032)
		(layer "B.Cu")
		(net "GND")
	)
	(segment
		(start 76.651002 1.499006)
		(end 76.251003 1.099007)
		(width 0.254)
		(layer "B.Cu")
		(net "GND")
	)
	(segment
		(start 60.563887 19.368897)
		(end 60.563887 19.177)
		(width 0.254)
		(layer "B.Cu")
		(net "GND")
	)
	(segment
		(start 44.237148 23.041991)
		(end 44.237148 23.041839)
		(width 0.254)
		(layer "B.Cu")
		(net "GND")
	)
	(segment
		(start 10.9474 16.4719)
		(end 10.3124 15.8369)
		(width 0.254)
		(layer "B.Cu")
		(net "GND")
	)
	(segment
		(start 5.715 17.4371)
		(end 5.715 16.256)
		(width 0.254)
		(layer "B.Cu")
		(net "GND")
	)
	(segment
		(start 40.64 29.2481)
		(end 40.030908 29.2481)
		(width 0.254)
		(layer "B.Cu")
		(net "GND")
	)
	(segment
		(start 61.237114 10.04189)
		(end 61.236987 10.04189)
		(width 0.254)
		(layer "B.Cu")
		(net "GND")
	)
	(segment
		(start 56.736996 7.541997)
		(end 57.23697 7.042023)
		(width 0.254)
		(layer "B.Cu")
		(net "GND")
	)
	(segment
		(start 49.237011 25.042012)
		(end 49.237011 25.04186)
		(width 0.254)
		(layer "B.Cu")
		(net "GND")
	)
	(segment
		(start 47.471889 44.297651)
		(end 47.471889 43.5864)
		(width 0.254)
		(layer "B.Cu")
		(net "GND")
	)
	(segment
		(start 80.650994 31.012994)
		(end 81.050994 31.412993)
		(width 0.254)
		(layer "B.Cu")
		(net "GND")
	)
	(segment
		(start 83.566 42.5069)
		(end 83.566 41.656)
		(width 0.2032)
		(layer "B.Cu")
		(net "GND")
	)
	(segment
		(start 50.237009 32.041998)
		(end 50.237009 32.0421)
		(width 0.254)
		(layer "B.Cu")
		(net "GND")
	)
	(segment
		(start 51.1683 41.390011)
		(end 51.879551 41.390011)
		(width 0.254)
		(layer "B.Cu")
		(net "GND")
	)
	(segment
		(start 17.2974 3.7719)
		(end 16.6624 3.1369)
		(width 0.254)
		(layer "B.Cu")
		(net "GND")
	)
	(segment
		(start 57.236868 14.042136)
		(end 57.236995 14.042136)
		(width 0.254)
		(layer "B.Cu")
		(net "GND")
	)
	(segment
		(start 13.4874 15.2019)
		(end 12.8524 14.5669)
		(width 0.254)
		(layer "B.Cu")
		(net "GND")
	)
	(segment
		(start 71.851012 7.898994)
		(end 72.251011 8.298993)
		(width 0.254)
		(layer "B.Cu")
		(net "GND")
	)
	(segment
		(start 44.736995 8.541995)
		(end 45.236892 9.041892)
		(width 0.254)
		(layer "B.Cu")
		(net "GND")
	)
	(segment
		(start 64.8716 39.889989)
		(end 65.735911 39.889989)
		(width 0.254)
		(layer "B.Cu")
		(net "GND")
	)
	(segment
		(start 45.236892 9.041892)
		(end 45.237019 9.041892)
		(width 0.254)
		(layer "B.Cu")
		(net "GND")
	)
	(segment
		(start 16.0274 10.1219)
		(end 15.3924 9.4869)
		(width 0.254)
		(layer "B.Cu")
		(net "GND")
	)
	(segment
		(start 46.236992 17.042003)
		(end 46.237144 17.042003)
		(width 0.254)
		(layer "B.Cu")
		(net "GND")
	)
	(segment
		(start 75.051006 25.413005)
		(end 74.651006 25.013006)
		(width 0.254)
		(layer "B.Cu")
		(net "GND")
	)
	(segment
		(start 49.581791 6.542024)
		(end 49.664112 7.469099)
		(width 0.508)
		(layer "B.Cu")
		(net "GND")
	)
	(segment
		(start 4.23418 10.41908)
		(end 4.259656 10.41908)
		(width 0.2032)
		(layer "B.Cu")
		(net "GND")
	)
	(segment
		(start 82.250991 19.455994)
		(end 82.65099 19.855993)
		(width 0.254)
		(layer "B.Cu")
		(net "GND")
	)
	(segment
		(start 27.432 26.67)
		(end 27.432 25.146)
		(width 0.2032)
		(layer "B.Cu")
		(net "GND")
	)
	(segment
		(start 47.0789 34.950806)
		(end 46.982609 34.854515)
		(width 0.254)
		(layer "B.Cu")
		(net "GND")
	)
	(segment
		(start 72.65101 31.012994)
		(end 72.251011 31.412993)
		(width 0.254)
		(layer "B.Cu")
		(net "GND")
	)
	(segment
		(start 47.9552 18.542)
		(end 47.736989 18.722111)
		(width 0.254)
		(layer "B.Cu")
		(net "GND")
	)
	(segment
		(start 17.2974 8.8519)
		(end 16.6624 8.2169)
		(width 0.254)
		(layer "B.Cu")
		(net "GND")
	)
	(segment
		(start 72.65101 1.499006)
		(end 72.251011 1.099007)
		(width 0.254)
		(layer "B.Cu")
		(net "GND")
	)
	(segment
		(start 60.736988 19.541998)
		(end 60.563887 19.368897)
		(width 0.254)
		(layer "B.Cu")
		(net "GND")
	)
	(segment
		(start 51.237007 13.042011)
		(end 51.737006 12.542012)
		(width 0.254)
		(layer "B.Cu")
		(net "GND")
	)
	(segment
		(start 75.851004 19.455994)
		(end 75.451005 19.855993)
		(width 0.254)
		(layer "B.Cu")
		(net "GND")
	)
	(segment
		(start 54.284093 27.542007)
		(end 54.737 27.0891)
		(width 0.254)
		(layer "B.Cu")
		(net "GND")
	)
	(segment
		(start 71.851012 19.455994)
		(end 72.251011 19.855993)
		(width 0.254)
		(layer "B.Cu")
		(net "GND")
	)
	(segment
		(start 45.736993 12.542012)
		(end 45.236994 12.042013)
		(width 0.254)
		(layer "B.Cu")
		(net "GND")
	)
	(segment
		(start 17.2974 17.7419)
		(end 17.9324 17.1069)
		(width 0.254)
		(layer "B.Cu")
		(net "GND")
	)
	(segment
		(start 60.236989 7.041998)
		(end 60.236989 7.041896)
		(width 0.254)
		(layer "B.Cu")
		(net "GND")
	)
	(segment
		(start 81.8134 42.3164)
		(end 82.1182 42.0116)
		(width 0.2032)
		(layer "B.Cu")
		(net "GND")
	)
	(segment
		(start 42.237025 7.041972)
		(end 41.737001 7.541997)
		(width 0.254)
		(layer "B.Cu")
		(net "GND")
	)
	(segment
		(start 55.41391 24.2189)
		(end 55.736998 24.541988)
		(width 0.254)
		(layer "B.Cu")
		(net "GND")
	)
	(segment
		(start 30.7721 27.686)
		(end 30.7721 27.2669)
		(width 0.254)
		(layer "B.Cu")
		(net "GND")
	)
	(segment
		(start 82.931 41.1607)
		(end 82.1817 41.1099)
		(width 0.2032)
		(layer "B.Cu")
		(net "GND")
	)
	(segment
		(start 28.6131 23.5712)
		(end 27.813 22.7711)
		(width 0.2032)
		(layer "B.Cu")
		(net "GND")
	)
	(segment
		(start 24.511 19.685)
		(end 24.511 21.336)
		(width 0.508)
		(layer "B.Cu")
		(net "GND")
	)
	(segment
		(start 39.237107 25.042114)
		(end 39.237031 25.042114)
		(width 0.254)
		(layer "B.Cu")
		(net "GND")
	)
	(segment
		(start 75.051006 30.212995)
		(end 74.651006 30.612994)
		(width 0.254)
		(layer "B.Cu")
		(net "GND")
	)
	(segment
		(start 61.23686 22.041866)
		(end 61.23686 22.041993)
		(width 0.254)
		(layer "B.Cu")
		(net "GND")
	)
	(segment
		(start 70.7644 42.390009)
		(end 71.475651 42.390009)
		(width 0.254)
		(layer "B.Cu")
		(net "GND")
	)
	(segment
		(start 4.9149 10.7569)
		(end 5.334 11.176)
		(width 0.2032)
		(layer "B.Cu")
		(net "GND")
	)
	(segment
		(start 26.8859 20.1168)
		(end 26.924 20.1041)
		(width 0.254)
		(layer "B.Cu")
		(net "GND")
	)
	(zone
		(layer "F.Cu")
		(hatch none 0.5)
		(connect_pads
			(clearance 0.5)
		)
		(min_thickness 0.25)
		(fill
			(thermal_gap 0.5)
			(thermal_bridge_width 0.5)
			(island_removal_mode 0)
		)
		(polygon
			(pts
				(xy 17.653 41.91) (xy 17.653 44.958) (xy 18.288 45.593) (xy 18.288 46.228) (xy 17.653 46.228) (xy 14.732 46.228)
				(xy 14.732 43.053) (xy 16.383 43.053) (xy 16.637 42.799) (xy 16.637 41.91)
			)
		)
	)
	(zone
		(layer "F.Cu")
		(hatch none 0.5)
		(connect_pads
			(clearance 0.5)
		)
		(min_thickness 0.25)
		(fill
			(thermal_gap 0.5)
			(thermal_bridge_width 0.5)
			(island_removal_mode 0)
		)
		(polygon
			(pts
				(xy 15.97406 39.541856) (xy 16.889298 39.541856) (xy 16.889298 39.170204) (xy 15.97406 39.170204)
			)
		)
	)
	(zone
		(net "DDR_VTT")
		(layer "F.Cu")
		(hatch none 0.5)
		(connect_pads
			(clearance 0.5)
		)
		(min_thickness 0.25)
		(fill yes
			(thermal_gap 0.5)
			(thermal_bridge_width 0.5)
			(island_removal_mode 0)
		)
		(polygon
			(pts
				(xy 78.1812 22.733) (xy 78.1812 21.209) (xy 86.995 21.209) (xy 86.995 43.18) (xy 86.106 43.18) (xy 86.106 34.036)
				(xy 82.296 34.036) (xy 82.296 35.433) (xy 82.042 35.433) (xy 82.042 34.036) (xy 78.105 34.036) (xy 78.105 32.893)
				(xy 78.359 32.893) (xy 78.359 33.401) (xy 79.121 33.401) (xy 79.121 32.893) (xy 79.375 32.893) (xy 79.375 33.401)
				(xy 82.677 33.401) (xy 82.677 32.893) (xy 82.931 32.893) (xy 82.931 33.401) (xy 83.566 33.401) (xy 83.566 32.893)
				(xy 83.82 32.893) (xy 83.82 33.401) (xy 84.455 33.401) (xy 84.455 32.893) (xy 84.709 32.893) (xy 84.709 33.401)
				(xy 86.106 33.401) (xy 86.106 28.321) (xy 85.344 28.321) (xy 84.963 27.94) (xy 84.709 27.94) (xy 84.709 28.448)
				(xy 84.455 28.448) (xy 84.455 27.94) (xy 83.82 27.94) (xy 83.82 28.448) (xy 83.566 28.448) (xy 83.566 27.94)
				(xy 82.931 27.94) (xy 82.931 28.448) (xy 82.677 28.448) (xy 82.677 27.94) (xy 82.042 27.94) (xy 82.042 28.448)
				(xy 81.788 28.448) (xy 81.788 27.94) (xy 81.153 27.94) (xy 81.153 28.448) (xy 80.899 28.448) (xy 80.899 27.94)
				(xy 80.264 27.94) (xy 80.264 28.448) (xy 80.01 28.448) (xy 80.01 27.94) (xy 79.375 27.94) (xy 79.375 28.448)
				(xy 78.994 28.448) (xy 78.994 27.94) (xy 78.994 27.813) (xy 77.343 27.813) (xy 77.343 27.178) (xy 78.994 27.178)
				(xy 79.375 27.178) (xy 79.375 27.686) (xy 80.01 27.686) (xy 80.01 27.178) (xy 80.264 27.178) (xy 80.264 27.686)
				(xy 80.899 27.686) (xy 80.899 27.178) (xy 81.153 27.178) (xy 81.153 27.686) (xy 81.788 27.686) (xy 81.788 27.178)
				(xy 82.042 27.178) (xy 82.042 27.686) (xy 82.677 27.686) (xy 82.677 27.178) (xy 82.931 27.178) (xy 82.931 27.686)
				(xy 83.566 27.686) (xy 83.566 27.178) (xy 83.82 27.178) (xy 83.82 27.686) (xy 84.455 27.686) (xy 84.455 27.178)
				(xy 84.709 27.178) (xy 84.709 27.686) (xy 84.963 27.686) (xy 85.344 27.305) (xy 86.106 27.305) (xy 86.106 21.844)
				(xy 84.7598 21.844) (xy 84.7598 22.606) (xy 84.328 22.606) (xy 84.51469 22.5679) (xy 84.5058 21.844)
				(xy 83.8708 21.844) (xy 83.8708 22.733) (xy 83.439 22.733) (xy 83.6168 22.689287) (xy 83.6168 21.844)
				(xy 82.8548 21.844) (xy 82.8548 22.733) (xy 82.6008 22.733) (xy 82.6008 21.844) (xy 81.153 21.844)
				(xy 81.153 22.606) (xy 80.899 22.606) (xy 80.899 21.844) (xy 80.2132 21.844) (xy 80.2132 22.733)
				(xy 79.9592 22.733) (xy 79.9592 21.844) (xy 79.3242 21.844) (xy 79.3242 22.733) (xy 79.0702 22.733)
				(xy 79.0702 21.844) (xy 78.4352 21.844) (xy 78.4352 22.733)
			)
		)
	)
	(zone
		(layer "F.Cu")
		(hatch none 0.5)
		(connect_pads
			(clearance 0.5)
		)
		(min_thickness 0.25)
		(fill
			(thermal_gap 0.5)
			(thermal_bridge_width 0.5)
			(island_removal_mode 0)
		)
		(polygon
			(pts
				(xy 9.398 41.783) (xy 9.398 45.339) (xy 7.112 45.339) (xy 7.112 41.783)
			)
		)
	)
	(zone
		(layer "F.Cu")
		(hatch none 0.5)
		(connect_pads
			(clearance 0.5)
		)
		(min_thickness 0.25)
		(fill
			(thermal_gap 0.5)
			(thermal_bridge_width 0.5)
			(island_removal_mode 0)
		)
		(polygon
			(pts
				(xy 17.78 38.1) (xy 17.78 38.608) (xy 18.923 39.751) (xy 20.828 39.751) (xy 20.828 41.656) (xy 20.193 41.656)
				(xy 20.193 43.815) (xy 20.447 44.069) (xy 20.828 44.069) (xy 21.717 44.069) (xy 21.717 38.608) (xy 20.066 38.608)
				(xy 19.558 38.1)
			)
		)
	)
	(zone
		(layer "F.Cu")
		(hatch none 0.5)
		(connect_pads
			(clearance 0.5)
		)
		(min_thickness 0.25)
		(fill
			(thermal_gap 0.5)
			(thermal_bridge_width 0.5)
			(island_removal_mode 0)
		)
		(polygon
			(pts
				(xy 17.653 41.275) (xy 17.653 40.513) (xy 16.891 39.751) (xy 16.383 39.751) (xy 16.383 41.275)
			)
		)
	)
	(zone
		(net "DDR_VTT")
		(layer "F.Cu")
		(hatch none 0.5)
		(connect_pads
			(clearance 0.5)
		)
		(min_thickness 0.25)
		(fill yes
			(thermal_gap 0.5)
			(thermal_bridge_width 0.5)
			(island_removal_mode 0)
		)
		(polygon
			(pts
				(xy 78.867 41.275) (xy 79.375 41.783) (xy 79.375 42.164) (xy 79.121 42.418) (xy 79.121 43.307) (xy 75.565 43.307)
				(xy 75.565 41.656) (xy 75.946 41.275)
			)
		)
	)
	(zone
		(net "VDD_5.0V")
		(layer "F.Cu")
		(hatch none 0.5)
		(connect_pads
			(clearance 0.5)
		)
		(min_thickness 0.25)
		(fill yes
			(thermal_gap 0.5)
			(thermal_bridge_width 0.5)
			(island_removal_mode 0)
		)
		(polygon
			(pts
				(xy 58.42 48.006) (xy 58.42 55.118) (xy 56.007 55.118) (xy 56.007 48.006)
			)
		)
	)
	(zone
		(layer "F.Cu")
		(hatch none 0.5)
		(connect_pads
			(clearance 0.5)
		)
		(min_thickness 0.25)
		(fill
			(thermal_gap 0.5)
			(thermal_bridge_width 0.5)
			(island_removal_mode 0)
		)
		(polygon
			(pts
				(xy 15.24 32.766) (xy 16.764 32.766) (xy 16.764 30.353) (xy 15.24 30.353)
			)
		)
	)
	(zone
		(layer "F.Cu")
		(hatch none 0.5)
		(connect_pads
			(clearance 0)
		)
		(min_thickness 0.25)
		(keepout
			(tracks not_allowed)
			(vias allowed)
			(pads allowed)
			(copperpour not_allowed)
			(footprints allowed)
		)
		(placement
			(enabled no)
			(sheetname "")
		)
		(fill
			(thermal_gap 0.5)
			(thermal_bridge_width 0.5)
			(island_removal_mode 0)
		)
		(polygon
			(pts
				(arc
					(start 33.264729 9.577019)
					(mid 29.469596 11.089325)
					(end 27.887219 14.855774)
				)
				(arc
					(start 27.887219 14.855774)
					(mid 29.506522 18.563936)
					(end 33.260767 20.073315)
				)
				(arc
					(start 33.260767 20.073315)
					(mid 36.879454 18.503284)
					(end 38.384937 14.857273)
				)
				(arc
					(start 38.384937 14.857273)
					(mid 36.9209 11.182579)
					(end 33.306664 9.575063)
				)
				(xy 33.306868 9.575267)
				(arc
					(start 33.306868 9.831756)
					(mid 36.745382 11.365957)
					(end 38.151333 14.858873)
				)
				(arc
					(start 38.151333 14.858873)
					(mid 36.717658 18.329269)
					(end 33.277023 19.832955)
				)
				(arc
					(start 33.277023 19.832955)
					(mid 29.670469 18.418975)
					(end 28.143175 14.858924)
				)
				(arc
					(start 28.143175 14.858924)
					(mid 29.643715 11.265699)
					(end 33.2629 9.828886)
				)
				(xy 33.2629 9.577019)
			)
		)
	)
	(zone
		(layer "F.Cu")
		(hatch none 0.5)
		(connect_pads
			(clearance 0.5)
		)
		(min_thickness 0.25)
		(fill
			(thermal_gap 0.5)
			(thermal_bridge_width 0.5)
			(island_removal_mode 0)
		)
		(polygon
			(pts
				(xy 11.303 36.068) (xy 11.303 35.814) (xy 10.16 34.671) (xy 9.144 34.671) (xy 9.144 32.893) (xy 5.842 32.893)
				(xy 5.842 36.068)
			)
		)
	)
	(zone
		(net "EXT_12.0V")
		(layer "F.Cu")
		(hatch none 0.5)
		(connect_pads
			(clearance 0.5)
		)
		(min_thickness 0.25)
		(fill yes
			(thermal_gap 0.5)
			(thermal_bridge_width 0.5)
			(island_removal_mode 0)
		)
		(polygon
			(pts
				(xy 5.588 14.224) (xy -1.651 14.224) (xy -1.651 27.178) (xy 1.651 30.48) (xy 5.461 30.48) (xy 5.588 30.353)
				(xy 5.588 26.797) (xy 5.461 26.67) (xy 3.429 26.67) (xy 0.254 23.495) (xy 0.254 15.621) (xy 5.588 15.621)
			)
		)
	)
	(zone
		(net "GND")
		(layer "F.Cu")
		(hatch none 0.5)
		(connect_pads
			(clearance 0.5)
		)
		(min_thickness 0.25)
		(fill yes
			(thermal_gap 0.5)
			(thermal_bridge_width 0.5)
			(island_removal_mode 0)
		)
		(polygon
			(pts
				(xy 38.735 45.72) (xy 48.895 45.72) (xy 49.022 45.593) (xy 49.022 44.45) (xy 48.768 44.196) (xy 38.735 44.196)
			)
		)
	)
	(zone
		(layer "F.Cu")
		(hatch none 0.5)
		(connect_pads
			(clearance 0.5)
		)
		(min_thickness 0.25)
		(fill
			(thermal_gap 0.5)
			(thermal_bridge_width 0.5)
			(island_removal_mode 0)
		)
		(polygon
			(pts
				(xy 16.764 34.671) (xy 17.399 34.671) (xy 17.399 34.417) (xy 17.907 33.909) (xy 18.669 33.909) (xy 18.669 33.02)
				(xy 16.637 33.02) (xy 16.637 34.036) (xy 16.764 34.163)
			)
		)
	)
	(zone
		(layer "F.Cu")
		(hatch none 0.5)
		(connect_pads
			(clearance 0.5)
		)
		(min_thickness 0.25)
		(fill
			(thermal_gap 0.5)
			(thermal_bridge_width 0.5)
			(island_removal_mode 0)
		)
		(polygon
			(pts
				(xy 12.973431 39.560475) (xy 12.117121 39.560475) (xy 12.117121 39.151331) (xy 12.973431 39.151331)
			)
		)
	)
	(zone
		(layer "F.Cu")
		(hatch none 0.5)
		(connect_pads
			(clearance 0.5)
		)
		(min_thickness 0.25)
		(fill
			(thermal_gap 0.5)
			(thermal_bridge_width 0.5)
			(island_removal_mode 0)
		)
		(polygon
			(pts
				(xy 13.462 34.417) (xy 13.462 32.004) (xy 13.335 31.877) (xy 12.446 31.877) (xy 12.319 32.004) (xy 12.319 34.036)
				(xy 12.7 34.417)
			)
		)
	)
	(zone
		(layer "F.Cu")
		(hatch none 0.5)
		(connect_pads
			(clearance 0.5)
		)
		(min_thickness 0.25)
		(fill
			(thermal_gap 0.5)
			(thermal_bridge_width 0.5)
			(island_removal_mode 0)
		)
		(polygon
			(pts
				(xy 53.975 55.372) (xy 53.975 45.085) (xy 54.61 45.085) (xy 54.61 37.719) (xy 62.865 37.719) (xy 62.865 45.339)
				(xy 58.928 45.339) (xy 58.928 46.355) (xy 55.499 46.355) (xy 55.499 55.372)
			)
		)
	)
	(zone
		(net "GND")
		(layer "F.Cu")
		(hatch none 0.5)
		(connect_pads
			(clearance 0.5)
		)
		(min_thickness 0.25)
		(fill yes
			(thermal_gap 0.5)
			(thermal_bridge_width 0.5)
			(island_removal_mode 0)
		)
		(polygon
			(pts
				(xy 50.419 46.228) (xy 50.419 55.245) (xy 52.324 55.245) (xy 52.324 46.228)
			)
		)
	)
	(zone
		(net "11N1952")
		(layer "F.Cu")
		(hatch none 0.5)
		(connect_pads
			(clearance 0.5)
		)
		(min_thickness 0.25)
		(fill yes
			(thermal_gap 0.5)
			(thermal_bridge_width 0.5)
			(island_removal_mode 0)
		)
		(polygon
			(pts
				(xy 62.865 51.435) (xy 59.436 51.435) (xy 59.436 50.165) (xy 58.674 50.165) (xy 58.674 49.53) (xy 59.436 49.53)
				(xy 59.436 48.006) (xy 61.087 48.006) (xy 61.214 48.133) (xy 62.865 48.133) (xy 62.865 48.641) (xy 62.357 48.641)
				(xy 62.357 49.149) (xy 61.722 49.149) (xy 61.722 50.419) (xy 62.357 50.419) (xy 62.357 50.927) (xy 62.865 50.927)
			)
		)
	)
	(zone
		(net "11N2253")
		(layer "F.Cu")
		(hatch none 0.5)
		(connect_pads
			(clearance 0.5)
		)
		(min_thickness 0.25)
		(fill yes
			(thermal_gap 0.5)
			(thermal_bridge_width 0.5)
			(island_removal_mode 0)
		)
		(polygon
			(pts
				(xy 83.693 46.355) (xy 80.391 46.355) (xy 80.391 47.117) (xy 79.502 47.117) (xy 79.502 48.006) (xy 77.978 48.006)
				(xy 77.978 45.339) (xy 79.375 45.339) (xy 79.502 45.212) (xy 79.502 44.577) (xy 83.693 44.577)
			)
		)
	)
	(zone
		(layer "F.Cu")
		(hatch none 0.5)
		(connect_pads
			(clearance 0.5)
		)
		(min_thickness 0.25)
		(fill
			(thermal_gap 0.5)
			(thermal_bridge_width 0.5)
			(island_removal_mode 0)
		)
		(polygon
			(pts
				(xy 12.965659 35.271354) (xy 12.445644 35.271354) (xy 12.445644 34.865818) (xy 12.965659 34.865818)
			)
		)
	)
	(zone
		(layer "F.Cu")
		(hatch none 0.5)
		(connect_pads
			(clearance 0.5)
		)
		(min_thickness 0.25)
		(fill
			(thermal_gap 0.5)
			(thermal_bridge_width 0.5)
			(island_removal_mode 0)
		)
		(polygon
			(pts
				(xy 14.224 40.005) (xy 14.224 41.529) (xy 13.716 42.037) (xy 13.715975 42.036975) (xy 12.954 42.036975)
				(xy 12.954 41.021) (xy 13.716 40.259) (xy 13.716 40.005)
			)
		)
	)
	(zone
		(net "EXT_12.0V")
		(layer "F.Cu")
		(hatch none 0.5)
		(connect_pads
			(clearance 0.5)
		)
		(min_thickness 0.25)
		(fill yes
			(thermal_gap 0.5)
			(thermal_bridge_width 0.5)
			(island_removal_mode 0)
		)
		(polygon
			(pts
				(xy 83.058 48.768) (xy 81.026 48.768) (xy 81.026 51.562) (xy 80.137 52.451) (xy 78.613 52.451) (xy 78.613 53.975)
				(xy 78.613 55.499) (xy 81.153 55.499) (xy 84.328 52.324) (xy 87.122 52.324) (xy 87.122 50.927) (xy 83.693 50.927)
				(xy 83.693 50.165) (xy 83.058 50.165)
			)
		)
	)
	(zone
		(net "DDR_VDDQ")
		(layer "F.Cu")
		(hatch none 0.5)
		(connect_pads
			(clearance 0.5)
		)
		(min_thickness 0.25)
		(fill yes
			(thermal_gap 0.5)
			(thermal_bridge_width 0.5)
			(island_removal_mode 0)
		)
		(polygon
			(pts
				(xy 75.946 52.07) (xy 75.946 48.641) (xy 74.422 47.117) (xy 74.422 45.847) (xy 76.708 45.847) (xy 76.708 47.371)
				(xy 77.343 48.006) (xy 77.343 50.419) (xy 78.105 50.419) (xy 78.105 52.07) (xy 77.343 52.07)
			)
		)
	)
	(zone
		(net "EXT_12.0V")
		(layer "F.Cu")
		(hatch none 0.5)
		(connect_pads
			(clearance 0.5)
		)
		(min_thickness 0.25)
		(fill yes
			(thermal_gap 0.5)
			(thermal_bridge_width 0.5)
			(island_removal_mode 0)
		)
		(polygon
			(pts
				(xy 63.881 50.927) (xy 63.881 51.816) (xy 64.262 51.816) (xy 64.262 52.324) (xy 63.754 52.324) (xy 63.754 55.499)
				(xy 61.468 55.499) (xy 61.468 51.689) (xy 63.119 51.689) (xy 63.119 50.927)
			)
		)
	)
	(zone
		(layer "F.Cu")
		(hatch none 0.5)
		(connect_pads
			(clearance 0.5)
		)
		(min_thickness 0.25)
		(fill
			(thermal_gap 0.5)
			(thermal_bridge_width 0.5)
			(island_removal_mode 0)
		)
		(polygon
			(pts
				(xy 12.153544 37.301856) (xy 13.58138 37.301856) (xy 13.58138 38.105766) (xy 13.585419 38.109804)
				(xy 15.340254 38.109804) (xy 15.360472 38.089586) (xy 15.360472 37.301856) (xy 16.842689 37.301856)
				(xy 16.842689 37.12939) (xy 15.356434 37.12939) (xy 15.356434 36.322635) (xy 15.35237 36.318571)
				(xy 13.58138 36.318571) (xy 13.577341 36.32261) (xy 13.58138 36.326648) (xy 13.58138 37.12939) (xy 12.153544 37.12939)
			)
		)
	)
	(zone
		(layer "F.Cu")
		(hatch none 0.5)
		(connect_pads
			(clearance 0.5)
		)
		(min_thickness 0.25)
		(fill
			(thermal_gap 0.5)
			(thermal_bridge_width 0.5)
			(island_removal_mode 0)
		)
		(polygon
			(pts
				(xy 10.795 45.339) (xy 11.938 45.339) (xy 11.938 42.672) (xy 11.43 42.164) (xy 11.43 41.91) (xy 11.43 41.656)
				(xy 11.176 41.402) (xy 10.795 41.783)
			)
		)
	)
	(zone
		(layer "F.Cu")
		(hatch none 0.5)
		(connect_pads
			(clearance 0.5)
		)
		(min_thickness 0.25)
		(fill
			(thermal_gap 0.5)
			(thermal_bridge_width 0.5)
			(island_removal_mode 0)
		)
		(polygon
			(pts
				(xy 15.875 33.909) (xy 13.97 33.909) (xy 13.716 33.655) (xy 13.716 33.02) (xy 15.875 33.02)
			)
		)
	)
	(zone
		(layer "F.Cu")
		(hatch none 0.5)
		(connect_pads
			(clearance 0.5)
		)
		(min_thickness 0.25)
		(fill
			(thermal_gap 0.5)
			(thermal_bridge_width 0.5)
			(island_removal_mode 0)
		)
		(polygon
			(pts
				(xy 12.319 42.037) (xy 12.7 41.656) (xy 12.7 40.767) (xy 13.335 40.132) (xy 13.335 40.005) (xy 13.208 39.878)
				(xy 12.192 39.878) (xy 11.684 40.386) (xy 11.684 42.037)
			)
		)
	)
	(zone
		(layer "F.Cu")
		(hatch none 0.5)
		(connect_pads
			(clearance 0)
		)
		(min_thickness 0.25)
		(keepout
			(tracks not_allowed)
			(vias allowed)
			(pads allowed)
			(copperpour not_allowed)
			(footprints allowed)
		)
		(placement
			(enabled no)
			(sheetname "")
		)
		(fill
			(thermal_gap 0.5)
			(thermal_bridge_width 0.5)
			(island_removal_mode 0)
		)
		(polygon
			(pts
				(arc
					(start 73.342449 46.289747)
					(mid 72.140602 45.771481)
					(end 70.847864 45.566863)
				)
				(xy 70.848068 45.567067)
				(arc
					(start 70.848068 45.823556)
					(mid 72.040823 46.011076)
					(end 73.154362 46.477834)
				)
			)
		)
	)
	(zone
		(layer "F.Cu")
		(hatch none 0.5)
		(connect_pads
			(clearance 0)
		)
		(min_thickness 0.25)
		(keepout
			(tracks allowed)
			(vias allowed)
			(pads allowed)
			(copperpour allowed)
			(footprints not_allowed)
		)
		(placement
			(enabled no)
			(sheetname "")
		)
		(fill
			(thermal_gap 0.5)
			(thermal_bridge_width 0.5)
			(island_removal_mode 0)
		)
		(polygon
			(pts
				(xy 72.771 -3.175) (xy 72.771 3.175) (xy 72.898 3.302) (xy 81.661 3.302) (xy 81.788 3.429) (xy 81.788 21.336)
				(xy 85.344 21.336) (xy 85.344 22.225) (xy 88.138 22.225) (xy 88.138 -3.048) (xy 88.011 -3.175)
			)
		)
	)
	(zone
		(layer "F.Cu")
		(hatch none 0.5)
		(connect_pads
			(clearance 0)
		)
		(min_thickness 0.25)
		(keepout
			(tracks not_allowed)
			(vias allowed)
			(pads allowed)
			(copperpour not_allowed)
			(footprints allowed)
		)
		(placement
			(enabled no)
			(sheetname "")
		)
		(fill
			(thermal_gap 0.5)
			(thermal_bridge_width 0.5)
			(island_removal_mode 0)
		)
		(polygon
			(pts
				(arc
					(start 70.805929 45.568819)
					(mid 67.010796 47.081125)
					(end 65.428419 50.847574)
				)
				(arc
					(start 65.428419 50.847574)
					(mid 67.047722 54.555736)
					(end 70.801967 56.065115)
				)
				(arc
					(start 70.801967 56.065115)
					(mid 74.420654 54.495084)
					(end 75.926137 50.849073)
				)
				(arc
					(start 75.926137 50.849073)
					(mid 75.395631 48.510895)
					(end 73.880142 46.652993)
				)
				(xy 73.861143 46.652993)
				(arc
					(start 73.686797 46.827338)
					(mid 75.164948 48.602064)
					(end 75.692533 50.850673)
				)
				(arc
					(start 75.692533 50.850673)
					(mid 74.258858 54.321069)
					(end 70.818223 55.824755)
				)
				(arc
					(start 70.818223 55.824755)
					(mid 67.211669 54.410775)
					(end 65.684375 50.850724)
				)
				(arc
					(start 65.684375 50.850724)
					(mid 67.184915 47.257499)
					(end 70.8041 45.820686)
				)
				(xy 70.8041 45.568819)
			)
		)
	)
	(zone
		(layer "F.Cu")
		(hatch none 0.5)
		(connect_pads
			(clearance 0.5)
		)
		(min_thickness 0.25)
		(fill
			(thermal_gap 0.5)
			(thermal_bridge_width 0.5)
			(island_removal_mode 0)
		)
		(polygon
			(pts
				(xy 17.272 35.814) (xy 17.907 35.179) (xy 17.907 34.544) (xy 19.05 34.544) (xy 19.05 32.766) (xy 17.526 32.766)
				(xy 17.526 30.353) (xy 19.558 30.353) (xy 19.939 30.734) (xy 19.939 35.306) (xy 18.923 36.322) (xy 17.78 36.322)
			)
		)
	)
	(zone
		(layer "F.Cu")
		(hatch none 0.5)
		(connect_pads
			(clearance 0.5)
		)
		(min_thickness 0.25)
		(fill
			(thermal_gap 0.5)
			(thermal_bridge_width 0.5)
			(island_removal_mode 0)
		)
		(polygon
			(pts
				(xy 15.113 40.513) (xy 15.113 42.672) (xy 16.002 42.672) (xy 16.002 40.513)
			)
		)
	)
	(zone
		(layer "F.Cu")
		(hatch none 0.5)
		(connect_pads
			(clearance 0.5)
		)
		(min_thickness 0.25)
		(fill
			(thermal_gap 0.5)
			(thermal_bridge_width 0.5)
			(island_removal_mode 0)
		)
		(polygon
			(pts
				(xy 10.922 39.116) (xy 10.922 41.275) (xy 9.652 41.275) (xy 9.398 41.021) (xy 8.636 41.021) (xy 8.636 39.878)
				(xy 9.906 39.878) (xy 10.668 39.116)
			)
		)
	)
	(zone
		(net "L_2_CORE_PHASE")
		(layer "F.Cu")
		(hatch none 0.5)
		(connect_pads
			(clearance 0.5)
		)
		(min_thickness 0.25)
		(fill yes
			(thermal_gap 0.5)
			(thermal_bridge_width 0.5)
			(island_removal_mode 0)
		)
		(polygon
			(pts
				(xy 50.419 42.672) (xy 50.419 41.91) (xy 49.53 41.91) (xy 49.53 41.148) (xy 50.419 41.148) (xy 50.419 40.386)
				(xy 46.101 40.386) (xy 46.101 42.672)
			)
		)
	)
	(zone
		(layer "F.Cu")
		(hatch none 0.5)
		(connect_pads
			(clearance 0.5)
		)
		(min_thickness 0.25)
		(fill
			(thermal_gap 0.5)
			(thermal_bridge_width 0.5)
			(island_removal_mode 0)
		)
		(polygon
			(pts
				(xy 14.351 45.339) (xy 12.319 45.339) (xy 12.319 43.688) (xy 12.319 42.799) (xy 12.636449 42.481551)
				(xy 13.525449 42.481551) (xy 14.605 41.402) (xy 14.605 42.418) (xy 14.351 42.672)
			)
		)
	)
	(zone
		(layer "F.Cu")
		(hatch none 0.5)
		(connect_pads
			(clearance 0.5)
		)
		(min_thickness 0.25)
		(fill
			(thermal_gap 0.5)
			(thermal_bridge_width 0.5)
			(island_removal_mode 0)
		)
		(polygon
			(pts
				(xy 11.684 33.02) (xy 12.065 33.02) (xy 12.065 31.369) (xy 5.842 31.369) (xy 5.842 32.385) (xy 11.049 32.385)
			)
		)
	)
	(zone
		(layer "F.Cu")
		(hatch none 0.5)
		(connect_pads
			(clearance 0.5)
		)
		(min_thickness 0.25)
		(fill
			(thermal_gap 0.5)
			(thermal_bridge_width 0.5)
			(island_removal_mode 0)
		)
		(polygon
			(pts
				(xy 18.415 40.513) (xy 18.415 41.275) (xy 20.574 41.275) (xy 20.574 40.513) (xy 20.066 40.513) (xy 19.685 40.132)
				(xy 18.796 40.132)
			)
		)
	)
	(zone
		(layer "F.Cu")
		(hatch none 0.5)
		(connect_pads
			(clearance 0.5)
		)
		(min_thickness 0.25)
		(fill
			(thermal_gap 0.5)
			(thermal_bridge_width 0.5)
			(island_removal_mode 0)
		)
		(polygon
			(pts
				(xy 11.43 33.02) (xy 11.43 34.671) (xy 11.049 35.052) (xy 10.922 35.052) (xy 9.906 34.036) (xy 9.398 34.036)
				(xy 9.398 33.02)
			)
		)
	)
	(zone
		(net "L_1_CORE_PHASE")
		(layer "F.Cu")
		(hatch none 0.5)
		(connect_pads
			(clearance 0.5)
		)
		(min_thickness 0.25)
		(fill yes
			(thermal_gap 0.5)
			(thermal_bridge_width 0.5)
			(island_removal_mode 0)
		)
		(polygon
			(pts
				(xy 65.659 40.386) (xy 65.659 41.148) (xy 67.818 41.148) (xy 67.818 41.91) (xy 65.659 41.91) (xy 65.659 42.799)
				(xy 70.485 42.799) (xy 70.485 40.386)
			)
		)
	)
	(zone
		(net "GND")
		(layer "F.Cu")
		(hatch none 0.5)
		(connect_pads
			(clearance 0.5)
		)
		(min_thickness 0.25)
		(fill yes
			(thermal_gap 0.5)
			(thermal_bridge_width 0.5)
			(island_removal_mode 0)
		)
		(polygon
			(pts
				(xy 79.248 48.768) (xy 79.248 51.435) (xy 80.645 51.435) (xy 80.772 51.308) (xy 80.772 48.768)
			)
		)
	)
	(zone
		(net "VDD_CORE")
		(layer "F.Cu")
		(hatch none 0.5)
		(connect_pads
			(clearance 0.5)
		)
		(min_thickness 0.25)
		(fill yes
			(thermal_gap 0.5)
			(thermal_bridge_width 0.5)
			(island_removal_mode 0)
		)
		(polygon
			(pts
				(xy 45.593 42.418) (xy 38.862 42.418) (xy 38.862 40.894) (xy 41.529 40.894) (xy 41.529 38.735) (xy 42.926 38.735)
				(xy 43.053 38.862) (xy 43.053 40.894) (xy 45.593 40.894)
			)
		)
	)
	(zone
		(layer "F.Cu")
		(hatch none 0.5)
		(connect_pads
			(clearance 0.5)
		)
		(min_thickness 0.25)
		(fill
			(thermal_gap 0.5)
			(thermal_bridge_width 0.5)
			(island_removal_mode 0)
		)
		(polygon
			(pts
				(xy 17.907 41.656) (xy 17.907 44.196) (xy 19.177 44.196) (xy 19.177 41.783) (xy 18.415 41.783) (xy 18.288 41.656)
			)
		)
	)
	(zone
		(layer "F.Cu")
		(hatch none 0.5)
		(connect_pads
			(clearance 0.5)
		)
		(min_thickness 0.25)
		(fill
			(thermal_gap 0.5)
			(thermal_bridge_width 0.5)
			(island_removal_mode 0)
		)
		(polygon
			(pts
				(xy 11.557 37.084) (xy 11.557 36.576) (xy 10.922 36.576) (xy 10.668 36.322) (xy 7.874 36.322) (xy 7.874 37.338)
				(xy 11.303 37.338)
			)
		)
	)
	(zone
		(layer "F.Cu")
		(hatch none 0.5)
		(connect_pads
			(clearance 0.5)
		)
		(min_thickness 0.25)
		(fill
			(thermal_gap 0.5)
			(thermal_bridge_width 0.5)
			(island_removal_mode 0)
		)
		(polygon
			(pts
				(xy 15.975101 35.270161) (xy 15.975101 34.899829) (xy 16.081832 34.793098) (xy 16.081832 34.32937)
				(xy 16.073501 34.321039) (xy 16.083509 34.311031) (xy 16.438804 34.311031) (xy 16.438804 34.998279)
				(xy 16.161918 35.275164) (xy 15.980105 35.275164)
			)
		)
	)
	(zone
		(layers "F.Cu" "B.Cu")
		(hatch none 0.5)
		(connect_pads
			(clearance 0)
		)
		(min_thickness 0.25)
		(keepout
			(tracks allowed)
			(vias allowed)
			(pads allowed)
			(copperpour allowed)
			(footprints not_allowed)
		)
		(placement
			(enabled no)
			(sheetname "")
		)
		(fill yes
			(thermal_gap 0.5)
			(thermal_bridge_width 0.5)
			(island_removal_mode 0)
		)
		(polygon
			(pts
				(arc
					(start 75.428094 50.824892)
					(mid 65.927884 50.825096)
					(end 75.428094 50.824892)
				)
			)
		)
	)
	(zone
		(net "MH_1")
		(layers "F.Cu" "B.Cu")
		(hatch none 0.5)
		(connect_pads
			(clearance 0.5)
		)
		(min_thickness 0.25)
		(fill yes
			(thermal_gap 0.5)
			(thermal_bridge_width 0.5)
			(island_removal_mode 0)
		)
		(polygon
			(pts
				(arc
					(start 75.438254 50.825502)
					(mid 65.938044 50.825502)
					(end 75.438254 50.825502)
				)
			)
		)
	)
	(zone
		(layers "F.Cu" "B.Cu")
		(hatch none 0.5)
		(connect_pads
			(clearance 0)
		)
		(min_thickness 0.25)
		(keepout
			(tracks allowed)
			(vias allowed)
			(pads allowed)
			(copperpour allowed)
			(footprints not_allowed)
		)
		(placement
			(enabled no)
			(sheetname "")
		)
		(fill yes
			(thermal_gap 0.5)
			(thermal_bridge_width 0.5)
			(island_removal_mode 0)
		)
		(polygon
			(pts
				(arc
					(start 37.88791 14.824964)
					(mid 28.388106 14.825014)
					(end 37.88791 14.824964)
				)
			)
		)
	)
	(zone
		(net "MH_2")
		(layers "F.Cu" "B.Cu")
		(hatch none 0.5)
		(connect_pads
			(clearance 0.5)
		)
		(min_thickness 0.25)
		(fill yes
			(thermal_gap 0.5)
			(thermal_bridge_width 0.5)
			(island_removal_mode 0)
		)
		(polygon
			(pts
				(arc
					(start 37.8968 14.833625)
					(mid 28.396996 14.833625)
					(end 37.8968 14.833625)
				)
			)
		)
	)
	(zone
		(layers "F.Cu" "B.Cu" "In1.Cu" "In2.Cu" "In3.Cu" "In4.Cu" "In5.Cu" "In6.Cu"
			"In7.Cu" "In8.Cu"
		)
		(hatch none 0.5)
		(connect_pads
			(clearance 0)
		)
		(min_thickness 0.25)
		(keepout
			(tracks allowed)
			(vias allowed)
			(pads allowed)
			(copperpour allowed)
			(footprints not_allowed)
		)
		(placement
			(enabled no)
			(sheetname "")
		)
		(fill
			(thermal_gap 0.5)
			(thermal_bridge_width 0.5)
			(island_removal_mode 0)
		)
		(polygon
			(pts
				(arc
					(start 39.138098 58.824876)
					(mid 38.43097 58.532006)
					(end 38.1381 57.824878)
				)
				(arc
					(start 38.1381 51.325018)
					(mid 37.8452 50.61792)
					(end 37.138102 50.32502)
				)
				(arc
					(start 6.13791 50.32502)
					(mid 5.430812 50.03212)
					(end 5.137912 49.325022)
				)
				(arc
					(start 5.137912 39.824914)
					(mid 4.845019 39.117809)
					(end 4.137914 38.824916)
				)
				(arc
					(start -2.162048 38.824916)
					(mid -2.869153 38.532023)
					(end -3.162046 37.824918)
				)
				(arc
					(start -3.162046 -2.175002)
					(mid -2.869146 -2.8821)
					(end -2.162048 -3.175)
				)
				(arc
					(start 87.138002 -3.175)
					(mid 87.845107 -2.882107)
					(end 88.138 -2.175002)
				)
				(xy 88.138 0.024892) (xy 84.938108 0.024892) (xy 0.037846 0.024892) (xy 0.037846 35.625024)
				(arc
					(start 4.137914 35.625024)
					(mid 7.107685 36.855143)
					(end 8.337804 39.824914)
				)
				(xy 8.337804 47.125128)
				(arc
					(start 37.138102 47.125128)
					(mid 40.107865 48.355255)
					(end 41.337992 51.325018)
				)
				(xy 41.337992 55.624984) (xy 84.938108 55.624984) (xy 84.938108 0.124968) (xy 88.138 0.124968)
				(arc
					(start 88.138 57.824878)
					(mid 87.845122 58.531998)
					(end 87.138002 58.824876)
				)
			)
		)
	)
	(zone
		(layers "F.Cu" "B.Cu" "In1.Cu" "In2.Cu" "In3.Cu" "In4.Cu" "In5.Cu" "In6.Cu"
			"In7.Cu" "In8.Cu"
		)
		(hatch none 0.5)
		(connect_pads
			(clearance 0)
		)
		(min_thickness 0.25)
		(keepout
			(tracks allowed)
			(vias allowed)
			(pads allowed)
			(copperpour allowed)
			(footprints not_allowed)
		)
		(placement
			(enabled no)
			(sheetname "")
		)
		(fill
			(thermal_gap 0.5)
			(thermal_bridge_width 0.5)
			(island_removal_mode 0)
		)
		(polygon
			(pts
				(arc
					(start 37.8968 14.833625)
					(mid 28.396996 14.833625)
					(end 37.8968 14.833625)
				)
			)
		)
	)
	(zone
		(layers "F.Cu" "B.Cu" "In1.Cu" "In2.Cu" "In3.Cu" "In4.Cu" "In5.Cu" "In6.Cu"
			"In7.Cu" "In8.Cu"
		)
		(hatch none 0.5)
		(connect_pads
			(clearance 0)
		)
		(min_thickness 0.25)
		(keepout
			(tracks allowed)
			(vias allowed)
			(pads allowed)
			(copperpour allowed)
			(footprints not_allowed)
		)
		(placement
			(enabled no)
			(sheetname "")
		)
		(fill
			(thermal_gap 0.5)
			(thermal_bridge_width 0.5)
			(island_removal_mode 0)
		)
		(polygon
			(pts
				(arc
					(start 75.438254 50.825502)
					(mid 65.938044 50.825502)
					(end 75.438254 50.825502)
				)
			)
		)
	)
	(zone
		(layers "F.Cu" "B.Cu" "In1.Cu" "In2.Cu" "In3.Cu" "In4.Cu" "In5.Cu" "In6.Cu"
			"In7.Cu" "In8.Cu"
		)
		(hatch none 0.5)
		(connect_pads
			(clearance 0)
		)
		(min_thickness 0.25)
		(keepout
			(tracks allowed)
			(vias allowed)
			(pads allowed)
			(copperpour allowed)
			(footprints not_allowed)
		)
		(placement
			(enabled no)
			(sheetname "")
		)
		(fill
			(thermal_gap 0.5)
			(thermal_bridge_width 0.5)
			(island_removal_mode 0)
		)
		(polygon
			(pts
				(arc
					(start 89.7255 55.626)
					(mid 80.2005 55.626)
					(end 89.7255 55.626)
				)
			)
		)
	)
	(zone
		(layers "F.Cu" "B.Cu" "In1.Cu" "In2.Cu" "In3.Cu" "In4.Cu" "In5.Cu" "In6.Cu"
			"In7.Cu" "In8.Cu"
		)
		(hatch none 0.5)
		(connect_pads
			(clearance 0)
		)
		(min_thickness 0.25)
		(keepout
			(tracks allowed)
			(vias allowed)
			(pads allowed)
			(copperpour allowed)
			(footprints not_allowed)
		)
		(placement
			(enabled no)
			(sheetname "")
		)
		(fill
			(thermal_gap 0.5)
			(thermal_bridge_width 0.5)
			(island_removal_mode 0)
		)
		(polygon
			(pts
				(arc
					(start 4.7625 0)
					(mid -4.7625 0)
					(end 4.7625 0)
				)
			)
		)
	)
	(zone
		(layers "F.Cu" "B.Cu" "In1.Cu" "In2.Cu" "In3.Cu" "In4.Cu" "In5.Cu" "In6.Cu"
			"In7.Cu" "In8.Cu"
		)
		(name "Route Keepin")
		(hatch none 0.5)
		(connect_pads
			(clearance 0)
		)
		(min_thickness 0.25)
		(keepout
			(tracks allowed)
			(vias allowed)
			(pads allowed)
			(copperpour allowed)
			(footprints allowed)
		)
		(placement
			(enabled no)
			(sheetname "")
		)
		(fill
			(thermal_gap 0.5)
			(thermal_bridge_width 0.5)
			(island_removal_mode 0)
		)
		(polygon
			(pts
				(xy -2.162048 -2.175002) (xy 87.138002 -2.175002) (xy 87.138002 33.655) (xy 87.138002 34.163) (xy 87.138002 57.824878)
				(xy 39.138098 57.824878)
				(arc
					(start 39.138098 51.325018)
					(mid 38.552305 49.910815)
					(end 37.138102 49.325022)
				)
				(xy 6.13791 49.325022)
				(arc
					(start 6.13791 39.824914)
					(mid 5.552125 38.410703)
					(end 4.137914 37.824918)
				)
				(xy -2.162048 37.824918) (xy -2.162048 24.257) (xy -2.162048 23.749)
			)
		)
	)
	(zone
		(layers "F.Cu" "B.Cu" "In1.Cu" "In2.Cu" "In3.Cu" "In4.Cu" "In5.Cu" "In6.Cu"
			"In7.Cu" "In8.Cu"
		)
		(name "Package Keepin")
		(hatch none 0.5)
		(connect_pads
			(clearance 0)
		)
		(min_thickness 0.25)
		(keepout
			(tracks allowed)
			(vias allowed)
			(pads allowed)
			(copperpour allowed)
			(footprints allowed)
		)
		(placement
			(enabled no)
			(sheetname "")
		)
		(fill
			(thermal_gap 0.5)
			(thermal_bridge_width 0.5)
			(island_removal_mode 0)
		)
		(polygon
			(pts
				(xy 133.731 91.541397) (xy -51.816 91.541397) (xy -51.816 -53.086) (xy 133.731 -53.086)
			)
		)
	)
	(zone
		(layer "B.Cu")
		(hatch none 0.5)
		(connect_pads
			(clearance 0)
		)
		(min_thickness 0.25)
		(keepout
			(tracks not_allowed)
			(vias allowed)
			(pads allowed)
			(copperpour not_allowed)
			(footprints allowed)
		)
		(placement
			(enabled no)
			(sheetname "")
		)
		(fill
			(thermal_gap 0.5)
			(thermal_bridge_width 0.5)
			(island_removal_mode 0)
		)
		(polygon
			(pts
				(arc
					(start 70.805929 45.568819)
					(mid 67.010796 47.081125)
					(end 65.428419 50.847574)
				)
				(arc
					(start 65.428419 50.847574)
					(mid 67.047722 54.555736)
					(end 70.801967 56.065115)
				)
				(arc
					(start 70.801967 56.065115)
					(mid 74.420654 54.495084)
					(end 75.926137 50.849073)
				)
				(arc
					(start 75.926137 50.849073)
					(mid 74.4621 47.174379)
					(end 70.847864 45.566863)
				)
				(xy 70.848068 45.567067)
				(arc
					(start 70.848068 45.823556)
					(mid 74.286582 47.357757)
					(end 75.692533 50.850673)
				)
				(arc
					(start 75.692533 50.850673)
					(mid 74.258858 54.321069)
					(end 70.818223 55.824755)
				)
				(arc
					(start 70.818223 55.824755)
					(mid 67.211669 54.410775)
					(end 65.684375 50.850724)
				)
				(arc
					(start 65.684375 50.850724)
					(mid 67.184915 47.257499)
					(end 70.8041 45.820686)
				)
				(xy 70.8041 45.568819)
			)
		)
	)
	(zone
		(layer "B.Cu")
		(hatch none 0.5)
		(connect_pads
			(clearance 0.5)
		)
		(min_thickness 0.25)
		(fill
			(thermal_gap 0.5)
			(thermal_bridge_width 0.5)
			(island_removal_mode 0)
		)
		(polygon
			(pts
				(xy 62.738 42.418) (xy 62.738 41.275) (xy 62.865 41.402) (xy 63.627 41.402) (xy 63.754 41.275) (xy 63.754 40.64)
				(xy 69.85 40.64) (xy 69.85 42.799) (xy 66.167 42.799) (xy 66.167 44.958) (xy 63.881 44.958) (xy 63.881 42.418)
			)
		)
		(polygon
			(pts
				(xy 65.225854 41.00195) (xy 64.531723 41.00195) (xy 64.531723 41.263494) (xy 65.225854 41.263494)
			)
		)
		(polygon
			(pts
				(xy 65.205737 41.504946) (xy 64.561898 41.504946) (xy 64.561898 41.756432) (xy 65.205737 41.756432)
			)
		)
		(polygon
			(pts
				(xy 65.205737 41.987826) (xy 64.551839 41.987826) (xy 64.551839 42.279545) (xy 65.205737 42.279545)
			)
		)
		(polygon
			(pts
				(xy 65.215795 42.510913) (xy 64.541781 42.510913) (xy 64.541781 42.85295) (xy 65.215795 42.85295)
			)
		)
		(polygon
			(pts
				(xy 65.950135 43.23522) (xy 65.648357 43.23522) (xy 65.648357 43.939409) (xy 65.950135 43.939409)
			)
		)
	)
	(zone
		(layer "B.Cu")
		(hatch none 0.5)
		(connect_pads
			(clearance 0.5)
		)
		(min_thickness 0.25)
		(fill
			(thermal_gap 0.5)
			(thermal_bridge_width 0.5)
			(island_removal_mode 0)
		)
		(polygon
			(pts
				(xy 68.961 36.068) (xy 68.961 38.481) (xy 67.945 38.481) (xy 67.945 39.878) (xy 70.104 39.878) (xy 70.231 40.005)
				(xy 74.549 40.005) (xy 74.549 36.068)
			)
		)
		(polygon
			(pts
				(xy 71.126452 39.523594) (xy 70.411543 39.523594) (xy 70.411543 39.765935) (xy 71.126452 39.765935)
			)
		)
		(polygon
			(pts
				(xy 71.114336 39.014679) (xy 70.393357 39.014679) (xy 70.393357 39.287298) (xy 71.114336 39.287298)
			)
		)
		(polygon
			(pts
				(xy 71.108265 38.529997) (xy 70.429704 38.529997) (xy 70.429704 38.778383) (xy 71.108265 38.778383)
			)
		)
		(polygon
			(pts
				(xy 69.469 37.338) (xy 69.215 37.338) (xy 69.215 38.1) (xy 69.469 38.1)
			)
		)
		(polygon
			(pts
				(xy 69.938976 37.32436) (xy 69.654242 37.32436) (xy 69.654242 38.033198) (xy 69.938976 38.033198)
			)
		)
	)
	(zone
		(net "DDR_VTT")
		(layer "B.Cu")
		(hatch none 0.5)
		(connect_pads
			(clearance 0.5)
		)
		(min_thickness 0.25)
		(fill yes
			(thermal_gap 0.5)
			(thermal_bridge_width 0.5)
			(island_removal_mode 0)
		)
		(polygon
			(pts
				(xy 79.121 43.307) (xy 78.359 43.307) (xy 77.724 43.307) (xy 76.962 43.307) (xy 76.454 43.307) (xy 75.692 43.307)
				(xy 75.692 42.418) (xy 75.438 42.164) (xy 75.438 41.148) (xy 78.74 41.148) (xy 79.375 41.783) (xy 79.375 42.291)
				(xy 79.121 42.545)
			)
		)
	)
	(zone
		(layer "B.Cu")
		(hatch none 0.5)
		(connect_pads
			(clearance 0.5)
		)
		(min_thickness 0.25)
		(fill
			(thermal_gap 0.5)
			(thermal_bridge_width 0.5)
			(island_removal_mode 0)
		)
		(polygon
			(pts
				(xy 49.3649 36.068) (xy 49.3649 38.481) (xy 48.3489 38.481) (xy 48.3489 39.878) (xy 50.5079 39.878)
				(xy 50.6349 40.005) (xy 54.9529 40.005) (xy 54.9529 36.068)
			)
		)
		(polygon
			(pts
				(xy 51.530352 39.523594) (xy 50.815443 39.523594) (xy 50.815443 39.765935) (xy 51.530352 39.765935)
			)
		)
		(polygon
			(pts
				(xy 51.518236 39.014679) (xy 50.797257 39.014679) (xy 50.797257 39.287298) (xy 51.518236 39.287298)
			)
		)
		(polygon
			(pts
				(xy 51.512165 38.529997) (xy 50.833604 38.529997) (xy 50.833604 38.778383) (xy 51.512165 38.778383)
			)
		)
		(polygon
			(pts
				(xy 49.8729 37.338) (xy 49.6189 37.338) (xy 49.6189 38.1) (xy 49.8729 38.1)
			)
		)
		(polygon
			(pts
				(xy 50.342876 37.32436) (xy 50.058142 37.32436) (xy 50.058142 38.033198) (xy 50.342876 38.033198)
			)
		)
	)
	(zone
		(layer "B.Cu")
		(hatch none 0.5)
		(connect_pads
			(clearance 0)
		)
		(min_thickness 0.25)
		(keepout
			(tracks not_allowed)
			(vias allowed)
			(pads allowed)
			(copperpour not_allowed)
			(footprints allowed)
		)
		(placement
			(enabled no)
			(sheetname "")
		)
		(fill
			(thermal_gap 0.5)
			(thermal_bridge_width 0.5)
			(island_removal_mode 0)
		)
		(polygon
			(pts
				(arc
					(start 28.191003 16.511067)
					(mid 30.156689 19.102266)
					(end 33.260767 20.073315)
				)
				(arc
					(start 33.260767 20.073315)
					(mid 36.879454 18.503284)
					(end 38.384937 14.857273)
				)
				(arc
					(start 38.384937 14.857273)
					(mid 36.9209 11.182579)
					(end 33.306664 9.575063)
				)
				(xy 33.306868 9.575267)
				(arc
					(start 33.306868 9.831756)
					(mid 36.745382 11.365957)
					(end 38.151333 14.858873)
				)
				(arc
					(start 38.151333 14.858873)
					(mid 36.717658 18.329269)
					(end 33.277023 19.832955)
				)
				(arc
					(start 33.277023 19.832955)
					(mid 30.273599 18.918335)
					(end 28.400223 16.3989)
				)
				(xy 28.288056 16.511067)
			)
		)
	)
	(zone
		(net "VDD_1.5V")
		(layer "B.Cu")
		(hatch none 0.5)
		(connect_pads
			(clearance 0.5)
		)
		(min_thickness 0.25)
		(fill yes
			(thermal_gap 0.5)
			(thermal_bridge_width 0.5)
			(island_removal_mode 0)
		)
		(polygon
			(pts
				(xy 38.1 26.67) (xy 38.1 24.13) (xy 37.592 24.13) (xy 37.592 26.67)
			)
		)
	)
	(zone
		(layer "B.Cu")
		(hatch none 0.5)
		(connect_pads
			(clearance 0)
		)
		(min_thickness 0.25)
		(keepout
			(tracks allowed)
			(vias allowed)
			(pads allowed)
			(copperpour allowed)
			(footprints not_allowed)
		)
		(placement
			(enabled no)
			(sheetname "")
		)
		(fill
			(thermal_gap 0.5)
			(thermal_bridge_width 0.5)
			(island_removal_mode 0)
		)
		(polygon
			(pts
				(xy 84.938108 45.824902) (xy 50.138076 45.824902) (xy 50.138076 43.824906) (xy 41.138094 43.824906)
				(xy 41.138094 33.824926) (xy 8.137906 33.824926) (xy 8.137906 19.025108) (xy 0.0381 19.025108) (xy 0.0381 0.024892)
				(xy 84.938108 0.024892)
			)
		)
	)
	(zone
		(layer "B.Cu")
		(hatch none 0.5)
		(connect_pads
			(clearance 0)
		)
		(min_thickness 0.25)
		(keepout
			(tracks allowed)
			(vias allowed)
			(pads allowed)
			(copperpour allowed)
			(footprints not_allowed)
		)
		(placement
			(enabled no)
			(sheetname "")
		)
		(fill
			(thermal_gap 0.5)
			(thermal_bridge_width 0.5)
			(island_removal_mode 0)
		)
		(polygon
			(pts
				(arc
					(start 39.138098 58.824876)
					(mid 38.43097 58.532006)
					(end 38.1381 57.824878)
				)
				(arc
					(start 38.1381 51.325018)
					(mid 37.8452 50.61792)
					(end 37.138102 50.32502)
				)
				(arc
					(start 6.13791 50.32502)
					(mid 5.430812 50.03212)
					(end 5.137912 49.325022)
				)
				(arc
					(start 5.137912 39.824914)
					(mid 4.845019 39.117809)
					(end 4.137914 38.824916)
				)
				(arc
					(start -2.162048 38.824916)
					(mid -2.869153 38.532023)
					(end -3.162046 37.824918)
				)
				(arc
					(start -3.162046 -2.175002)
					(mid -2.869146 -2.8821)
					(end -2.162048 -3.175)
				)
				(arc
					(start 87.138002 -3.175)
					(mid 87.845107 -2.882107)
					(end 88.138 -2.175002)
				)
				(xy 88.138 0.024892) (xy 84.938108 0.024892) (xy 0.037846 0.024892) (xy 0.037846 19.025108) (xy 8.137906 19.025108)
				(xy 8.137906 33.82518) (xy 41.13784 33.82518) (xy 41.13784 43.82516) (xy 50.137822 43.82516) (xy 50.137822 45.825156)
				(xy 84.938108 45.825156) (xy 84.938108 0.124968) (xy 88.138 0.124968)
				(arc
					(start 88.138 57.824878)
					(mid 87.845122 58.531998)
					(end 87.138002 58.824876)
				)
			)
		)
	)
	(zone
		(net "VDD_1.8V")
		(layer "B.Cu")
		(hatch none 0.5)
		(connect_pads
			(clearance 0.5)
		)
		(min_thickness 0.25)
		(fill yes
			(thermal_gap 0.5)
			(thermal_bridge_width 0.5)
			(island_removal_mode 0)
		)
		(polygon
			(pts
				(xy 67.056 3.937) (xy 66.167 3.937) (xy 66.167 0) (xy 65.913 -0.254) (xy 45.339 -0.254) (xy 45.339 1.397)
				(xy 44.577 1.397) (xy 44.577 0.508) (xy 44.45 0.381) (xy 43.815 0.381) (xy 43.307 0.889) (xy 43.18 0.889)
				(xy 42.037 -0.254) (xy 37.592 -0.254) (xy 37.465 -0.127) (xy 7.747 -0.127) (xy 5.588 -0.127) (xy 5.333975 0.127025)
				(xy 5.333975 1.651025) (xy -0.381 7.366) (xy -0.381 35.941) (xy -2.032 35.941) (xy -2.032 5.461)
				(xy 5.588 -2.159) (xy 66.294 -2.159) (xy 67.056 -1.397)
			)
		)
	)
	(zone
		(layer "B.Cu")
		(hatch none 0.5)
		(connect_pads
			(clearance 0.5)
		)
		(min_thickness 0.25)
		(fill
			(thermal_gap 0.5)
			(thermal_bridge_width 0.5)
			(island_removal_mode 0)
		)
		(polygon
			(pts
				(xy 43.1419 44.831) (xy 43.1419 41.275) (xy 43.2689 41.402) (xy 44.0309 41.402) (xy 44.1579 41.275)
				(xy 44.1579 40.64) (xy 50.2539 40.64) (xy 50.2539 42.799) (xy 46.5709 42.799) (xy 46.5709 44.831)
			)
		)
		(polygon
			(pts
				(xy 45.629754 41.00195) (xy 44.935623 41.00195) (xy 44.935623 41.263494) (xy 45.629754 41.263494)
			)
		)
		(polygon
			(pts
				(xy 45.609637 41.504946) (xy 44.965798 41.504946) (xy 44.965798 41.756432) (xy 45.609637 41.756432)
			)
		)
		(polygon
			(pts
				(xy 45.609637 41.987826) (xy 44.955739 41.987826) (xy 44.955739 42.279545) (xy 45.609637 42.279545)
			)
		)
		(polygon
			(pts
				(xy 45.619695 42.510913) (xy 44.945681 42.510913) (xy 44.945681 42.85295) (xy 45.619695 42.85295)
			)
		)
		(polygon
			(pts
				(xy 46.354035 43.23522) (xy 46.052257 43.23522) (xy 46.052257 43.939409) (xy 46.354035 43.939409)
			)
		)
	)
	(zone
		(net "VDDA_PLL")
		(layer "B.Cu")
		(hatch none 0.5)
		(connect_pads
			(clearance 0.5)
		)
		(min_thickness 0.25)
		(fill yes
			(thermal_gap 0.5)
			(thermal_bridge_width 0.5)
			(island_removal_mode 0)
		)
		(polygon
			(pts
				(xy 36.703 26.162) (xy 36.703 28.956) (xy 38.1 28.956) (xy 38.227 28.829) (xy 38.227 27.051) (xy 37.211 27.051)
				(xy 37.211 26.162)
			)
		)
	)
	(zone
		(layer "B.Cu")
		(hatch none 0.5)
		(connect_pads
			(clearance 0)
		)
		(min_thickness 0.25)
		(keepout
			(tracks not_allowed)
			(vias allowed)
			(pads allowed)
			(copperpour not_allowed)
			(footprints allowed)
		)
		(placement
			(enabled no)
			(sheetname "")
		)
		(fill
			(thermal_gap 0.5)
			(thermal_bridge_width 0.5)
			(island_removal_mode 0)
		)
		(polygon
			(pts
				(arc
					(start 33.264729 9.577019)
					(mid 29.469596 11.089325)
					(end 27.887219 14.855774)
				)
				(arc
					(start 27.887219 14.855774)
					(mid 27.920479 15.339186)
					(end 27.997404 15.817596)
				)
				(xy 28.196311 15.618689)
				(arc
					(start 28.208148 15.618689)
					(mid 28.161221 15.240041)
					(end 28.143175 14.858924)
				)
				(arc
					(start 28.143175 14.858924)
					(mid 29.643715 11.265699)
					(end 33.2629 9.828886)
				)
				(xy 33.2629 9.577019)
			)
		)
	)
	(zone
		(layer "B.Cu")
		(hatch none 0.5)
		(connect_pads
			(clearance 0.5)
		)
		(min_thickness 0.25)
		(fill
			(thermal_gap 0.5)
			(thermal_bridge_width 0.5)
			(island_removal_mode 0)
		)
		(polygon
			(pts
				(xy 66.421 43.18) (xy 66.421 44.704) (xy 63.754 44.704) (xy 63.754 42.291) (xy 60.198 42.291) (xy 60.198 43.18)
				(xy 62.611 43.18) (xy 62.611 44.831) (xy 60.071 44.831) (xy 59.055 45.847) (xy 59.055 52.07) (xy 60.833 53.848)
				(xy 62.357 53.848) (xy 65.913 53.848) (xy 65.913 52.832) (xy 65.659 52.578) (xy 65.659 48.641) (xy 68.707 45.593)
				(xy 72.771 45.593) (xy 77.089 49.911) (xy 83.566 49.911) (xy 84.709 48.768) (xy 84.709 46.355) (xy 84.455 46.101)
				(xy 79.883 46.101) (xy 79.248 45.466) (xy 79.248 44.069) (xy 78.359 44.069) (xy 77.724 44.069) (xy 76.962 44.069)
				(xy 76.454 44.069) (xy 75.692 44.069) (xy 75.184 44.069) (xy 74.549 44.069) (xy 74.549 40.386) (xy 71.501 40.386)
				(xy 71.247 40.64) (xy 70.358 40.64) (xy 70.231 40.767) (xy 70.231 43.18)
			)
		)
	)
	(zone
		(layer "B.Cu")
		(hatch none 0.5)
		(connect_pads
			(clearance 0.5)
		)
		(min_thickness 0.25)
		(fill
			(thermal_gap 0.5)
			(thermal_bridge_width 0.5)
			(island_removal_mode 0)
		)
		(polygon
			(pts
				(xy 46.8249 43.18) (xy 46.8249 52.197) (xy 54.864 52.197) (xy 54.864 46.041945) (xy 54.737 46.041945)
				(xy 54.9529 45.826045) (xy 54.9529 43.18) (xy 57.658 43.18) (xy 57.658 42.164) (xy 54.9529 42.164)
				(xy 54.9529 40.386) (xy 51.9049 40.386) (xy 51.6509 40.64) (xy 50.7619 40.64) (xy 50.6349 40.767)
				(xy 50.6349 43.18)
			)
		)
	)
	(zone
		(net "GND")
		(layer "In1.Cu")
		(hatch none 0.5)
		(connect_pads
			(clearance 0.5)
		)
		(min_thickness 0.25)
		(fill yes
			(thermal_gap 0.5)
			(thermal_bridge_width 0.5)
			(island_removal_mode 0)
		)
		(polygon
			(pts
				(xy 39.1382 57.824776)
				(arc
					(start 39.1382 51.325018)
					(mid 38.552378 49.910742)
					(end 37.138102 49.32492)
				)
				(xy 6.138012 49.32492)
				(arc
					(start 6.138012 39.824914)
					(mid 5.552197 38.410631)
					(end 4.137914 37.824816)
				)
				(xy -2.161946 37.824816) (xy -2.161946 -0.393954) (xy -0.381 -2.1749) (xy 87.1379 -2.1749) (xy 87.1379 55.626)
				(xy 84.939124 57.824776)
			)
		)
		(polygon
			(pts
				(xy 63.239853 1.596898) (xy 62.242675 1.596898) (xy 62.242675 0.844652) (xy 63.239853 0.844652)
			)
		)
		(polygon
			(pts
				(xy 63.228195 0.698881) (xy 62.231016 0.698881) (xy 62.231016 -0.035865) (xy 63.228195 -0.035865)
			)
		)
		(polygon
			(pts
				(xy 61.222204 1.596898) (xy 60.324162 1.596898) (xy 60.324162 0.838835) (xy 61.222204 0.838835)
			)
		)
		(polygon
			(pts
				(xy 61.216362 0.722198) (xy 60.341662 0.722198) (xy 60.341662 -0.024206) (xy 61.216362 -0.024206)
			)
		)
		(polygon
			(pts
				(xy 59.391144 1.591056) (xy 58.411491 1.591056) (xy 58.411491 0.85631) (xy 59.391144 0.85631)
			)
		)
		(polygon
			(pts
				(xy 59.373668 0.704698) (xy 58.382332 0.704698) (xy 58.382332 -0.03589) (xy 59.373668 -0.03589)
			)
		)
		(polygon
			(pts
				(xy 57.390995 1.591056) (xy 56.411317 1.591056) (xy 56.411317 0.850468) (xy 57.390995 0.850468)
			)
		)
		(polygon
			(pts
				(xy 57.437655 0.716356) (xy 56.405501 0.716356) (xy 56.405501 -0.041732) (xy 57.437655 -0.041732)
			)
		)
		(polygon
			(pts
				(xy 55.437481 1.602715) (xy 54.498621 1.602715) (xy 54.498621 0.85631) (xy 55.437481 0.85631)
			)
		)
		(polygon
			(pts
				(xy 55.443323 0.710514) (xy 54.498621 0.710514) (xy 54.498621 -0.03589) (xy 55.443323 -0.03589)
			)
		)
		(polygon
			(pts
				(xy 53.46065 1.608557) (xy 52.504315 1.608557) (xy 52.504315 0.850468) (xy 53.46065 0.850468)
			)
		)
		(polygon
			(pts
				(xy 53.472309 0.716356) (xy 52.510157 0.716356) (xy 52.510157 -0.03589) (xy 53.472309 -0.03589)
			)
		)
		(polygon
			(pts
				(xy 51.472135 1.605661) (xy 50.489561 1.605661) (xy 50.489561 0.853415) (xy 51.472135 0.853415)
			)
		)
		(polygon
			(pts
				(xy 51.463397 0.722198) (xy 50.483719 0.722198) (xy 50.483719 -0.030048) (xy 51.463397 -0.030048)
			)
		)
		(polygon
			(pts
				(xy 49.390732 1.608557) (xy 48.285679 1.608557) (xy 48.285679 0.865048) (xy 49.390732 0.865048)
			)
		)
		(polygon
			(pts
				(xy 49.390732 0.71308) (xy 48.276942 0.71308) (xy 48.276942 -0.030429) (xy 49.390732 -0.030429)
			)
		)
		(polygon
			(pts
				(xy 32.512 25.4) (xy 30.607 25.4) (xy 30.607 23.495) (xy 32.512 23.495)
			)
		)
	)
	(zone
		(layer "In2.Cu")
		(hatch none 0.5)
		(connect_pads
			(clearance 0)
		)
		(min_thickness 0.25)
		(keepout
			(tracks not_allowed)
			(vias allowed)
			(pads allowed)
			(copperpour not_allowed)
			(footprints allowed)
		)
		(placement
			(enabled no)
			(sheetname "")
		)
		(fill
			(thermal_gap 0.5)
			(thermal_bridge_width 0.5)
			(island_removal_mode 0)
		)
		(polygon
			(pts
				(xy 51.689 5.842) (xy 51.689 6.223) (xy 51.816 6.223) (xy 51.816 5.842)
			)
		)
	)
	(zone
		(layer "In2.Cu")
		(hatch none 0.5)
		(connect_pads
			(clearance 0)
		)
		(min_thickness 0.25)
		(keepout
			(tracks not_allowed)
			(vias allowed)
			(pads allowed)
			(copperpour not_allowed)
			(footprints allowed)
		)
		(placement
			(enabled no)
			(sheetname "")
		)
		(fill
			(thermal_gap 0.5)
			(thermal_bridge_width 0.5)
			(island_removal_mode 0)
		)
		(polygon
			(pts
				(xy 13.97 4.826) (xy 13.97 5.207) (xy 14.097 5.207) (xy 14.097 4.826)
			)
		)
	)
	(zone
		(layer "In2.Cu")
		(hatch none 0.5)
		(connect_pads
			(clearance 0)
		)
		(min_thickness 0.25)
		(keepout
			(tracks not_allowed)
			(vias allowed)
			(pads allowed)
			(copperpour not_allowed)
			(footprints allowed)
		)
		(placement
			(enabled no)
			(sheetname "")
		)
		(fill
			(thermal_gap 0.5)
			(thermal_bridge_width 0.5)
			(island_removal_mode 0)
		)
		(polygon
			(pts
				(xy 8.89 9.906) (xy 8.89 10.287) (xy 9.017 10.287) (xy 9.017 9.906)
			)
		)
	)
	(zone
		(layer "In2.Cu")
		(hatch none 0.5)
		(connect_pads
			(clearance 0)
		)
		(min_thickness 0.25)
		(keepout
			(tracks not_allowed)
			(vias allowed)
			(pads allowed)
			(copperpour not_allowed)
			(footprints allowed)
		)
		(placement
			(enabled no)
			(sheetname "")
		)
		(fill
			(thermal_gap 0.5)
			(thermal_bridge_width 0.5)
			(island_removal_mode 0)
		)
		(polygon
			(pts
				(xy 45.72 2.794) (xy 45.72 3.175) (xy 45.847 3.175) (xy 45.847 2.794)
			)
		)
	)
	(zone
		(layer "In2.Cu")
		(hatch none 0.5)
		(connect_pads
			(clearance 0)
		)
		(min_thickness 0.25)
		(keepout
			(tracks not_allowed)
			(vias allowed)
			(pads allowed)
			(copperpour not_allowed)
			(footprints allowed)
		)
		(placement
			(enabled no)
			(sheetname "")
		)
		(fill
			(thermal_gap 0.5)
			(thermal_bridge_width 0.5)
			(island_removal_mode 0)
		)
		(polygon
			(pts
				(xy 13.9192 9.906) (xy 13.9192 10.287) (xy 14.0462 10.287) (xy 14.0462 9.906)
			)
		)
	)
	(zone
		(layer "In2.Cu")
		(hatch none 0.5)
		(connect_pads
			(clearance 0)
		)
		(min_thickness 0.25)
		(keepout
			(tracks not_allowed)
			(vias allowed)
			(pads allowed)
			(copperpour not_allowed)
			(footprints allowed)
		)
		(placement
			(enabled no)
			(sheetname "")
		)
		(fill
			(thermal_gap 0.5)
			(thermal_bridge_width 0.5)
			(island_removal_mode 0)
		)
		(polygon
			(pts
				(xy 16.637 9.906) (xy 16.637 10.287) (xy 16.764 10.287) (xy 16.764 9.906)
			)
		)
	)
	(zone
		(layer "In2.Cu")
		(hatch none 0.5)
		(connect_pads
			(clearance 0)
		)
		(min_thickness 0.25)
		(keepout
			(tracks not_allowed)
			(vias allowed)
			(pads allowed)
			(copperpour not_allowed)
			(footprints allowed)
		)
		(placement
			(enabled no)
			(sheetname "")
		)
		(fill
			(thermal_gap 0.5)
			(thermal_bridge_width 0.5)
			(island_removal_mode 0)
		)
		(polygon
			(pts
				(xy 14.097 14.986) (xy 14.097 15.367) (xy 14.224 15.367) (xy 14.224 14.986)
			)
		)
	)
	(zone
		(net "EXT_12.0V")
		(layer "In2.Cu")
		(hatch none 0.5)
		(connect_pads
			(clearance 0.5)
		)
		(min_thickness 0.25)
		(fill yes
			(thermal_gap 0.5)
			(thermal_bridge_width 0.5)
			(island_removal_mode 0)
		)
		(polygon
			(pts
				(xy 18.796 25.781) (xy 18.796 33.02) (xy 21.844 36.068) (xy 84.963 36.068) (xy 86.868 37.973) (xy 86.868 53.086)
				(xy 85.598 54.356) (xy 65.151 54.356) (xy 64.135 55.372) (xy 62.738 55.372) (xy 61.722 54.356) (xy 41.783 54.356)
				(xy 40.132 52.705) (xy 40.132 49.403) (xy 38.1 47.371) (xy 21.844 47.371) (xy 18.796 44.323) (xy 16.002 44.323)
				(xy 15.113 43.434) (xy 9.906 43.434) (xy 8.509 42.037) (xy 8.509 35.052) (xy 3.556 30.099) (xy 3.556 26.162)
				(xy 4.699 25.019) (xy 18.034 25.019)
			)
		)
	)
	(zone
		(layer "In2.Cu")
		(hatch none 0.5)
		(connect_pads
			(clearance 0)
		)
		(min_thickness 0.25)
		(keepout
			(tracks not_allowed)
			(vias allowed)
			(pads allowed)
			(copperpour not_allowed)
			(footprints allowed)
		)
		(placement
			(enabled no)
			(sheetname "")
		)
		(fill
			(thermal_gap 0.5)
			(thermal_bridge_width 0.5)
			(island_removal_mode 0)
		)
		(polygon
			(pts
				(xy 9.017 20.066) (xy 9.017 20.447) (xy 9.144 20.447) (xy 9.144 20.066)
			)
		)
	)
	(zone
		(layer "In2.Cu")
		(hatch none 0.5)
		(connect_pads
			(clearance 0)
		)
		(min_thickness 0.25)
		(keepout
			(tracks not_allowed)
			(vias allowed)
			(pads allowed)
			(copperpour not_allowed)
			(footprints allowed)
		)
		(placement
			(enabled no)
			(sheetname "")
		)
		(fill
			(thermal_gap 0.5)
			(thermal_bridge_width 0.5)
			(island_removal_mode 0)
		)
		(polygon
			(pts
				(xy 17.78 20.066) (xy 17.78 20.32) (xy 17.907 20.32) (xy 17.907 20.066)
			)
		)
	)
	(zone
		(layer "In2.Cu")
		(hatch none 0.5)
		(connect_pads
			(clearance 0)
		)
		(min_thickness 0.25)
		(keepout
			(tracks not_allowed)
			(vias allowed)
			(pads allowed)
			(copperpour not_allowed)
			(footprints allowed)
		)
		(placement
			(enabled no)
			(sheetname "")
		)
		(fill
			(thermal_gap 0.5)
			(thermal_bridge_width 0.5)
			(island_removal_mode 0)
		)
		(polygon
			(pts
				(xy 15.367 7.366) (xy 15.367 7.747) (xy 15.494 7.747) (xy 15.494 7.366)
			)
		)
	)
	(zone
		(layer "In2.Cu")
		(hatch none 0.5)
		(connect_pads
			(clearance 0)
		)
		(min_thickness 0.25)
		(keepout
			(tracks not_allowed)
			(vias allowed)
			(pads allowed)
			(copperpour not_allowed)
			(footprints allowed)
		)
		(placement
			(enabled no)
			(sheetname "")
		)
		(fill
			(thermal_gap 0.5)
			(thermal_bridge_width 0.5)
			(island_removal_mode 0)
		)
		(polygon
			(pts
				(xy 12.827 22.479) (xy 12.827 22.86) (xy 12.954 22.86) (xy 12.954 22.479)
			)
		)
	)
	(zone
		(layer "In2.Cu")
		(hatch none 0.5)
		(connect_pads
			(clearance 0)
		)
		(min_thickness 0.25)
		(keepout
			(tracks not_allowed)
			(vias allowed)
			(pads allowed)
			(copperpour not_allowed)
			(footprints allowed)
		)
		(placement
			(enabled no)
			(sheetname "")
		)
		(fill
			(thermal_gap 0.5)
			(thermal_bridge_width 0.5)
			(island_removal_mode 0)
		)
		(polygon
			(pts
				(xy 56.642 3.81) (xy 56.642 4.191) (xy 56.769 4.191) (xy 56.769 3.81)
			)
		)
	)
	(zone
		(layer "In2.Cu")
		(hatch none 0.5)
		(connect_pads
			(clearance 0)
		)
		(min_thickness 0.25)
		(keepout
			(tracks not_allowed)
			(vias allowed)
			(pads allowed)
			(copperpour not_allowed)
			(footprints allowed)
		)
		(placement
			(enabled no)
			(sheetname "")
		)
		(fill
			(thermal_gap 0.5)
			(thermal_bridge_width 0.5)
			(island_removal_mode 0)
		)
		(polygon
			(pts
				(xy 50.673 3.81) (xy 50.673 4.191) (xy 50.8 4.191) (xy 50.8 3.81)
			)
		)
	)
	(zone
		(layer "In2.Cu")
		(hatch none 0.5)
		(connect_pads
			(clearance 0)
		)
		(min_thickness 0.25)
		(keepout
			(tracks allowed)
			(vias allowed)
			(pads allowed)
			(copperpour allowed)
			(footprints allowed)
		)
		(placement
			(enabled no)
			(sheetname "")
		)
		(fill
			(thermal_gap 0.5)
			(thermal_bridge_width 0.5)
			(island_removal_mode 0)
		)
		(polygon
			(pts
				(xy 12.573 15.494) (xy 12.573 16.256) (xy 15.621 16.256) (xy 15.621 15.494)
			)
		)
	)
	(zone
		(layer "In2.Cu")
		(hatch none 0.5)
		(connect_pads
			(clearance 0)
		)
		(min_thickness 0.25)
		(keepout
			(tracks not_allowed)
			(vias allowed)
			(pads allowed)
			(copperpour not_allowed)
			(footprints allowed)
		)
		(placement
			(enabled no)
			(sheetname "")
		)
		(fill
			(thermal_gap 0.5)
			(thermal_bridge_width 0.5)
			(island_removal_mode 0)
		)
		(polygon
			(pts
				(xy 9.017 12.446) (xy 9.017 12.827) (xy 9.144 12.827) (xy 9.144 12.446)
			)
		)
	)
	(zone
		(layer "In2.Cu")
		(hatch none 0.5)
		(connect_pads
			(clearance 0)
		)
		(min_thickness 0.25)
		(keepout
			(tracks not_allowed)
			(vias allowed)
			(pads allowed)
			(copperpour not_allowed)
			(footprints allowed)
		)
		(placement
			(enabled no)
			(sheetname "")
		)
		(fill
			(thermal_gap 0.5)
			(thermal_bridge_width 0.5)
			(island_removal_mode 0)
		)
		(polygon
			(pts
				(xy 54.737 3.81) (xy 54.737 4.191) (xy 54.864 4.191) (xy 54.864 3.81)
			)
		)
	)
	(zone
		(layer "In2.Cu")
		(hatch none 0.5)
		(connect_pads
			(clearance 0)
		)
		(min_thickness 0.25)
		(keepout
			(tracks not_allowed)
			(vias allowed)
			(pads allowed)
			(copperpour not_allowed)
			(footprints allowed)
		)
		(placement
			(enabled no)
			(sheetname "")
		)
		(fill
			(thermal_gap 0.5)
			(thermal_bridge_width 0.5)
			(island_removal_mode 0)
		)
		(polygon
			(pts
				(xy 58.674 5.969) (xy 58.674 6.223) (xy 58.801 6.223) (xy 58.801 5.969)
			)
		)
	)
	(zone
		(net "VDDA_PCIE0")
		(layer "In2.Cu")
		(hatch none 0.5)
		(connect_pads
			(clearance 0.5)
		)
		(min_thickness 0.25)
		(fill yes
			(thermal_gap 0.5)
			(thermal_bridge_width 0.5)
			(island_removal_mode 0)
		)
		(polygon
			(pts
				(xy 59.817 7.747) (xy 55.118 7.747) (xy 55.118 7.239) (xy 53.34 7.239) (xy 53.34 10.287) (xy 60.452 10.287)
				(xy 60.452 9.525) (xy 61.087 9.525) (xy 61.976 8.636) (xy 61.976 8.509) (xy 62.484 8.001) (xy 62.484 4.699)
				(xy 61.976 4.191) (xy 60.071 4.191) (xy 59.817 4.445) (xy 59.817 6.096) (xy 60.198 6.477) (xy 60.198 7.366)
			)
		)
	)
	(zone
		(layer "In2.Cu")
		(hatch none 0.5)
		(connect_pads
			(clearance 0)
		)
		(min_thickness 0.25)
		(keepout
			(tracks allowed)
			(vias allowed)
			(pads allowed)
			(copperpour allowed)
			(footprints allowed)
		)
		(placement
			(enabled no)
			(sheetname "")
		)
		(fill
			(thermal_gap 0.5)
			(thermal_bridge_width 0.5)
			(island_removal_mode 0)
		)
		(polygon
			(pts
				(xy 6.985 8.636) (xy 6.985 11.811) (xy 13.843 11.811) (xy 13.843 8.636)
			)
		)
	)
	(zone
		(layer "In2.Cu")
		(hatch none 0.5)
		(connect_pads
			(clearance 0)
		)
		(min_thickness 0.25)
		(keepout
			(tracks not_allowed)
			(vias allowed)
			(pads allowed)
			(copperpour not_allowed)
			(footprints allowed)
		)
		(placement
			(enabled no)
			(sheetname "")
		)
		(fill
			(thermal_gap 0.5)
			(thermal_bridge_width 0.5)
			(island_removal_mode 0)
		)
		(polygon
			(pts
				(xy 44.704 3.81) (xy 44.704 4.191) (xy 44.831 4.191) (xy 44.831 3.81)
			)
		)
	)
	(zone
		(layer "In2.Cu")
		(hatch none 0.5)
		(connect_pads
			(clearance 0)
		)
		(min_thickness 0.25)
		(keepout
			(tracks not_allowed)
			(vias allowed)
			(pads allowed)
			(copperpour not_allowed)
			(footprints allowed)
		)
		(placement
			(enabled no)
			(sheetname "")
		)
		(fill
			(thermal_gap 0.5)
			(thermal_bridge_width 0.5)
			(island_removal_mode 0)
		)
		(polygon
			(pts
				(xy 16.637 17.526) (xy 16.637 17.907) (xy 16.764 17.907) (xy 16.764 17.526)
			)
		)
	)
	(zone
		(layer "In2.Cu")
		(hatch none 0.5)
		(connect_pads
			(clearance 0)
		)
		(min_thickness 0.25)
		(keepout
			(tracks not_allowed)
			(vias allowed)
			(pads allowed)
			(copperpour not_allowed)
			(footprints allowed)
		)
		(placement
			(enabled no)
			(sheetname "")
		)
		(fill
			(thermal_gap 0.5)
			(thermal_bridge_width 0.5)
			(island_removal_mode 0)
		)
		(polygon
			(pts
				(xy 12.6492 7.366) (xy 12.6492 7.747) (xy 12.7762 7.747) (xy 12.7762 7.366)
			)
		)
	)
	(zone
		(layer "In2.Cu")
		(hatch none 0.5)
		(connect_pads
			(clearance 0)
		)
		(min_thickness 0.25)
		(keepout
			(tracks allowed)
			(vias allowed)
			(pads allowed)
			(copperpour allowed)
			(footprints allowed)
		)
		(placement
			(enabled no)
			(sheetname "")
		)
		(fill
			(thermal_gap 0.5)
			(thermal_bridge_width 0.5)
			(island_removal_mode 0)
		)
		(polygon
			(pts
				(xy 14.986 17.907) (xy 14.986 19.05) (xy 17.272 19.05) (xy 17.272 17.907)
			)
		)
	)
	(zone
		(layer "In2.Cu")
		(hatch none 0.5)
		(connect_pads
			(clearance 0)
		)
		(min_thickness 0.25)
		(keepout
			(tracks not_allowed)
			(vias allowed)
			(pads allowed)
			(copperpour not_allowed)
			(footprints allowed)
		)
		(placement
			(enabled no)
			(sheetname "")
		)
		(fill
			(thermal_gap 0.5)
			(thermal_bridge_width 0.5)
			(island_removal_mode 0)
		)
		(polygon
			(pts
				(xy 46.609 6.858) (xy 46.609 7.239) (xy 46.736 7.239) (xy 46.736 6.858)
			)
		)
	)
	(zone
		(layer "In2.Cu")
		(hatch none 0.5)
		(connect_pads
			(clearance 0)
		)
		(min_thickness 0.25)
		(keepout
			(tracks not_allowed)
			(vias allowed)
			(pads allowed)
			(copperpour not_allowed)
			(footprints allowed)
		)
		(placement
			(enabled no)
			(sheetname "")
		)
		(fill
			(thermal_gap 0.5)
			(thermal_bridge_width 0.5)
			(island_removal_mode 0)
		)
		(polygon
			(pts
				(xy 56.007 6.858) (xy 56.007 7.239) (xy 56.134 7.239) (xy 56.134 6.858)
			)
		)
	)
	(zone
		(layer "In2.Cu")
		(hatch none 0.5)
		(connect_pads
			(clearance 0)
		)
		(min_thickness 0.25)
		(keepout
			(tracks not_allowed)
			(vias allowed)
			(pads allowed)
			(copperpour not_allowed)
			(footprints allowed)
		)
		(placement
			(enabled no)
			(sheetname "")
		)
		(fill
			(thermal_gap 0.5)
			(thermal_bridge_width 0.5)
			(island_removal_mode 0)
		)
		(polygon
			(pts
				(xy 8.89 14.986) (xy 8.89 15.367) (xy 9.017 15.367) (xy 9.017 14.986)
			)
		)
	)
	(zone
		(layer "In2.Cu")
		(hatch none 0.5)
		(connect_pads
			(clearance 0)
		)
		(min_thickness 0.25)
		(keepout
			(tracks not_allowed)
			(vias allowed)
			(pads allowed)
			(copperpour not_allowed)
			(footprints allowed)
		)
		(placement
			(enabled no)
			(sheetname "")
		)
		(fill
			(thermal_gap 0.5)
			(thermal_bridge_width 0.5)
			(island_removal_mode 0)
		)
		(polygon
			(pts
				(xy 7.747 17.653) (xy 7.747 18.034) (xy 7.874 18.034) (xy 7.874 17.653)
			)
		)
	)
	(zone
		(layer "In2.Cu")
		(hatch none 0.5)
		(connect_pads
			(clearance 0)
		)
		(min_thickness 0.25)
		(keepout
			(tracks not_allowed)
			(vias allowed)
			(pads allowed)
			(copperpour not_allowed)
			(footprints allowed)
		)
		(placement
			(enabled no)
			(sheetname "")
		)
		(fill
			(thermal_gap 0.5)
			(thermal_bridge_width 0.5)
			(island_removal_mode 0)
		)
		(polygon
			(pts
				(xy 53.721 5.842) (xy 53.721 6.223) (xy 53.848 6.223) (xy 53.848 5.842)
			)
		)
	)
	(zone
		(layer "In2.Cu")
		(hatch none 0.5)
		(connect_pads
			(clearance 0)
		)
		(min_thickness 0.25)
		(keepout
			(tracks not_allowed)
			(vias allowed)
			(pads allowed)
			(copperpour not_allowed)
			(footprints allowed)
		)
		(placement
			(enabled no)
			(sheetname "")
		)
		(fill
			(thermal_gap 0.5)
			(thermal_bridge_width 0.5)
			(island_removal_mode 0)
		)
		(polygon
			(pts
				(xy 15.367 12.446) (xy 15.367 12.827) (xy 15.494 12.827) (xy 15.494 12.446)
			)
		)
	)
	(zone
		(layer "In2.Cu")
		(hatch none 0.5)
		(connect_pads
			(clearance 0)
		)
		(min_thickness 0.25)
		(keepout
			(tracks not_allowed)
			(vias allowed)
			(pads allowed)
			(copperpour not_allowed)
			(footprints allowed)
		)
		(placement
			(enabled no)
			(sheetname "")
		)
		(fill
			(thermal_gap 0.5)
			(thermal_bridge_width 0.5)
			(island_removal_mode 0)
		)
		(polygon
			(pts
				(xy 16.637 4.826) (xy 16.637 5.207) (xy 16.764 5.207) (xy 16.764 4.826)
			)
		)
	)
	(zone
		(layer "In2.Cu")
		(hatch none 0.5)
		(connect_pads
			(clearance 0)
		)
		(min_thickness 0.25)
		(keepout
			(tracks not_allowed)
			(vias allowed)
			(pads allowed)
			(copperpour not_allowed)
			(footprints allowed)
		)
		(placement
			(enabled no)
			(sheetname "")
		)
		(fill
			(thermal_gap 0.5)
			(thermal_bridge_width 0.5)
			(island_removal_mode 0)
		)
		(polygon
			(pts
				(xy 43.688 2.794) (xy 43.688 3.175) (xy 43.815 3.175) (xy 43.815 2.794)
			)
		)
	)
	(zone
		(layer "In2.Cu")
		(hatch none 0.5)
		(connect_pads
			(clearance 0)
		)
		(min_thickness 0.25)
		(keepout
			(tracks allowed)
			(vias allowed)
			(pads allowed)
			(copperpour allowed)
			(footprints allowed)
		)
		(placement
			(enabled no)
			(sheetname "")
		)
		(fill
			(thermal_gap 0.5)
			(thermal_bridge_width 0.5)
			(island_removal_mode 0)
		)
		(polygon
			(pts
				(xy 41.737026 -1.957959) (xy 41.737026 1.042035) (xy 56.736996 1.042035) (xy 56.736996 -1.957959)
			)
		)
	)
	(zone
		(layer "In2.Cu")
		(hatch none 0.5)
		(connect_pads
			(clearance 0)
		)
		(min_thickness 0.25)
		(keepout
			(tracks not_allowed)
			(vias allowed)
			(pads allowed)
			(copperpour not_allowed)
			(footprints allowed)
		)
		(placement
			(enabled no)
			(sheetname "")
		)
		(fill
			(thermal_gap 0.5)
			(thermal_bridge_width 0.5)
			(island_removal_mode 0)
		)
		(polygon
			(pts
				(xy 44.704 6.858) (xy 44.704 7.239) (xy 44.831 7.239) (xy 44.831 6.858)
			)
		)
	)
	(zone
		(layer "In2.Cu")
		(hatch none 0.5)
		(connect_pads
			(clearance 0)
		)
		(min_thickness 0.25)
		(keepout
			(tracks not_allowed)
			(vias allowed)
			(pads allowed)
			(copperpour not_allowed)
			(footprints allowed)
		)
		(placement
			(enabled no)
			(sheetname "")
		)
		(fill
			(thermal_gap 0.5)
			(thermal_bridge_width 0.5)
			(island_removal_mode 0)
		)
		(polygon
			(pts
				(xy 13.081 12.573) (xy 13.081 12.954) (xy 13.208 12.954) (xy 13.208 12.573)
			)
		)
	)
	(zone
		(layer "In2.Cu")
		(hatch none 0.5)
		(connect_pads
			(clearance 0)
		)
		(min_thickness 0.25)
		(keepout
			(tracks not_allowed)
			(vias allowed)
			(pads allowed)
			(copperpour not_allowed)
			(footprints allowed)
		)
		(placement
			(enabled no)
			(sheetname "")
		)
		(fill
			(thermal_gap 0.5)
			(thermal_bridge_width 0.5)
			(island_removal_mode 0)
		)
		(polygon
			(pts
				(xy 59.69 6.985) (xy 59.69 7.239) (xy 59.817 7.239) (xy 59.817 6.985)
			)
		)
	)
	(zone
		(layer "In2.Cu")
		(hatch none 0.5)
		(connect_pads
			(clearance 0)
		)
		(min_thickness 0.25)
		(keepout
			(tracks not_allowed)
			(vias allowed)
			(pads allowed)
			(copperpour not_allowed)
			(footprints allowed)
		)
		(placement
			(enabled no)
			(sheetname "")
		)
		(fill
			(thermal_gap 0.5)
			(thermal_bridge_width 0.5)
			(island_removal_mode 0)
		)
		(polygon
			(pts
				(xy 7.747 22.606) (xy 7.747 22.987) (xy 7.874 22.987) (xy 7.874 22.606)
			)
		)
	)
	(zone
		(layer "In2.Cu")
		(hatch none 0.5)
		(connect_pads
			(clearance 0)
		)
		(min_thickness 0.25)
		(keepout
			(tracks not_allowed)
			(vias allowed)
			(pads allowed)
			(copperpour not_allowed)
			(footprints allowed)
		)
		(placement
			(enabled no)
			(sheetname "")
		)
		(fill
			(thermal_gap 0.5)
			(thermal_bridge_width 0.5)
			(island_removal_mode 0)
		)
		(polygon
			(pts
				(xy 43.688 5.842) (xy 43.688 6.223) (xy 43.815 6.223) (xy 43.815 5.842)
			)
		)
	)
	(zone
		(layer "In2.Cu")
		(hatch none 0.5)
		(connect_pads
			(clearance 0)
		)
		(min_thickness 0.25)
		(keepout
			(tracks not_allowed)
			(vias allowed)
			(pads allowed)
			(copperpour not_allowed)
			(footprints allowed)
		)
		(placement
			(enabled no)
			(sheetname "")
		)
		(fill
			(thermal_gap 0.5)
			(thermal_bridge_width 0.5)
			(island_removal_mode 0)
		)
		(polygon
			(pts
				(xy 50.673 6.858) (xy 50.673 7.239) (xy 50.8 7.239) (xy 50.8 6.858)
			)
		)
	)
	(zone
		(layer "In2.Cu")
		(hatch none 0.5)
		(connect_pads
			(clearance 0)
		)
		(min_thickness 0.25)
		(keepout
			(tracks allowed)
			(vias allowed)
			(pads allowed)
			(copperpour allowed)
			(footprints allowed)
		)
		(placement
			(enabled no)
			(sheetname "")
		)
		(fill
			(thermal_gap 0.5)
			(thermal_bridge_width 0.5)
			(island_removal_mode 0)
		)
		(polygon
			(pts
				(xy 12.573 16.764) (xy 12.573 17.907) (xy 14.859 17.907) (xy 14.859 16.764)
			)
		)
	)
	(zone
		(net "VDD_CORE")
		(layer "In2.Cu")
		(hatch none 0.5)
		(connect_pads
			(clearance 0.5)
		)
		(min_thickness 0.25)
		(fill yes
			(thermal_gap 0.5)
			(thermal_bridge_width 0.5)
			(island_removal_mode 0)
		)
		(polygon
			(pts
				(xy 39.497 23.241) (xy 47.371 23.241) (xy 48.006 23.876) (xy 48.006 27.813) (xy 47.625 28.194) (xy 42.672 28.194)
				(xy 42.164 27.686) (xy 42.164 27.432) (xy 41.91 27.178) (xy 39.751 27.178) (xy 39.243 26.797) (xy 39.243 23.495)
			)
		)
	)
	(zone
		(layer "In2.Cu")
		(hatch none 0.5)
		(connect_pads
			(clearance 0)
		)
		(min_thickness 0.25)
		(keepout
			(tracks allowed)
			(vias allowed)
			(pads allowed)
			(copperpour allowed)
			(footprints allowed)
		)
		(placement
			(enabled no)
			(sheetname "")
		)
		(fill
			(thermal_gap 0.5)
			(thermal_bridge_width 0.5)
			(island_removal_mode 0)
		)
		(polygon
			(pts
				(xy 17.145 22.225) (xy 19.431 22.225) (xy 19.558 22.352) (xy 25.4 22.352) (xy 25.4 21.59) (xy 19.431 21.59)
				(xy 19.431 21.082) (xy 17.653 21.082) (xy 17.653 20.828) (xy 16.51 19.685) (xy 13.589 19.685) (xy 13.589 20.447)
				(xy 15.367 22.225)
			)
		)
	)
	(zone
		(layer "In2.Cu")
		(hatch none 0.5)
		(connect_pads
			(clearance 0)
		)
		(min_thickness 0.25)
		(keepout
			(tracks not_allowed)
			(vias allowed)
			(pads allowed)
			(copperpour not_allowed)
			(footprints allowed)
		)
		(placement
			(enabled no)
			(sheetname "")
		)
		(fill
			(thermal_gap 0.5)
			(thermal_bridge_width 0.5)
			(island_removal_mode 0)
		)
		(polygon
			(pts
				(xy 16.383 14.986) (xy 16.383 15.367) (xy 16.51 15.367) (xy 16.51 14.986)
			)
		)
	)
	(zone
		(layer "In2.Cu")
		(hatch none 0.5)
		(connect_pads
			(clearance 0)
		)
		(min_thickness 0.25)
		(keepout
			(tracks allowed)
			(vias allowed)
			(pads allowed)
			(copperpour allowed)
			(footprints allowed)
		)
		(placement
			(enabled no)
			(sheetname "")
		)
		(fill
			(thermal_gap 0.5)
			(thermal_bridge_width 0.5)
			(island_removal_mode 0)
		)
		(polygon
			(pts
				(xy 31.242 11.176) (xy 31.242 11.938) (xy 34.925 11.938) (xy 34.925 11.176)
			)
		)
	)
	(zone
		(layer "In2.Cu")
		(hatch none 0.5)
		(connect_pads
			(clearance 0)
		)
		(min_thickness 0.25)
		(keepout
			(tracks not_allowed)
			(vias allowed)
			(pads allowed)
			(copperpour not_allowed)
			(footprints allowed)
		)
		(placement
			(enabled no)
			(sheetname "")
		)
		(fill
			(thermal_gap 0.5)
			(thermal_bridge_width 0.5)
			(island_removal_mode 0)
		)
		(polygon
			(pts
				(xy 45.72 5.842) (xy 45.72 6.223) (xy 45.847 6.223) (xy 45.847 5.842)
			)
		)
	)
	(zone
		(net "VDD_1.8V")
		(layer "In2.Cu")
		(hatch none 0.5)
		(connect_pads
			(clearance 0.5)
		)
		(min_thickness 0.25)
		(fill yes
			(thermal_gap 0.5)
			(thermal_bridge_width 0.5)
			(island_removal_mode 0)
		)
		(polygon
			(pts
				(xy 14.73708 45.541946) (xy 18.737072 45.541946) (xy 18.737072 47.041943) (xy 17.737074 48.041941)
				(xy 7.237095 48.041941) (xy 6.237097 47.041943) (xy 6.237097 39.041959) (xy 4.237101 37.041963)
				(xy -1.762887 37.041963) (xy -1.762887 34.041969) (xy -0.26289 34.041969) (xy -0.26289 35.541966)
				(xy 0.237109 36.041965) (xy 6.196965 36.041965) (xy 8.255 38.1) (xy 8.255 46.355) (xy 14.73708 46.355)
			)
		)
	)
	(zone
		(layer "In2.Cu")
		(hatch none 0.5)
		(connect_pads
			(clearance 0)
		)
		(min_thickness 0.25)
		(keepout
			(tracks allowed)
			(vias allowed)
			(pads allowed)
			(copperpour allowed)
			(footprints allowed)
		)
		(placement
			(enabled no)
			(sheetname "")
		)
		(fill
			(thermal_gap 0.5)
			(thermal_bridge_width 0.5)
			(island_removal_mode 0)
		)
		(polygon
			(pts
				(xy 6.477 13.462) (xy 6.477 17.526) (xy 13.335 17.526) (xy 13.335 13.462)
			)
		)
	)
	(zone
		(layer "In2.Cu")
		(hatch none 0.5)
		(connect_pads
			(clearance 0)
		)
		(min_thickness 0.25)
		(keepout
			(tracks not_allowed)
			(vias allowed)
			(pads allowed)
			(copperpour not_allowed)
			(footprints allowed)
		)
		(placement
			(enabled no)
			(sheetname "")
		)
		(fill
			(thermal_gap 0.5)
			(thermal_bridge_width 0.5)
			(island_removal_mode 0)
		)
		(polygon
			(pts
				(xy 46.609 3.81) (xy 46.609 4.191) (xy 46.736 4.191) (xy 46.736 3.81)
			)
		)
	)
	(zone
		(layer "In2.Cu")
		(hatch none 0.5)
		(connect_pads
			(clearance 0)
		)
		(min_thickness 0.25)
		(keepout
			(tracks not_allowed)
			(vias allowed)
			(pads allowed)
			(copperpour not_allowed)
			(footprints allowed)
		)
		(placement
			(enabled no)
			(sheetname "")
		)
		(fill
			(thermal_gap 0.5)
			(thermal_bridge_width 0.5)
			(island_removal_mode 0)
		)
		(polygon
			(pts
				(xy 9.017 25.146) (xy 9.017 25.527) (xy 9.144 25.527) (xy 9.144 25.146)
			)
		)
	)
	(zone
		(layer "In2.Cu")
		(hatch none 0.5)
		(connect_pads
			(clearance 0)
		)
		(min_thickness 0.25)
		(keepout
			(tracks not_allowed)
			(vias allowed)
			(pads allowed)
			(copperpour not_allowed)
			(footprints allowed)
		)
		(placement
			(enabled no)
			(sheetname "")
		)
		(fill
			(thermal_gap 0.5)
			(thermal_bridge_width 0.5)
			(island_removal_mode 0)
		)
		(polygon
			(pts
				(xy 12.827 17.526) (xy 12.827 17.907) (xy 12.954 17.907) (xy 12.954 17.526)
			)
		)
	)
	(zone
		(layer "In2.Cu")
		(hatch none 0.5)
		(connect_pads
			(clearance 0)
		)
		(min_thickness 0.25)
		(keepout
			(tracks not_allowed)
			(vias allowed)
			(pads allowed)
			(copperpour not_allowed)
			(footprints allowed)
		)
		(placement
			(enabled no)
			(sheetname "")
		)
		(fill
			(thermal_gap 0.5)
			(thermal_bridge_width 0.5)
			(island_removal_mode 0)
		)
		(polygon
			(pts
				(xy 10.287 22.733) (xy 10.287 23.114) (xy 10.414 23.114) (xy 10.414 22.733)
			)
		)
	)
	(zone
		(layer "In2.Cu")
		(hatch none 0.5)
		(connect_pads
			(clearance 0)
		)
		(min_thickness 0.25)
		(keepout
			(tracks not_allowed)
			(vias allowed)
			(pads allowed)
			(copperpour not_allowed)
			(footprints allowed)
		)
		(placement
			(enabled no)
			(sheetname "")
		)
		(fill
			(thermal_gap 0.5)
			(thermal_bridge_width 0.5)
			(island_removal_mode 0)
		)
		(polygon
			(pts
				(xy 15.367 22.606) (xy 15.367 22.987) (xy 15.494 22.987) (xy 15.494 22.606)
			)
		)
	)
	(zone
		(layer "In2.Cu")
		(hatch none 0.5)
		(connect_pads
			(clearance 0)
		)
		(min_thickness 0.25)
		(keepout
			(tracks not_allowed)
			(vias allowed)
			(pads allowed)
			(copperpour not_allowed)
			(footprints allowed)
		)
		(placement
			(enabled no)
			(sheetname "")
		)
		(fill
			(thermal_gap 0.5)
			(thermal_bridge_width 0.5)
			(island_removal_mode 0)
		)
		(polygon
			(pts
				(xy 57.658 6.858) (xy 57.658 7.239) (xy 57.785 7.239) (xy 57.785 6.858)
			)
		)
	)
	(zone
		(layer "In2.Cu")
		(hatch none 0.5)
		(connect_pads
			(clearance 0)
		)
		(min_thickness 0.25)
		(keepout
			(tracks not_allowed)
			(vias allowed)
			(pads allowed)
			(copperpour not_allowed)
			(footprints allowed)
		)
		(placement
			(enabled no)
			(sheetname "")
		)
		(fill
			(thermal_gap 0.5)
			(thermal_bridge_width 0.5)
			(island_removal_mode 0)
		)
		(polygon
			(pts
				(xy 14.605 20.955) (xy 14.986 20.955) (xy 14.986 20.828) (xy 14.605 20.828)
			)
		)
	)
	(zone
		(layer "In2.Cu")
		(hatch none 0.5)
		(connect_pads
			(clearance 0)
		)
		(min_thickness 0.25)
		(keepout
			(tracks not_allowed)
			(vias allowed)
			(pads allowed)
			(copperpour not_allowed)
			(footprints allowed)
		)
		(placement
			(enabled no)
			(sheetname "")
		)
		(fill
			(thermal_gap 0.5)
			(thermal_bridge_width 0.5)
			(island_removal_mode 0)
		)
		(polygon
			(pts
				(xy 11.557 25.146) (xy 11.557 25.527) (xy 11.684 25.527) (xy 11.684 25.146)
			)
		)
	)
	(zone
		(layer "In2.Cu")
		(hatch none 0.5)
		(connect_pads
			(clearance 0)
		)
		(min_thickness 0.25)
		(keepout
			(tracks not_allowed)
			(vias allowed)
			(pads allowed)
			(copperpour not_allowed)
			(footprints allowed)
		)
		(placement
			(enabled no)
			(sheetname "")
		)
		(fill
			(thermal_gap 0.5)
			(thermal_bridge_width 0.5)
			(island_removal_mode 0)
		)
		(polygon
			(pts
				(xy 52.578 3.81) (xy 52.578 4.191) (xy 52.705 4.191) (xy 52.705 3.81)
			)
		)
	)
	(zone
		(layer "In2.Cu")
		(hatch none 0.5)
		(connect_pads
			(clearance 0)
		)
		(min_thickness 0.25)
		(keepout
			(tracks not_allowed)
			(vias allowed)
			(pads allowed)
			(copperpour not_allowed)
			(footprints allowed)
		)
		(placement
			(enabled no)
			(sheetname "")
		)
		(fill
			(thermal_gap 0.5)
			(thermal_bridge_width 0.5)
			(island_removal_mode 0)
		)
		(polygon
			(pts
				(xy 52.832 6.858) (xy 52.832 7.239) (xy 52.959 7.239) (xy 52.959 6.858)
			)
		)
	)
	(zone
		(layer "In2.Cu")
		(hatch none 0.5)
		(connect_pads
			(clearance 0)
		)
		(min_thickness 0.25)
		(keepout
			(tracks not_allowed)
			(vias allowed)
			(pads allowed)
			(copperpour not_allowed)
			(footprints allowed)
		)
		(placement
			(enabled no)
			(sheetname "")
		)
		(fill
			(thermal_gap 0.5)
			(thermal_bridge_width 0.5)
			(island_removal_mode 0)
		)
		(polygon
			(pts
				(xy 7.747 7.366) (xy 7.747 7.747) (xy 7.874 7.747) (xy 7.874 7.366)
			)
		)
	)
	(zone
		(layer "In2.Cu")
		(hatch none 0.5)
		(connect_pads
			(clearance 0)
		)
		(min_thickness 0.25)
		(keepout
			(tracks not_allowed)
			(vias allowed)
			(pads allowed)
			(copperpour not_allowed)
			(footprints allowed)
		)
		(placement
			(enabled no)
			(sheetname "")
		)
		(fill
			(thermal_gap 0.5)
			(thermal_bridge_width 0.5)
			(island_removal_mode 0)
		)
		(polygon
			(pts
				(xy 59.69 3.81) (xy 59.69 4.191) (xy 59.817 4.191) (xy 59.817 3.81)
			)
		)
	)
	(zone
		(layer "In2.Cu")
		(hatch none 0.5)
		(connect_pads
			(clearance 0)
		)
		(min_thickness 0.25)
		(keepout
			(tracks allowed)
			(vias allowed)
			(pads allowed)
			(copperpour allowed)
			(footprints allowed)
		)
		(placement
			(enabled no)
			(sheetname "")
		)
		(fill
			(thermal_gap 0.5)
			(thermal_bridge_width 0.5)
			(island_removal_mode 0)
		)
		(polygon
			(pts
				(xy 32.258 17.653) (xy 32.258 18.415) (xy 34.925 18.415) (xy 34.925 17.653)
			)
		)
	)
	(zone
		(layer "In3.Cu")
		(hatch none 0.5)
		(connect_pads
			(clearance 0)
		)
		(min_thickness 0.25)
		(keepout
			(tracks allowed)
			(vias allowed)
			(pads allowed)
			(copperpour allowed)
			(footprints allowed)
		)
		(placement
			(enabled no)
			(sheetname "")
		)
		(fill
			(thermal_gap 0.5)
			(thermal_bridge_width 0.5)
			(island_removal_mode 0)
		)
		(polygon
			(pts
				(xy 27.813 9.906) (xy 27.813 11.938) (xy 28.829 11.938) (xy 28.829 9.906)
			)
		)
	)
	(zone
		(layer "In3.Cu")
		(hatch none 0.5)
		(connect_pads
			(clearance 0)
		)
		(min_thickness 0.25)
		(keepout
			(tracks not_allowed)
			(vias allowed)
			(pads allowed)
			(copperpour not_allowed)
			(footprints allowed)
		)
		(placement
			(enabled no)
			(sheetname "")
		)
		(fill
			(thermal_gap 0.5)
			(thermal_bridge_width 0.5)
			(island_removal_mode 0)
		)
		(polygon
			(pts
				(xy 14.224 15.367) (xy 14.351 15.367) (xy 14.351 14.986) (xy 14.224 14.986)
			)
		)
	)
	(zone
		(layer "In3.Cu")
		(hatch none 0.5)
		(connect_pads
			(clearance 0)
		)
		(min_thickness 0.25)
		(keepout
			(tracks not_allowed)
			(vias allowed)
			(pads allowed)
			(copperpour not_allowed)
			(footprints allowed)
		)
		(placement
			(enabled no)
			(sheetname "")
		)
		(fill
			(thermal_gap 0.5)
			(thermal_bridge_width 0.5)
			(island_removal_mode 0)
		)
		(polygon
			(pts
				(xy 12.954 17.907) (xy 13.081 17.907) (xy 13.081 17.526) (xy 12.954 17.526)
			)
		)
	)
	(zone
		(net "VDD_1.2V")
		(layer "In3.Cu")
		(hatch none 0.5)
		(connect_pads
			(clearance 0.5)
		)
		(min_thickness 0.25)
		(fill yes
			(thermal_gap 0.5)
			(thermal_bridge_width 0.5)
			(island_removal_mode 0)
		)
		(polygon
			(pts
				(xy 8.128 35.941) (xy 8.128 32.512) (xy 9.525 31.115) (xy 36.576 31.115) (xy 36.576 33.274) (xy 14.351 33.274)
				(xy 11.684 35.941)
			)
		)
	)
	(zone
		(net "VDDA_DDR0_32A")
		(layer "In3.Cu")
		(hatch none 0.5)
		(connect_pads
			(clearance 0.5)
		)
		(min_thickness 0.25)
		(fill yes
			(thermal_gap 0.5)
			(thermal_bridge_width 0.5)
			(island_removal_mode 0)
		)
		(polygon
			(pts
				(xy 60.736988 11.042015) (xy 60.736988 14.542008) (xy 62.736984 16.542004) (xy 62.736984 18.670016)
				(xy 61.365003 20.041997) (xy 52.737004 20.041997) (xy 52.737004 22.041993) (xy 64.236981 22.041993)
				(xy 64.236981 12.042013) (xy 63.236983 11.042015)
			)
		)
	)
	(zone
		(net "VDDA_PLL")
		(layer "In3.Cu")
		(hatch none 0.5)
		(connect_pads
			(clearance 0.5)
		)
		(min_thickness 0.25)
		(fill yes
			(thermal_gap 0.5)
			(thermal_bridge_width 0.5)
			(island_removal_mode 0)
		)
		(polygon
			(pts
				(xy 62.236985 17.042003) (xy 53.721 17.042003) (xy 53.721 11.042015) (xy 51.562 11.042015) (xy 51.562 18.042001)
				(xy 42.737024 18.042001) (xy 42.737024 27.041983) (xy 37.338 27.041983) (xy 37.338 29.041979) (xy 46.237017 29.041979)
				(xy 46.237017 19.541998) (xy 61.230002 19.541998) (xy 62.236985 18.535015)
			)
		)
	)
	(zone
		(layer "In3.Cu")
		(hatch none 0.5)
		(connect_pads
			(clearance 0)
		)
		(min_thickness 0.25)
		(keepout
			(tracks allowed)
			(vias allowed)
			(pads allowed)
			(copperpour allowed)
			(footprints allowed)
		)
		(placement
			(enabled no)
			(sheetname "")
		)
		(fill
			(thermal_gap 0.5)
			(thermal_bridge_width 0.5)
			(island_removal_mode 0)
		)
		(polygon
			(pts
				(xy 27.305 19.304) (xy 29.337 19.304) (xy 29.337 18.288) (xy 27.305 18.288)
			)
		)
	)
	(zone
		(net "EXT_3.3V")
		(layer "In3.Cu")
		(hatch none 0.5)
		(connect_pads
			(clearance 0.5)
		)
		(min_thickness 0.25)
		(fill yes
			(thermal_gap 0.5)
			(thermal_bridge_width 0.5)
			(island_removal_mode 0)
		)
		(polygon
			(pts
				(xy 9.144 45.72) (xy 10.414 45.72) (xy 11.43 46.736) (xy 32.385 46.736) (xy 33.147 47.498) (xy 46.609 47.498)
				(xy 53.721 47.498) (xy 55.245 49.022) (xy 62.357 49.022) (xy 62.357 46.228) (xy 62.865 45.72) (xy 64.897 45.72)
				(xy 65.278 46.101) (xy 65.278 54.737) (xy 65.913 55.372) (xy 74.549 55.372) (xy 85.598 44.323) (xy 85.598 38.735)
				(xy 84.709 37.846) (xy 81.28 37.846) (xy 81.153 37.719) (xy 81.153 37.084) (xy 81.534 36.703) (xy 86.614 36.703)
				(xy 87.122 37.211) (xy 87.122 50.165) (xy 79.883 57.404) (xy 40.767 57.404) (xy 40.132 56.769) (xy 40.132 50.419)
				(xy 38.735 49.022) (xy 28.575 49.022) (xy 28.321 49.276) (xy 26.289 49.276) (xy 25.527 48.514) (xy 9.779 48.514)
				(xy 9.144 47.879)
			)
		)
	)
	(zone
		(layer "In3.Cu")
		(hatch none 0.5)
		(connect_pads
			(clearance 0)
		)
		(min_thickness 0.25)
		(keepout
			(tracks not_allowed)
			(vias allowed)
			(pads allowed)
			(copperpour not_allowed)
			(footprints allowed)
		)
		(placement
			(enabled no)
			(sheetname "")
		)
		(fill
			(thermal_gap 0.5)
			(thermal_bridge_width 0.5)
			(island_removal_mode 0)
		)
		(polygon
			(pts
				(xy 57.658 7.2898) (xy 57.785 7.2898) (xy 57.785 7.1628) (xy 57.658 7.1628)
			)
		)
	)
	(zone
		(layer "In3.Cu")
		(hatch none 0.5)
		(connect_pads
			(clearance 0)
		)
		(min_thickness 0.25)
		(keepout
			(tracks not_allowed)
			(vias allowed)
			(pads allowed)
			(copperpour not_allowed)
			(footprints allowed)
		)
		(placement
			(enabled no)
			(sheetname "")
		)
		(fill
			(thermal_gap 0.5)
			(thermal_bridge_width 0.5)
			(island_removal_mode 0)
		)
		(polygon
			(pts
				(xy 14.986 21.1074) (xy 14.986 20.9804) (xy 14.605 20.9804) (xy 14.605 21.1074)
			)
		)
	)
	(zone
		(layer "In3.Cu")
		(hatch none 0.5)
		(connect_pads
			(clearance 0)
		)
		(min_thickness 0.25)
		(keepout
			(tracks allowed)
			(vias allowed)
			(pads allowed)
			(copperpour allowed)
			(footprints allowed)
		)
		(placement
			(enabled no)
			(sheetname "")
		)
		(fill
			(thermal_gap 0.5)
			(thermal_bridge_width 0.5)
			(island_removal_mode 0)
		)
		(polygon
			(pts
				(xy 32.131 18.542) (xy 34.163 18.542) (xy 34.163 17.526) (xy 32.131 17.526)
			)
		)
	)
	(zone
		(layer "In3.Cu")
		(hatch none 0.5)
		(connect_pads
			(clearance 0)
		)
		(min_thickness 0.25)
		(keepout
			(tracks allowed)
			(vias allowed)
			(pads allowed)
			(copperpour allowed)
			(footprints allowed)
		)
		(placement
			(enabled no)
			(sheetname "")
		)
		(fill
			(thermal_gap 0.5)
			(thermal_bridge_width 0.5)
			(island_removal_mode 0)
		)
		(polygon
			(pts
				(xy 23.114 20.193) (xy 24.384 20.193) (xy 24.384 17.653) (xy 22.352 17.653) (xy 22.352 19.685) (xy 20.828 19.685)
				(xy 19.939 20.574) (xy 19.939 22.098) (xy 20.193 22.352) (xy 21.463 22.352) (xy 22.098 21.717) (xy 22.098 21.209)
			)
		)
	)
	(zone
		(net "MAIN_3.3V")
		(layer "In3.Cu")
		(hatch none 0.5)
		(connect_pads
			(clearance 0.5)
		)
		(min_thickness 0.25)
		(fill yes
			(thermal_gap 0.5)
			(thermal_bridge_width 0.5)
			(island_removal_mode 0)
		)
		(polygon
			(pts
				(xy 12.573 27.432) (xy 14.478 27.432) (xy 14.478 25.781) (xy 12.573 25.781)
			)
		)
	)
	(zone
		(net "VDDA_SERDES")
		(layer "In3.Cu")
		(hatch none 0.5)
		(connect_pads
			(clearance 0.5)
		)
		(min_thickness 0.25)
		(fill yes
			(thermal_gap 0.5)
			(thermal_bridge_width 0.5)
			(island_removal_mode 0)
		)
		(polygon
			(pts
				(xy 54.356 11.811) (xy 54.356 10.795) (xy 46.482 10.795) (xy 46.482 8.255) (xy 55.245 8.255) (xy 55.245 11.811)
			)
		)
	)
	(zone
		(layer "In3.Cu")
		(hatch none 0.5)
		(connect_pads
			(clearance 0)
		)
		(min_thickness 0.25)
		(keepout
			(tracks allowed)
			(vias allowed)
			(pads allowed)
			(copperpour allowed)
			(footprints allowed)
		)
		(placement
			(enabled no)
			(sheetname "")
		)
		(fill
			(thermal_gap 0.5)
			(thermal_bridge_width 0.5)
			(island_removal_mode 0)
		)
		(polygon
			(pts
				(xy 41.737026 -1.957959) (xy 41.737026 1.042035) (xy 64.135 1.042035) (xy 64.135 -1.957959)
			)
		)
	)
	(zone
		(layer "In3.Cu")
		(hatch none 0.5)
		(connect_pads
			(clearance 0)
		)
		(min_thickness 0.25)
		(keepout
			(tracks allowed)
			(vias allowed)
			(pads allowed)
			(copperpour allowed)
			(footprints allowed)
		)
		(placement
			(enabled no)
			(sheetname "")
		)
		(fill
			(thermal_gap 0.5)
			(thermal_bridge_width 0.5)
			(island_removal_mode 0)
		)
		(polygon
			(pts
				(xy 19.812 14.859) (xy 19.812 16.891) (xy 22.987 16.891) (xy 22.987 14.859)
			)
		)
	)
	(zone
		(layer "In3.Cu")
		(hatch none 0.5)
		(connect_pads
			(clearance 0)
		)
		(min_thickness 0.25)
		(keepout
			(tracks allowed)
			(vias allowed)
			(pads allowed)
			(copperpour allowed)
			(footprints allowed)
		)
		(placement
			(enabled no)
			(sheetname "")
		)
		(fill
			(thermal_gap 0.5)
			(thermal_bridge_width 0.5)
			(island_removal_mode 0)
		)
		(polygon
			(pts
				(xy 37.973 17.145) (xy 37.973 19.177) (xy 38.989 19.177) (xy 38.989 17.145)
			)
		)
	)
	(zone
		(layer "In3.Cu")
		(hatch none 0.5)
		(connect_pads
			(clearance 0)
		)
		(min_thickness 0.25)
		(keepout
			(tracks not_allowed)
			(vias allowed)
			(pads allowed)
			(copperpour not_allowed)
			(footprints allowed)
		)
		(placement
			(enabled no)
			(sheetname "")
		)
		(fill
			(thermal_gap 0.5)
			(thermal_bridge_width 0.5)
			(island_removal_mode 0)
		)
		(polygon
			(pts
				(xy 16.764 10.287) (xy 16.891 10.287) (xy 16.891 9.906) (xy 16.764 9.906)
			)
		)
	)
	(zone
		(net "VDD_1.5V")
		(layer "In3.Cu")
		(hatch none 0.5)
		(connect_pads
			(clearance 0.5)
		)
		(min_thickness 0.25)
		(fill yes
			(thermal_gap 0.5)
			(thermal_bridge_width 0.5)
			(island_removal_mode 0)
		)
		(polygon
			(pts
				(xy 38.354 23.876) (xy 38.354 26.67) (xy 38.227 26.797) (xy 37.084 26.797) (xy 37.084 29.083) (xy 39.751 31.75)
				(xy 39.751 36.576) (xy 39.243 37.084) (xy 19.685 37.084) (xy 18.161 38.608) (xy 18.161 43.307) (xy 16.129 45.339)
				(xy 7.62 45.339) (xy 7.112 44.831) (xy 7.112 42.037) (xy 7.366 41.783) (xy 13.589 41.783) (xy 15.875 39.497)
				(xy 15.875 36.957) (xy 18.796 34.036) (xy 35.941 34.036) (xy 36.957 33.02) (xy 36.957 31.115) (xy 35.56 29.718)
				(xy 34.036 29.718) (xy 34.036 23.749) (xy 38.227 23.749)
			)
		)
	)
	(zone
		(net "DDR_1.8V")
		(layer "In3.Cu")
		(hatch none 0.5)
		(connect_pads
			(clearance 0.5)
		)
		(min_thickness 0.25)
		(fill yes
			(thermal_gap 0.5)
			(thermal_bridge_width 0.5)
			(island_removal_mode 0)
		)
		(polygon
			(pts
				(xy 20.574 42.418) (xy 52.959 42.418) (xy 56.642 38.735) (xy 56.642 22.225) (xy 53.237003 22.225)
				(xy 53.237003 36.678997) (xy 49.911 40.005) (xy 33.02 40.005) (xy 31.623 38.608) (xy 24.892 38.608)
				(xy 24.003 39.497) (xy 23.495 40.005) (xy 22.733 40.005) (xy 21.209 38.481) (xy 18.923 38.481) (xy 18.923 40.767)
			)
		)
	)
	(zone
		(layers "In3.Cu" "In6.Cu")
		(hatch none 0.5)
		(connect_pads
			(clearance 0)
		)
		(min_thickness 0.25)
		(keepout
			(tracks not_allowed)
			(vias allowed)
			(pads allowed)
			(copperpour not_allowed)
			(footprints allowed)
		)
		(placement
			(enabled no)
			(sheetname "")
		)
		(fill yes
			(thermal_gap 0.5)
			(thermal_bridge_width 0.5)
			(island_removal_mode 0)
		)
		(polygon
			(pts
				(xy 46.609 4.191) (xy 46.736 4.191) (xy 46.736 3.81) (xy 46.609 3.81)
			)
		)
	)
	(zone
		(layers "In3.Cu" "In6.Cu")
		(hatch none 0.5)
		(connect_pads
			(clearance 0)
		)
		(min_thickness 0.25)
		(keepout
			(tracks not_allowed)
			(vias allowed)
			(pads allowed)
			(copperpour not_allowed)
			(footprints allowed)
		)
		(placement
			(enabled no)
			(sheetname "")
		)
		(fill yes
			(thermal_gap 0.5)
			(thermal_bridge_width 0.5)
			(island_removal_mode 0)
		)
		(polygon
			(pts
				(xy 10.287 23.114) (xy 10.414 23.114) (xy 10.414 22.733) (xy 10.287 22.733)
			)
		)
	)
	(zone
		(layers "In3.Cu" "In6.Cu" "In7.Cu")
		(hatch none 0.5)
		(connect_pads
			(clearance 0)
		)
		(min_thickness 0.25)
		(keepout
			(tracks not_allowed)
			(vias allowed)
			(pads allowed)
			(copperpour not_allowed)
			(footprints allowed)
		)
		(placement
			(enabled no)
			(sheetname "")
		)
		(fill yes
			(thermal_gap 0.5)
			(thermal_bridge_width 0.5)
			(island_removal_mode 0)
		)
		(polygon
			(pts
				(xy 16.637 15.367) (xy 16.764 15.367) (xy 16.764 14.986) (xy 16.637 14.986)
			)
		)
	)
	(zone
		(layers "In3.Cu" "In6.Cu" "In7.Cu")
		(hatch none 0.5)
		(connect_pads
			(clearance 0)
		)
		(min_thickness 0.25)
		(keepout
			(tracks not_allowed)
			(vias allowed)
			(pads allowed)
			(copperpour not_allowed)
			(footprints allowed)
		)
		(placement
			(enabled no)
			(sheetname "")
		)
		(fill yes
			(thermal_gap 0.5)
			(thermal_bridge_width 0.5)
			(island_removal_mode 0)
		)
		(polygon
			(pts
				(xy 17.907 20.447) (xy 18.034 20.447) (xy 18.034 20.066) (xy 17.907 20.066)
			)
		)
	)
	(zone
		(layers "In3.Cu" "In6.Cu" "In7.Cu")
		(hatch none 0.5)
		(connect_pads
			(clearance 0)
		)
		(min_thickness 0.25)
		(keepout
			(tracks not_allowed)
			(vias allowed)
			(pads allowed)
			(copperpour not_allowed)
			(footprints allowed)
		)
		(placement
			(enabled no)
			(sheetname "")
		)
		(fill yes
			(thermal_gap 0.5)
			(thermal_bridge_width 0.5)
			(island_removal_mode 0)
		)
		(polygon
			(pts
				(xy 16.637 17.907) (xy 16.764 17.907) (xy 16.764 17.526) (xy 16.637 17.526)
			)
		)
	)
	(zone
		(layers "In3.Cu" "In6.Cu" "In7.Cu")
		(hatch none 0.5)
		(connect_pads
			(clearance 0)
		)
		(min_thickness 0.25)
		(keepout
			(tracks not_allowed)
			(vias allowed)
			(pads allowed)
			(copperpour not_allowed)
			(footprints allowed)
		)
		(placement
			(enabled no)
			(sheetname "")
		)
		(fill yes
			(thermal_gap 0.5)
			(thermal_bridge_width 0.5)
			(island_removal_mode 0)
		)
		(polygon
			(pts
				(xy 14.097 10.287) (xy 14.224 10.287) (xy 14.224 9.906) (xy 14.097 9.906)
			)
		)
	)
	(zone
		(layers "In3.Cu" "In6.Cu" "In7.Cu")
		(hatch none 0.5)
		(connect_pads
			(clearance 0)
		)
		(min_thickness 0.25)
		(keepout
			(tracks not_allowed)
			(vias allowed)
			(pads allowed)
			(copperpour not_allowed)
			(footprints allowed)
		)
		(placement
			(enabled no)
			(sheetname "")
		)
		(fill yes
			(thermal_gap 0.5)
			(thermal_bridge_width 0.5)
			(island_removal_mode 0)
		)
		(polygon
			(pts
				(xy 9.017 12.827) (xy 9.144 12.827) (xy 9.144 12.446) (xy 9.017 12.446)
			)
		)
	)
	(zone
		(layers "In3.Cu" "In6.Cu" "In7.Cu")
		(hatch none 0.5)
		(connect_pads
			(clearance 0)
		)
		(min_thickness 0.25)
		(keepout
			(tracks not_allowed)
			(vias allowed)
			(pads allowed)
			(copperpour not_allowed)
			(footprints allowed)
		)
		(placement
			(enabled no)
			(sheetname "")
		)
		(fill yes
			(thermal_gap 0.5)
			(thermal_bridge_width 0.5)
			(island_removal_mode 0)
		)
		(polygon
			(pts
				(xy 51.689 6.223) (xy 51.816 6.223) (xy 51.816 5.842) (xy 51.689 5.842)
			)
		)
	)
	(zone
		(layers "In3.Cu" "In6.Cu" "In7.Cu")
		(hatch none 0.5)
		(connect_pads
			(clearance 0)
		)
		(min_thickness 0.25)
		(keepout
			(tracks not_allowed)
			(vias allowed)
			(pads allowed)
			(copperpour not_allowed)
			(footprints allowed)
		)
		(placement
			(enabled no)
			(sheetname "")
		)
		(fill yes
			(thermal_gap 0.5)
			(thermal_bridge_width 0.5)
			(island_removal_mode 0)
		)
		(polygon
			(pts
				(xy 12.827 12.827) (xy 12.954 12.827) (xy 12.954 12.446) (xy 12.827 12.446)
			)
		)
	)
	(zone
		(layers "In3.Cu" "In6.Cu" "In7.Cu")
		(hatch none 0.5)
		(connect_pads
			(clearance 0)
		)
		(min_thickness 0.25)
		(keepout
			(tracks not_allowed)
			(vias allowed)
			(pads allowed)
			(copperpour not_allowed)
			(footprints allowed)
		)
		(placement
			(enabled no)
			(sheetname "")
		)
		(fill yes
			(thermal_gap 0.5)
			(thermal_bridge_width 0.5)
			(island_removal_mode 0)
		)
		(polygon
			(pts
				(xy 45.72 3.175) (xy 45.847 3.175) (xy 45.847 2.794) (xy 45.72 2.794)
			)
		)
	)
	(zone
		(layers "In3.Cu" "In6.Cu" "In7.Cu")
		(hatch none 0.5)
		(connect_pads
			(clearance 0)
		)
		(min_thickness 0.25)
		(keepout
			(tracks not_allowed)
			(vias allowed)
			(pads allowed)
			(copperpour not_allowed)
			(footprints allowed)
		)
		(placement
			(enabled no)
			(sheetname "")
		)
		(fill yes
			(thermal_gap 0.5)
			(thermal_bridge_width 0.5)
			(island_removal_mode 0)
		)
		(polygon
			(pts
				(xy 11.557 25.527) (xy 11.684 25.527) (xy 11.684 25.146) (xy 11.557 25.146)
			)
		)
	)
	(zone
		(layers "In3.Cu" "In6.Cu" "In7.Cu")
		(hatch none 0.5)
		(connect_pads
			(clearance 0)
		)
		(min_thickness 0.25)
		(keepout
			(tracks not_allowed)
			(vias allowed)
			(pads allowed)
			(copperpour not_allowed)
			(footprints allowed)
		)
		(placement
			(enabled no)
			(sheetname "")
		)
		(fill yes
			(thermal_gap 0.5)
			(thermal_bridge_width 0.5)
			(island_removal_mode 0)
		)
		(polygon
			(pts
				(xy 59.69 7.239) (xy 59.817 7.239) (xy 59.817 6.858) (xy 59.69 6.858)
			)
		)
	)
	(zone
		(layers "In3.Cu" "In6.Cu" "In7.Cu")
		(hatch none 0.5)
		(connect_pads
			(clearance 0)
		)
		(min_thickness 0.25)
		(keepout
			(tracks not_allowed)
			(vias allowed)
			(pads allowed)
			(copperpour not_allowed)
			(footprints allowed)
		)
		(placement
			(enabled no)
			(sheetname "")
		)
		(fill yes
			(thermal_gap 0.5)
			(thermal_bridge_width 0.5)
			(island_removal_mode 0)
		)
		(polygon
			(pts
				(xy 50.673 7.239) (xy 50.8 7.239) (xy 50.8 6.858) (xy 50.673 6.858)
			)
		)
	)
	(zone
		(layers "In3.Cu" "In6.Cu" "In7.Cu")
		(hatch none 0.5)
		(connect_pads
			(clearance 0)
		)
		(min_thickness 0.25)
		(keepout
			(tracks not_allowed)
			(vias allowed)
			(pads allowed)
			(copperpour not_allowed)
			(footprints allowed)
		)
		(placement
			(enabled no)
			(sheetname "")
		)
		(fill yes
			(thermal_gap 0.5)
			(thermal_bridge_width 0.5)
			(island_removal_mode 0)
		)
		(polygon
			(pts
				(xy 8.89 10.287) (xy 9.017 10.287) (xy 9.017 9.906) (xy 8.89 9.906)
			)
		)
	)
	(zone
		(layers "In3.Cu" "In6.Cu" "In7.Cu")
		(hatch none 0.5)
		(connect_pads
			(clearance 0)
		)
		(min_thickness 0.25)
		(keepout
			(tracks not_allowed)
			(vias allowed)
			(pads allowed)
			(copperpour not_allowed)
			(footprints allowed)
		)
		(placement
			(enabled no)
			(sheetname "")
		)
		(fill yes
			(thermal_gap 0.5)
			(thermal_bridge_width 0.5)
			(island_removal_mode 0)
		)
		(polygon
			(pts
				(xy 12.827 22.86) (xy 12.954 22.86) (xy 12.954 22.479) (xy 12.827 22.479)
			)
		)
	)
	(zone
		(layers "In3.Cu" "In6.Cu" "In7.Cu")
		(hatch none 0.5)
		(connect_pads
			(clearance 0)
		)
		(min_thickness 0.25)
		(keepout
			(tracks not_allowed)
			(vias allowed)
			(pads allowed)
			(copperpour not_allowed)
			(footprints allowed)
		)
		(placement
			(enabled no)
			(sheetname "")
		)
		(fill yes
			(thermal_gap 0.5)
			(thermal_bridge_width 0.5)
			(island_removal_mode 0)
		)
		(polygon
			(pts
				(xy 43.688 6.223) (xy 43.815 6.223) (xy 43.815 5.842) (xy 43.688 5.842)
			)
		)
	)
	(zone
		(layers "In3.Cu" "In6.Cu" "In7.Cu")
		(hatch none 0.5)
		(connect_pads
			(clearance 0)
		)
		(min_thickness 0.25)
		(keepout
			(tracks not_allowed)
			(vias allowed)
			(pads allowed)
			(copperpour not_allowed)
			(footprints allowed)
		)
		(placement
			(enabled no)
			(sheetname "")
		)
		(fill yes
			(thermal_gap 0.5)
			(thermal_bridge_width 0.5)
			(island_removal_mode 0)
		)
		(polygon
			(pts
				(xy 44.704 4.191) (xy 44.831 4.191) (xy 44.831 3.81) (xy 44.704 3.81)
			)
		)
	)
	(zone
		(layers "In3.Cu" "In6.Cu" "In7.Cu")
		(hatch none 0.5)
		(connect_pads
			(clearance 0)
		)
		(min_thickness 0.25)
		(keepout
			(tracks not_allowed)
			(vias allowed)
			(pads allowed)
			(copperpour not_allowed)
			(footprints allowed)
		)
		(placement
			(enabled no)
			(sheetname "")
		)
		(fill yes
			(thermal_gap 0.5)
			(thermal_bridge_width 0.5)
			(island_removal_mode 0)
		)
		(polygon
			(pts
				(xy 53.721 6.223) (xy 53.848 6.223) (xy 53.848 5.842) (xy 53.721 5.842)
			)
		)
	)
	(zone
		(layers "In3.Cu" "In6.Cu" "In7.Cu")
		(hatch none 0.5)
		(connect_pads
			(clearance 0)
		)
		(min_thickness 0.25)
		(keepout
			(tracks not_allowed)
			(vias allowed)
			(pads allowed)
			(copperpour not_allowed)
			(footprints allowed)
		)
		(placement
			(enabled no)
			(sheetname "")
		)
		(fill yes
			(thermal_gap 0.5)
			(thermal_bridge_width 0.5)
			(island_removal_mode 0)
		)
		(polygon
			(pts
				(xy 56.642 6.223) (xy 56.769 6.223) (xy 56.769 5.842) (xy 56.642 5.842)
			)
		)
	)
	(zone
		(layers "In3.Cu" "In6.Cu" "In7.Cu")
		(hatch none 0.5)
		(connect_pads
			(clearance 0)
		)
		(min_thickness 0.25)
		(keepout
			(tracks not_allowed)
			(vias allowed)
			(pads allowed)
			(copperpour not_allowed)
			(footprints allowed)
		)
		(placement
			(enabled no)
			(sheetname "")
		)
		(fill yes
			(thermal_gap 0.5)
			(thermal_bridge_width 0.5)
			(island_removal_mode 0)
		)
		(polygon
			(pts
				(xy 16.637 5.207) (xy 16.764 5.207) (xy 16.764 4.826) (xy 16.637 4.826)
			)
		)
	)
	(zone
		(layers "In3.Cu" "In6.Cu" "In7.Cu")
		(hatch none 0.5)
		(connect_pads
			(clearance 0)
		)
		(min_thickness 0.25)
		(keepout
			(tracks not_allowed)
			(vias allowed)
			(pads allowed)
			(copperpour not_allowed)
			(footprints allowed)
		)
		(placement
			(enabled no)
			(sheetname "")
		)
		(fill yes
			(thermal_gap 0.5)
			(thermal_bridge_width 0.5)
			(island_removal_mode 0)
		)
		(polygon
			(pts
				(xy 7.747 7.747) (xy 7.874 7.747) (xy 7.874 7.366) (xy 7.747 7.366)
			)
		)
	)
	(zone
		(layers "In3.Cu" "In6.Cu" "In7.Cu")
		(hatch none 0.5)
		(connect_pads
			(clearance 0)
		)
		(min_thickness 0.25)
		(keepout
			(tracks not_allowed)
			(vias allowed)
			(pads allowed)
			(copperpour not_allowed)
			(footprints allowed)
		)
		(placement
			(enabled no)
			(sheetname "")
		)
		(fill yes
			(thermal_gap 0.5)
			(thermal_bridge_width 0.5)
			(island_removal_mode 0)
		)
		(polygon
			(pts
				(xy 12.827 7.747) (xy 12.954 7.747) (xy 12.954 7.366) (xy 12.827 7.366)
			)
		)
	)
	(zone
		(layers "In3.Cu" "In6.Cu" "In7.Cu")
		(hatch none 0.5)
		(connect_pads
			(clearance 0)
		)
		(min_thickness 0.25)
		(keepout
			(tracks not_allowed)
			(vias allowed)
			(pads allowed)
			(copperpour not_allowed)
			(footprints allowed)
		)
		(placement
			(enabled no)
			(sheetname "")
		)
		(fill yes
			(thermal_gap 0.5)
			(thermal_bridge_width 0.5)
			(island_removal_mode 0)
		)
		(polygon
			(pts
				(xy 45.72 6.223) (xy 45.847 6.223) (xy 45.847 5.842) (xy 45.72 5.842)
			)
		)
	)
	(zone
		(layers "In3.Cu" "In6.Cu" "In7.Cu")
		(hatch none 0.5)
		(connect_pads
			(clearance 0)
		)
		(min_thickness 0.25)
		(keepout
			(tracks not_allowed)
			(vias allowed)
			(pads allowed)
			(copperpour not_allowed)
			(footprints allowed)
		)
		(placement
			(enabled no)
			(sheetname "")
		)
		(fill yes
			(thermal_gap 0.5)
			(thermal_bridge_width 0.5)
			(island_removal_mode 0)
		)
		(polygon
			(pts
				(xy 55.753 7.239) (xy 55.88 7.239) (xy 55.88 6.858) (xy 55.753 6.858)
			)
		)
	)
	(zone
		(layers "In3.Cu" "In6.Cu" "In7.Cu")
		(hatch none 0.5)
		(connect_pads
			(clearance 0)
		)
		(min_thickness 0.25)
		(keepout
			(tracks not_allowed)
			(vias allowed)
			(pads allowed)
			(copperpour not_allowed)
			(footprints allowed)
		)
		(placement
			(enabled no)
			(sheetname "")
		)
		(fill yes
			(thermal_gap 0.5)
			(thermal_bridge_width 0.5)
			(island_removal_mode 0)
		)
		(polygon
			(pts
				(xy 50.673 4.191) (xy 50.8 4.191) (xy 50.8 3.81) (xy 50.673 3.81)
			)
		)
	)
	(zone
		(layers "In3.Cu" "In6.Cu" "In7.Cu")
		(hatch none 0.5)
		(connect_pads
			(clearance 0)
		)
		(min_thickness 0.25)
		(keepout
			(tracks not_allowed)
			(vias allowed)
			(pads allowed)
			(copperpour not_allowed)
			(footprints allowed)
		)
		(placement
			(enabled no)
			(sheetname "")
		)
		(fill yes
			(thermal_gap 0.5)
			(thermal_bridge_width 0.5)
			(island_removal_mode 0)
		)
		(polygon
			(pts
				(xy 8.89 15.367) (xy 9.017 15.367) (xy 9.017 14.986) (xy 8.89 14.986)
			)
		)
	)
	(zone
		(layers "In3.Cu" "In6.Cu" "In7.Cu")
		(hatch none 0.5)
		(connect_pads
			(clearance 0)
		)
		(min_thickness 0.25)
		(keepout
			(tracks not_allowed)
			(vias allowed)
			(pads allowed)
			(copperpour not_allowed)
			(footprints allowed)
		)
		(placement
			(enabled no)
			(sheetname "")
		)
		(fill yes
			(thermal_gap 0.5)
			(thermal_bridge_width 0.5)
			(island_removal_mode 0)
		)
		(polygon
			(pts
				(xy 52.705 7.239) (xy 52.832 7.239) (xy 52.832 6.858) (xy 52.705 6.858)
			)
		)
	)
	(zone
		(layers "In3.Cu" "In6.Cu" "In7.Cu")
		(hatch none 0.5)
		(connect_pads
			(clearance 0)
		)
		(min_thickness 0.25)
		(keepout
			(tracks not_allowed)
			(vias allowed)
			(pads allowed)
			(copperpour not_allowed)
			(footprints allowed)
		)
		(placement
			(enabled no)
			(sheetname "")
		)
		(fill yes
			(thermal_gap 0.5)
			(thermal_bridge_width 0.5)
			(island_removal_mode 0)
		)
		(polygon
			(pts
				(xy 7.747 18.034) (xy 7.874 18.034) (xy 7.874 17.653) (xy 7.747 17.653)
			)
		)
	)
	(zone
		(layers "In3.Cu" "In6.Cu" "In7.Cu")
		(hatch none 0.5)
		(connect_pads
			(clearance 0)
		)
		(min_thickness 0.25)
		(keepout
			(tracks not_allowed)
			(vias allowed)
			(pads allowed)
			(copperpour not_allowed)
			(footprints allowed)
		)
		(placement
			(enabled no)
			(sheetname "")
		)
		(fill yes
			(thermal_gap 0.5)
			(thermal_bridge_width 0.5)
			(island_removal_mode 0)
		)
		(polygon
			(pts
				(xy 43.688 3.175) (xy 43.815 3.175) (xy 43.815 2.794) (xy 43.688 2.794)
			)
		)
	)
	(zone
		(layers "In3.Cu" "In6.Cu" "In7.Cu")
		(hatch none 0.5)
		(connect_pads
			(clearance 0)
		)
		(min_thickness 0.25)
		(keepout
			(tracks not_allowed)
			(vias allowed)
			(pads allowed)
			(copperpour not_allowed)
			(footprints allowed)
		)
		(placement
			(enabled no)
			(sheetname "")
		)
		(fill yes
			(thermal_gap 0.5)
			(thermal_bridge_width 0.5)
			(island_removal_mode 0)
		)
		(polygon
			(pts
				(xy 13.97 5.207) (xy 14.097 5.207) (xy 14.097 4.826) (xy 13.97 4.826)
			)
		)
	)
	(zone
		(layers "In3.Cu" "In6.Cu" "In7.Cu")
		(hatch none 0.5)
		(connect_pads
			(clearance 0)
		)
		(min_thickness 0.25)
		(keepout
			(tracks not_allowed)
			(vias allowed)
			(pads allowed)
			(copperpour not_allowed)
			(footprints allowed)
		)
		(placement
			(enabled no)
			(sheetname "")
		)
		(fill yes
			(thermal_gap 0.5)
			(thermal_bridge_width 0.5)
			(island_removal_mode 0)
		)
		(polygon
			(pts
				(xy 15.367 7.747) (xy 15.494 7.747) (xy 15.494 7.366) (xy 15.367 7.366)
			)
		)
	)
	(zone
		(layers "In3.Cu" "In6.Cu" "In7.Cu")
		(hatch none 0.5)
		(connect_pads
			(clearance 0)
		)
		(min_thickness 0.25)
		(keepout
			(tracks not_allowed)
			(vias allowed)
			(pads allowed)
			(copperpour not_allowed)
			(footprints allowed)
		)
		(placement
			(enabled no)
			(sheetname "")
		)
		(fill yes
			(thermal_gap 0.5)
			(thermal_bridge_width 0.5)
			(island_removal_mode 0)
		)
		(polygon
			(pts
				(xy 44.704 7.239) (xy 44.831 7.239) (xy 44.831 6.858) (xy 44.704 6.858)
			)
		)
	)
	(zone
		(layers "In3.Cu" "In6.Cu" "In7.Cu")
		(hatch none 0.5)
		(connect_pads
			(clearance 0)
		)
		(min_thickness 0.25)
		(keepout
			(tracks not_allowed)
			(vias allowed)
			(pads allowed)
			(copperpour not_allowed)
			(footprints allowed)
		)
		(placement
			(enabled no)
			(sheetname "")
		)
		(fill yes
			(thermal_gap 0.5)
			(thermal_bridge_width 0.5)
			(island_removal_mode 0)
		)
		(polygon
			(pts
				(xy 58.674 6.223) (xy 58.801 6.223) (xy 58.801 5.842) (xy 58.674 5.842)
			)
		)
	)
	(zone
		(layers "In3.Cu" "In6.Cu" "In7.Cu")
		(hatch none 0.5)
		(connect_pads
			(clearance 0)
		)
		(min_thickness 0.25)
		(keepout
			(tracks not_allowed)
			(vias allowed)
			(pads allowed)
			(copperpour not_allowed)
			(footprints allowed)
		)
		(placement
			(enabled no)
			(sheetname "")
		)
		(fill yes
			(thermal_gap 0.5)
			(thermal_bridge_width 0.5)
			(island_removal_mode 0)
		)
		(polygon
			(pts
				(xy 15.367 22.987) (xy 15.494 22.987) (xy 15.494 22.606) (xy 15.367 22.606)
			)
		)
	)
	(zone
		(layers "In3.Cu" "In6.Cu" "In7.Cu")
		(hatch none 0.5)
		(connect_pads
			(clearance 0)
		)
		(min_thickness 0.25)
		(keepout
			(tracks not_allowed)
			(vias allowed)
			(pads allowed)
			(copperpour not_allowed)
			(footprints allowed)
		)
		(placement
			(enabled no)
			(sheetname "")
		)
		(fill yes
			(thermal_gap 0.5)
			(thermal_bridge_width 0.5)
			(island_removal_mode 0)
		)
		(polygon
			(pts
				(xy 15.367 12.827) (xy 15.494 12.827) (xy 15.494 12.446) (xy 15.367 12.446)
			)
		)
	)
	(zone
		(layers "In3.Cu" "In7.Cu")
		(hatch none 0.5)
		(connect_pads
			(clearance 0)
		)
		(min_thickness 0.25)
		(keepout
			(tracks not_allowed)
			(vias allowed)
			(pads allowed)
			(copperpour not_allowed)
			(footprints allowed)
		)
		(placement
			(enabled no)
			(sheetname "")
		)
		(fill yes
			(thermal_gap 0.5)
			(thermal_bridge_width 0.5)
			(island_removal_mode 0)
		)
		(polygon
			(pts
				(xy 52.578 4.191) (xy 52.705 4.191) (xy 52.705 3.81) (xy 52.578 3.81)
			)
		)
	)
	(zone
		(layers "In3.Cu" "In7.Cu")
		(hatch none 0.5)
		(connect_pads
			(clearance 0)
		)
		(min_thickness 0.25)
		(keepout
			(tracks not_allowed)
			(vias allowed)
			(pads allowed)
			(copperpour not_allowed)
			(footprints allowed)
		)
		(placement
			(enabled no)
			(sheetname "")
		)
		(fill yes
			(thermal_gap 0.5)
			(thermal_bridge_width 0.5)
			(island_removal_mode 0)
		)
		(polygon
			(pts
				(xy 46.609 7.239) (xy 46.736 7.239) (xy 46.736 6.858) (xy 46.609 6.858)
			)
		)
	)
	(zone
		(layers "In3.Cu" "In7.Cu")
		(hatch none 0.5)
		(connect_pads
			(clearance 0)
		)
		(min_thickness 0.25)
		(keepout
			(tracks not_allowed)
			(vias allowed)
			(pads allowed)
			(copperpour not_allowed)
			(footprints allowed)
		)
		(placement
			(enabled no)
			(sheetname "")
		)
		(fill yes
			(thermal_gap 0.5)
			(thermal_bridge_width 0.5)
			(island_removal_mode 0)
		)
		(polygon
			(pts
				(xy 59.69 4.191) (xy 59.817 4.191) (xy 59.817 3.81) (xy 59.69 3.81)
			)
		)
	)
	(zone
		(layers "In3.Cu" "In7.Cu")
		(hatch none 0.5)
		(connect_pads
			(clearance 0)
		)
		(min_thickness 0.25)
		(keepout
			(tracks not_allowed)
			(vias allowed)
			(pads allowed)
			(copperpour not_allowed)
			(footprints allowed)
		)
		(placement
			(enabled no)
			(sheetname "")
		)
		(fill yes
			(thermal_gap 0.5)
			(thermal_bridge_width 0.5)
			(island_removal_mode 0)
		)
		(polygon
			(pts
				(xy 9.017 20.447) (xy 9.144 20.447) (xy 9.144 20.066) (xy 9.017 20.066)
			)
		)
	)
	(zone
		(layers "In3.Cu" "In7.Cu")
		(hatch none 0.5)
		(connect_pads
			(clearance 0)
		)
		(min_thickness 0.25)
		(keepout
			(tracks not_allowed)
			(vias allowed)
			(pads allowed)
			(copperpour not_allowed)
			(footprints allowed)
		)
		(placement
			(enabled no)
			(sheetname "")
		)
		(fill yes
			(thermal_gap 0.5)
			(thermal_bridge_width 0.5)
			(island_removal_mode 0)
		)
		(polygon
			(pts
				(xy 7.747 22.987) (xy 7.874 22.987) (xy 7.874 22.606) (xy 7.747 22.606)
			)
		)
	)
	(zone
		(layers "In3.Cu" "In7.Cu")
		(hatch none 0.5)
		(connect_pads
			(clearance 0)
		)
		(min_thickness 0.25)
		(keepout
			(tracks not_allowed)
			(vias allowed)
			(pads allowed)
			(copperpour not_allowed)
			(footprints allowed)
		)
		(placement
			(enabled no)
			(sheetname "")
		)
		(fill yes
			(thermal_gap 0.5)
			(thermal_bridge_width 0.5)
			(island_removal_mode 0)
		)
		(polygon
			(pts
				(xy 56.642 4.191) (xy 56.769 4.191) (xy 56.769 3.81) (xy 56.642 3.81)
			)
		)
	)
	(zone
		(layers "In3.Cu" "In7.Cu")
		(hatch none 0.5)
		(connect_pads
			(clearance 0)
		)
		(min_thickness 0.25)
		(keepout
			(tracks not_allowed)
			(vias allowed)
			(pads allowed)
			(copperpour not_allowed)
			(footprints allowed)
		)
		(placement
			(enabled no)
			(sheetname "")
		)
		(fill yes
			(thermal_gap 0.5)
			(thermal_bridge_width 0.5)
			(island_removal_mode 0)
		)
		(polygon
			(pts
				(xy 54.737 4.191) (xy 54.864 4.191) (xy 54.864 3.81) (xy 54.737 3.81)
			)
		)
	)
	(zone
		(layers "In3.Cu" "In7.Cu")
		(hatch none 0.5)
		(connect_pads
			(clearance 0)
		)
		(min_thickness 0.25)
		(keepout
			(tracks not_allowed)
			(vias allowed)
			(pads allowed)
			(copperpour not_allowed)
			(footprints allowed)
		)
		(placement
			(enabled no)
			(sheetname "")
		)
		(fill yes
			(thermal_gap 0.5)
			(thermal_bridge_width 0.5)
			(island_removal_mode 0)
		)
		(polygon
			(pts
				(xy 9.017 25.527) (xy 9.144 25.527) (xy 9.144 25.146) (xy 9.017 25.146)
			)
		)
	)
	(zone
		(net "GND")
		(layer "In4.Cu")
		(hatch none 0.5)
		(connect_pads
			(clearance 0.5)
		)
		(min_thickness 0.25)
		(fill yes
			(thermal_gap 0.5)
			(thermal_bridge_width 0.5)
			(island_removal_mode 0)
		)
		(polygon
			(pts
				(xy 39.1382 57.824776)
				(arc
					(start 39.1382 51.325018)
					(mid 38.552378 49.910742)
					(end 37.138102 49.32492)
				)
				(xy 6.138012 49.32492)
				(arc
					(start 6.138012 39.824914)
					(mid 5.552197 38.410631)
					(end 4.137914 37.824816)
				)
				(xy -2.161946 37.824816) (xy -2.161946 -0.124054) (xy -0.127 -2.159) (xy -0.127 -2.1749) (xy 87.1379 -2.1749)
				(xy 87.1379 55.88) (xy 85.193124 57.824776)
			)
		)
		(polygon
			(pts
				(arc
					(start 35.306 38.510972)
					(mid 35.306 37.943028)
					(end 35.306 38.510972)
				)
			)
		)
		(polygon
			(pts
				(xy 63.204115 1.604721) (xy 62.230406 1.604721) (xy 62.230406 0.853796) (xy 63.204115 0.853796)
			)
		)
		(polygon
			(pts
				(xy 63.183465 0.717652) (xy 62.238661 0.717652) (xy 62.238661 -0.029134) (xy 63.183465 -0.029134)
			)
		)
		(polygon
			(pts
				(xy 61.211333 1.600581) (xy 60.324289 1.600581) (xy 60.324289 0.849681) (xy 61.211333 0.849681)
			)
		)
		(polygon
			(pts
				(xy 61.198963 0.717652) (xy 60.361398 0.717652) (xy 60.361398 -0.029108) (xy 61.198963 -0.029108)
			)
		)
		(polygon
			(pts
				(xy 59.33821 1.604721) (xy 58.414006 1.604721) (xy 58.414006 0.849681) (xy 59.33821 0.849681)
			)
		)
		(polygon
			(pts
				(xy 59.36709 0.701167) (xy 58.393381 0.701167) (xy 58.393381 -0.037363) (xy 59.36709 -0.037363)
			)
		)
		(polygon
			(pts
				(xy 57.399072 1.600581) (xy 56.388229 1.600581) (xy 56.388229 0.833171) (xy 57.399072 0.833171)
			)
		)
		(polygon
			(pts
				(xy 57.386677 0.713537) (xy 56.400598 0.713537) (xy 56.400598 -0.041504) (xy 57.386677 -0.041504)
			)
		)
		(polygon
			(pts
				(xy 55.43517 1.600581) (xy 54.494481 1.600581) (xy 54.494481 0.845566) (xy 55.43517 0.845566)
			)
		)
		(polygon
			(pts
				(xy 55.426915 0.713537) (xy 54.498596 0.713537) (xy 54.498596 -0.029108) (xy 55.426915 -0.029108)
			)
		)
		(polygon
			(pts
				(xy 53.458872 1.600581) (xy 52.509928 1.600581) (xy 52.509928 0.857936) (xy 53.458872 0.857936)
			)
		)
		(polygon
			(pts
				(xy 53.454757 0.709397) (xy 52.501673 0.709397) (xy 52.501673 -0.049759) (xy 53.454757 -0.049759)
			)
		)
		(polygon
			(pts
				(xy 51.466115 1.605026) (xy 50.504776 1.605026) (xy 50.504776 0.845871) (xy 51.466115 0.845871)
			)
		)
		(polygon
			(pts
				(xy 51.45372 0.713842) (xy 50.488291 0.713842) (xy 50.488291 -0.041173) (xy 51.45372 -0.041173)
			)
		)
		(polygon
			(pts
				(xy 49.374298 1.600911) (xy 48.30158 1.600911) (xy 48.30158 0.845871) (xy 49.374298 0.845871)
			)
		)
		(polygon
			(pts
				(xy 49.378438 0.713842) (xy 48.32223 0.713842) (xy 48.32223 -0.037059) (xy 49.378438 -0.037059)
			)
		)
	)
	(zone
		(net "VDD_3.3V")
		(layer "In5.Cu")
		(hatch none 0.5)
		(connect_pads
			(clearance 0.5)
		)
		(min_thickness 0.25)
		(fill yes
			(thermal_gap 0.5)
			(thermal_bridge_width 0.5)
			(island_removal_mode 0)
		)
		(polygon
			(pts
				(xy 17.78 37.338) (xy 17.78 31.496) (xy 29.845 31.496) (xy 29.845 32.131) (xy 30.353 32.131) (xy 30.353 31.496)
				(xy 32.512 31.496) (xy 32.512 32.004) (xy 33.02 32.004) (xy 33.02 31.496) (xy 35.179 31.496) (xy 35.179 32.004)
				(xy 35.56 32.004) (xy 35.56 31.496) (xy 38.862 31.496) (xy 38.862 10.033) (xy 44.069 10.033) (xy 44.069 11.193983)
				(xy 44.559017 11.684) (xy 44.905397 11.684) (xy 45.085 11.863603) (xy 45.085 16.965397) (xy 43.053 18.997397)
				(xy 43.053 34.798) (xy 44.196 35.941) (xy 44.196 37.338) (xy 32.639 37.338) (xy 32.639 37.211) (xy 29.591 37.211)
				(xy 29.591 37.338) (xy 26.543 37.338) (xy 26.543 37.084) (xy 26.035 37.084) (xy 26.035 37.338)
			)
		)
	)
	(zone
		(net "VDD_5.0V")
		(layer "In5.Cu")
		(hatch none 0.5)
		(connect_pads
			(clearance 0.5)
		)
		(min_thickness 0.25)
		(fill yes
			(thermal_gap 0.5)
			(thermal_bridge_width 0.5)
			(island_removal_mode 0)
		)
		(polygon
			(pts
				(xy 39.1382 57.824776)
				(arc
					(start 39.1382 51.325018)
					(mid 38.552378 49.910742)
					(end 37.138102 49.32492)
				)
				(xy 27.94 49.32492) (xy 27.94 47.371) (xy 11.43 47.371) (xy 11.43 44.704) (xy 7.874 44.704) (xy 7.874 36.523397)
				(xy 7.418603 36.068) (xy 3.81 36.068) (xy 3.81 31.496) (xy 17.526 31.496) (xy 17.526 37.592) (xy 29.591 37.592)
				(xy 29.591 37.719) (xy 32.639 37.719) (xy 32.639 37.592) (xy 34.798 37.592) (xy 34.798 38.481) (xy 35.052 38.481)
				(xy 35.306 38.227) (xy 35.814 38.227) (xy 35.814 37.846) (xy 37.084 37.846) (xy 37.084 37.592) (xy 41.402 37.592)
				(xy 41.402 43.105603) (xy 44.270397 45.974) (xy 74.422 45.974) (xy 74.422 52.324) (xy 79.248 52.324)
				(xy 79.248 48.768) (xy 87.1379 48.768) (xy 87.1379 55.753) (xy 85.066124 57.824776)
			)
		)
		(polygon
			(pts
				(arc
					(start 26.67 41.558972)
					(mid 26.67 40.991028)
					(end 26.67 41.558972)
				)
			)
		)
		(polygon
			(pts
				(xy 15.367 38.481) (xy 13.208 38.481) (xy 13.208 36.068) (xy 15.367 36.068)
			)
		)
	)
	(zone
		(net "EXT_3.3V")
		(layer "In5.Cu")
		(hatch none 0.5)
		(connect_pads
			(clearance 0.5)
		)
		(min_thickness 0.25)
		(fill yes
			(thermal_gap 0.5)
			(thermal_bridge_width 0.5)
			(island_removal_mode 0)
		)
		(polygon
			(pts
				(xy 6.138012 49.32492)
				(arc
					(start 6.138012 39.824914)
					(mid 5.552197 38.410631)
					(end 4.137914 37.824816)
				)
				(xy -2.161946 37.824816) (xy -2.161946 0.254) (xy 0.254 -2.161946) (xy 0.254 -2.1749) (xy 61.849 -2.1749)
				(xy 64.512114 -2.1749) (xy 64.521309 -2.165706) (xy 64.521309 2.776779) (xy 61.849 2.776779) (xy 61.849 7.493)
				(xy 49.657 7.493) (xy 49.657 8.509) (xy 49.022 8.509) (xy 49.022 9.485808) (xy 48.728808 9.779)
				(xy 38.608 9.779) (xy 38.608 31.242) (xy 32.258 31.242) (xy 32.258 30.734) (xy 31.623 30.734) (xy 31.623 31.242)
				(arc
					(start 31.242 31.242)
					(mid 30.988 30.403095)
					(end 30.734 31.242)
				)
				(xy 3.556 31.242) (xy 3.556 36.322) (xy 7.313397 36.322) (xy 7.62 36.628603) (xy 7.62 44.958) (xy 11.176 44.958)
				(xy 11.176 47.625) (xy 27.686 47.625) (xy 27.686 49.32492)
			)
		)
		(polygon
			(pts
				(xy 52.403731 1.671701) (xy 52.26271 1.671701) (xy 52.008202 1.417193) (xy 52.008202 1.296822) (xy 52.03571 1.269314)
				(xy 52.156081 1.269314) (xy 52.434668 1.547901) (xy 52.434668 1.640764)
			)
		)
		(polygon
			(pts
				(arc
					(start 49.37694 1.348003)
					(mid 49.71314 1.490574)
					(end 49.366348 1.605026)
				)
				(xy 48.285806 1.605026) (xy 48.285806 0.847725) (xy 49.37694 0.847725)
			)
		)
		(polygon
			(pts
				(xy 63.148007 0.678993) (xy 62.255857 0.678993) (xy 62.255857 -0.044806) (xy 63.148007 -0.044806)
			)
		)
		(polygon
			(pts
				(xy 63.187275 1.576756) (xy 62.283924 1.576756) (xy 62.283924 0.858545) (xy 63.187275 0.858545)
			)
		)
		(polygon
			(pts
				(xy 61.176662 1.577137) (xy 60.391243 1.577137) (xy 60.391243 0.862355) (xy 61.176662 0.862355)
			)
		)
		(polygon
			(pts
				(xy 61.155885 0.687832) (xy 60.403715 0.687832) (xy 60.403715 -0.03109) (xy 61.155885 -0.03109)
			)
		)
		(polygon
			(pts
				(xy 59.372297 1.600962) (xy 58.407376 1.600962) (xy 58.407376 0.843686) (xy 59.372297 0.843686)
			)
		)
		(polygon
			(pts
				(xy 59.360079 0.725602) (xy 58.399223 0.725602) (xy 58.399223 -0.035763) (xy 59.360079 -0.035763)
			)
		)
		(polygon
			(pts
				(xy 57.393586 1.596873) (xy 56.400141 1.596873) (xy 56.400141 0.859942) (xy 57.393586 0.859942)
			)
		)
		(polygon
			(pts
				(xy 57.393586 0.705231) (xy 56.400141 0.705231) (xy 56.400141 -0.043891) (xy 57.393586 -0.043891)
			)
		)
		(polygon
			(pts
				(xy 55.414875 1.596873) (xy 54.506952 1.596873) (xy 54.506952 0.839597) (xy 55.414875 0.839597)
			)
		)
		(polygon
			(pts
				(xy 55.406747 0.717448) (xy 54.515106 0.717448) (xy 54.515106 -0.035763) (xy 55.406747 -0.035763)
			)
		)
		(polygon
			(pts
				(xy 53.448382 1.596873) (xy 52.516024 1.596873) (xy 52.516024 0.851814) (xy 53.448382 0.851814)
			)
		)
		(polygon
			(pts
				(xy 53.444292 0.709295) (xy 52.495653 0.709295) (xy 52.495653 -0.031699) (xy 53.444292 -0.031699)
			)
		)
		(polygon
			(pts
				(xy 51.45339 1.592809) (xy 50.500661 1.592809) (xy 50.500661 0.839597) (xy 51.45339 0.839597)
			)
		)
		(polygon
			(pts
				(xy 51.445236 0.709295) (xy 50.516942 0.709295) (xy 50.516942 -0.027635) (xy 51.445236 -0.027635)
			)
		)
		(polygon
			(pts
				(xy 49.37694 0.717448) (xy 48.285806 0.717448) (xy 48.285806 -0.039853) (xy 49.37694 -0.039853)
			)
		)
	)
	(zone
		(net "VDD_CORE")
		(layer "In5.Cu")
		(hatch none 0.5)
		(connect_pads
			(clearance 0.5)
		)
		(min_thickness 0.25)
		(fill yes
			(thermal_gap 0.5)
			(thermal_bridge_width 0.5)
			(island_removal_mode 0)
		)
		(polygon
			(pts
				(xy 44.375603 45.72) (xy 41.656 43.000397) (xy 41.656 37.592) (xy 44.45 37.592) (xy 44.45 35.634397)
				(xy 43.434 34.618397) (xy 43.434 18.975603) (xy 45.280047 17.129557) (xy 45.280047 11.699443) (xy 45.010603 11.43)
				(xy 44.629146 11.43) (xy 44.323 11.123854) (xy 44.323 10.033) (xy 49.276 10.033) (xy 49.276 8.763)
				(xy 49.911 8.763) (xy 49.911 7.747) (xy 61.849 7.747) (xy 61.849 17.526) (xy 60.706 18.669) (xy 60.706 19.812)
				(xy 61.214 20.32) (xy 61.214 22.023603) (xy 61.595 22.404603) (xy 61.595 26.363397) (xy 60.706 27.252397)
				(xy 60.706 27.738603) (xy 61.595 28.627603) (xy 61.595 34.798) (xy 69.596 34.798) (xy 69.596 45.72)
			)
		)
	)
	(zone
		(net "DDR_VDDQ")
		(layer "In5.Cu")
		(hatch none 0.5)
		(connect_pads
			(clearance 0.5)
		)
		(min_thickness 0.25)
		(fill yes
			(thermal_gap 0.5)
			(thermal_bridge_width 0.5)
			(island_removal_mode 0)
		)
		(polygon
			(pts
				(xy 74.676 52.07) (xy 74.676 45.72) (xy 69.85 45.72) (xy 69.85 34.544) (xy 61.849 34.544) (xy 61.849 28.522397)
				(xy 60.96 27.633397) (xy 60.96 27.357603) (xy 61.849 26.468603) (xy 61.849 22.299397) (xy 61.468 21.918397)
				(xy 61.468 20.193) (xy 60.96 19.685) (xy 60.96 16.562603) (xy 62.103 15.419603) (xy 62.103 3.068549)
				(xy 64.786408 3.068549) (xy 64.786408 -2.1749) (xy 87.1379 -2.1749) (xy 87.1379 21.844) (xy 87.122 21.844)
				(xy 87.122 38.651688) (xy 76.327 38.651688) (xy 76.327 43.688) (xy 87.1379 43.688) (xy 87.1379 48.514)
				(xy 78.994 48.514) (xy 78.994 52.07)
			)
		)
	)
	(zone
		(net "DDR_VTT")
		(layer "In5.Cu")
		(hatch none 0.5)
		(connect_pads
			(clearance 0.5)
		)
		(min_thickness 0.25)
		(fill yes
			(thermal_gap 0.5)
			(thermal_bridge_width 0.5)
			(island_removal_mode 0)
		)
		(polygon
			(pts
				(xy 76.581 43.434) (xy 76.581 38.989) (xy 87.1379 38.989) (xy 87.1379 43.434)
			)
		)
	)
	(zone
		(layer "In6.Cu")
		(hatch none 0.5)
		(connect_pads
			(clearance 0)
		)
		(min_thickness 0.25)
		(keepout
			(tracks allowed)
			(vias allowed)
			(pads allowed)
			(copperpour allowed)
			(footprints allowed)
		)
		(placement
			(enabled no)
			(sheetname "")
		)
		(fill
			(thermal_gap 0.5)
			(thermal_bridge_width 0.5)
			(island_removal_mode 0)
		)
		(polygon
			(pts
				(xy 27.94 47.244) (xy 27.94 48.514) (xy 30.861 48.514) (xy 30.988 48.387) (xy 30.988 47.244) (xy 29.083 47.244)
			)
		)
	)
	(zone
		(layer "In6.Cu")
		(hatch none 0.5)
		(connect_pads
			(clearance 0)
		)
		(min_thickness 0.25)
		(keepout
			(tracks not_allowed)
			(vias allowed)
			(pads allowed)
			(copperpour not_allowed)
			(footprints allowed)
		)
		(placement
			(enabled no)
			(sheetname "")
		)
		(fill
			(thermal_gap 0.5)
			(thermal_bridge_width 0.5)
			(island_removal_mode 0)
		)
		(polygon
			(pts
				(xy 46.609 7.239) (xy 46.736 7.239) (xy 46.736 6.985) (xy 46.609 6.985)
			)
		)
	)
	(zone
		(layer "In6.Cu")
		(hatch none 0.5)
		(connect_pads
			(clearance 0.5)
		)
		(min_thickness 0.25)
		(fill
			(thermal_gap 0.5)
			(thermal_bridge_width 0.5)
			(island_removal_mode 0)
		)
		(polygon
			(pts
				(xy 14.859 38.354) (xy 14.859 46.228) (xy 19.05 46.228) (xy 19.05 38.354)
			)
		)
	)
	(zone
		(layer "In6.Cu")
		(hatch none 0.5)
		(connect_pads
			(clearance 0)
		)
		(min_thickness 0.25)
		(keepout
			(tracks allowed)
			(vias allowed)
			(pads allowed)
			(copperpour allowed)
			(footprints allowed)
		)
		(placement
			(enabled no)
			(sheetname "")
		)
		(fill
			(thermal_gap 0.5)
			(thermal_bridge_width 0.5)
			(island_removal_mode 0)
		)
		(polygon
			(pts
				(xy 20.955 44.323) (xy 20.955 47.117) (xy 22.098 47.117) (xy 22.098 45.593) (xy 23.876 45.593) (xy 24.003 45.466)
				(xy 24.003 44.323) (xy 22.098 44.323)
			)
		)
	)
	(zone
		(layer "In6.Cu")
		(hatch none 0.5)
		(connect_pads
			(clearance 0)
		)
		(min_thickness 0.25)
		(keepout
			(tracks allowed)
			(vias allowed)
			(pads allowed)
			(copperpour allowed)
			(footprints allowed)
		)
		(placement
			(enabled no)
			(sheetname "")
		)
		(fill
			(thermal_gap 0.5)
			(thermal_bridge_width 0.5)
			(island_removal_mode 0)
		)
		(polygon
			(pts
				(xy 28.956 35.687) (xy 28.956 33.909) (xy 21.336 33.909) (xy 21.336 35.687)
			)
		)
	)
	(zone
		(layer "In6.Cu")
		(hatch none 0.5)
		(connect_pads
			(clearance 0)
		)
		(min_thickness 0.25)
		(keepout
			(tracks not_allowed)
			(vias allowed)
			(pads allowed)
			(copperpour not_allowed)
			(footprints allowed)
		)
		(placement
			(enabled no)
			(sheetname "")
		)
		(fill
			(thermal_gap 0.5)
			(thermal_bridge_width 0.5)
			(island_removal_mode 0)
		)
		(polygon
			(pts
				(xy 8.89 25.4) (xy 9.017 25.4) (xy 9.017 25.146) (xy 8.89 25.146)
			)
		)
	)
	(zone
		(layer "In6.Cu")
		(hatch none 0.5)
		(connect_pads
			(clearance 0)
		)
		(min_thickness 0.25)
		(keepout
			(tracks not_allowed)
			(vias allowed)
			(pads allowed)
			(copperpour not_allowed)
			(footprints allowed)
		)
		(placement
			(enabled no)
			(sheetname "")
		)
		(fill
			(thermal_gap 0.5)
			(thermal_bridge_width 0.5)
			(island_removal_mode 0)
		)
		(polygon
			(pts
				(xy 7.874 23.114) (xy 8.001 23.114) (xy 8.001 22.733) (xy 7.874 22.733)
			)
		)
	)
	(zone
		(layer "In6.Cu")
		(hatch none 0.5)
		(connect_pads
			(clearance 0)
		)
		(min_thickness 0.25)
		(keepout
			(tracks allowed)
			(vias allowed)
			(pads allowed)
			(copperpour allowed)
			(footprints allowed)
		)
		(placement
			(enabled no)
			(sheetname "")
		)
		(fill
			(thermal_gap 0.5)
			(thermal_bridge_width 0.5)
			(island_removal_mode 0)
		)
		(polygon
			(pts
				(xy 33.02 49.022) (xy 33.02 48.26) (xy 33.02 46.228) (xy 33.274 45.974) (xy 34.925 45.974) (xy 34.925 42.164)
				(xy 36.195 42.164) (xy 36.449 42.418) (xy 36.449 44.196) (xy 36.957 44.196) (xy 37.465 44.704) (xy 37.465 47.498)
				(xy 37.338 47.625) (xy 35.56 47.625) (xy 35.56 49.022) (xy 35.433 49.149) (xy 33.147 49.149)
			)
		)
	)
	(zone
		(layer "In6.Cu")
		(hatch none 0.5)
		(connect_pads
			(clearance 0)
		)
		(min_thickness 0.25)
		(keepout
			(tracks not_allowed)
			(vias allowed)
			(pads allowed)
			(copperpour not_allowed)
			(footprints allowed)
		)
		(placement
			(enabled no)
			(sheetname "")
		)
		(fill
			(thermal_gap 0.5)
			(thermal_bridge_width 0.5)
			(island_removal_mode 0)
		)
		(polygon
			(pts
				(xy 59.69 4.191) (xy 59.817 4.191) (xy 59.817 3.937) (xy 59.69 3.937)
			)
		)
	)
	(zone
		(layer "In6.Cu")
		(hatch none 0.5)
		(connect_pads
			(clearance 0)
		)
		(min_thickness 0.25)
		(keepout
			(tracks not_allowed)
			(vias allowed)
			(pads allowed)
			(copperpour not_allowed)
			(footprints allowed)
		)
		(placement
			(enabled no)
			(sheetname "")
		)
		(fill
			(thermal_gap 0.5)
			(thermal_bridge_width 0.5)
			(island_removal_mode 0)
		)
		(polygon
			(pts
				(xy 9.271 25.781) (xy 9.398 25.781) (xy 9.398 25.527) (xy 9.271 25.527)
			)
		)
	)
	(zone
		(layer "In6.Cu")
		(hatch none 0.5)
		(connect_pads
			(clearance 0)
		)
		(min_thickness 0.25)
		(keepout
			(tracks allowed)
			(vias allowed)
			(pads allowed)
			(copperpour allowed)
			(footprints allowed)
		)
		(placement
			(enabled no)
			(sheetname "")
		)
		(fill
			(thermal_gap 0.5)
			(thermal_bridge_width 0.5)
			(island_removal_mode 0)
		)
		(polygon
			(pts
				(xy 2.032 34.671) (xy 2.032 35.941) (xy 4.953 35.941) (xy 5.08 35.814) (xy 5.08 34.671) (xy 3.175 34.671)
			)
		)
	)
	(zone
		(layer "In6.Cu")
		(hatch none 0.5)
		(connect_pads
			(clearance 0)
		)
		(min_thickness 0.25)
		(keepout
			(tracks allowed)
			(vias allowed)
			(pads allowed)
			(copperpour allowed)
			(footprints allowed)
		)
		(placement
			(enabled no)
			(sheetname "")
		)
		(fill
			(thermal_gap 0.5)
			(thermal_bridge_width 0.5)
			(island_removal_mode 0)
		)
		(polygon
			(pts
				(xy 30.988 43.434) (xy 33.655 43.434) (xy 33.782 43.307) (xy 33.782 42.164) (xy 31.877 42.164) (xy 30.734 42.164)
				(xy 29.464 42.164) (xy 28.956 42.672) (xy 28.956 43.688) (xy 29.21 43.942) (xy 30.48 43.942)
			)
		)
	)
	(zone
		(layer "In6.Cu")
		(hatch none 0.5)
		(connect_pads
			(clearance 0.5)
		)
		(min_thickness 0.25)
		(fill
			(thermal_gap 0.5)
			(thermal_bridge_width 0.5)
			(island_removal_mode 0)
		)
		(polygon
			(pts
				(xy 7.239 45.339) (xy 7.239 39.37) (xy 11.684 39.37) (xy 12.573 38.481) (xy 13.716 38.481) (xy 13.97 38.735)
				(xy 13.97 44.069) (xy 12.7 45.339)
			)
		)
	)
	(zone
		(layer "In6.Cu")
		(hatch none 0.5)
		(connect_pads
			(clearance 0)
		)
		(min_thickness 0.25)
		(keepout
			(tracks not_allowed)
			(vias allowed)
			(pads allowed)
			(copperpour not_allowed)
			(footprints allowed)
		)
		(placement
			(enabled no)
			(sheetname "")
		)
		(fill
			(thermal_gap 0.5)
			(thermal_bridge_width 0.5)
			(island_removal_mode 0)
		)
		(polygon
			(pts
				(xy 9.144 20.447) (xy 9.271 20.447) (xy 9.271 20.066) (xy 9.144 20.066)
			)
		)
	)
	(zone
		(layer "In6.Cu")
		(hatch none 0.5)
		(connect_pads
			(clearance 0)
		)
		(min_thickness 0.25)
		(keepout
			(tracks allowed)
			(vias allowed)
			(pads allowed)
			(copperpour allowed)
			(footprints allowed)
		)
		(placement
			(enabled no)
			(sheetname "")
		)
		(fill
			(thermal_gap 0.5)
			(thermal_bridge_width 0.5)
			(island_removal_mode 0)
		)
		(polygon
			(pts
				(xy 16.129 37.084) (xy 16.129 38.354) (xy 19.05 38.354) (xy 19.177 38.227) (xy 19.177 37.084) (xy 17.272 37.084)
			)
		)
	)
	(zone
		(layers "In6.Cu" "In7.Cu")
		(hatch none 0.5)
		(connect_pads
			(clearance 0)
		)
		(min_thickness 0.25)
		(keepout
			(tracks not_allowed)
			(vias allowed)
			(pads allowed)
			(copperpour not_allowed)
			(footprints allowed)
		)
		(placement
			(enabled no)
			(sheetname "")
		)
		(fill yes
			(thermal_gap 0.5)
			(thermal_bridge_width 0.5)
			(island_removal_mode 0)
		)
		(polygon
			(pts
				(xy 12.827 17.907) (xy 12.954 17.907) (xy 12.954 17.526) (xy 12.827 17.526)
			)
		)
	)
	(zone
		(layers "In6.Cu" "In7.Cu")
		(hatch none 0.5)
		(connect_pads
			(clearance 0)
		)
		(min_thickness 0.25)
		(keepout
			(tracks not_allowed)
			(vias allowed)
			(pads allowed)
			(copperpour not_allowed)
			(footprints allowed)
		)
		(placement
			(enabled no)
			(sheetname "")
		)
		(fill yes
			(thermal_gap 0.5)
			(thermal_bridge_width 0.5)
			(island_removal_mode 0)
		)
		(polygon
			(pts
				(xy 57.658 7.239) (xy 57.785 7.239) (xy 57.785 6.858) (xy 57.658 6.858)
			)
		)
	)
	(zone
		(layers "In6.Cu" "In7.Cu")
		(hatch none 0.5)
		(connect_pads
			(clearance 0)
		)
		(min_thickness 0.25)
		(keepout
			(tracks not_allowed)
			(vias allowed)
			(pads allowed)
			(copperpour not_allowed)
			(footprints allowed)
		)
		(placement
			(enabled no)
			(sheetname "")
		)
		(fill yes
			(thermal_gap 0.5)
			(thermal_bridge_width 0.5)
			(island_removal_mode 0)
		)
		(polygon
			(pts
				(xy 14.986 20.955) (xy 14.986 20.828) (xy 14.605 20.828) (xy 14.605 20.955)
			)
		)
	)
	(zone
		(layers "In6.Cu" "In7.Cu")
		(hatch none 0.5)
		(connect_pads
			(clearance 0)
		)
		(min_thickness 0.25)
		(keepout
			(tracks not_allowed)
			(vias allowed)
			(pads allowed)
			(copperpour not_allowed)
			(footprints allowed)
		)
		(placement
			(enabled no)
			(sheetname "")
		)
		(fill yes
			(thermal_gap 0.5)
			(thermal_bridge_width 0.5)
			(island_removal_mode 0)
		)
		(polygon
			(pts
				(xy 16.637 10.287) (xy 16.764 10.287) (xy 16.764 9.906) (xy 16.637 9.906)
			)
		)
	)
	(zone
		(layers "In6.Cu" "In7.Cu")
		(hatch none 0.5)
		(connect_pads
			(clearance 0)
		)
		(min_thickness 0.25)
		(keepout
			(tracks not_allowed)
			(vias allowed)
			(pads allowed)
			(copperpour not_allowed)
			(footprints allowed)
		)
		(placement
			(enabled no)
			(sheetname "")
		)
		(fill yes
			(thermal_gap 0.5)
			(thermal_bridge_width 0.5)
			(island_removal_mode 0)
		)
		(polygon
			(pts
				(xy 14.097 15.367) (xy 14.224 15.367) (xy 14.224 14.986) (xy 14.097 14.986)
			)
		)
	)
	(zone
		(layer "In7.Cu")
		(hatch none 0.5)
		(connect_pads
			(clearance 0)
		)
		(min_thickness 0.25)
		(keepout
			(tracks not_allowed)
			(vias allowed)
			(pads allowed)
			(copperpour not_allowed)
			(footprints allowed)
		)
		(placement
			(enabled no)
			(sheetname "")
		)
		(fill
			(thermal_gap 0.5)
			(thermal_bridge_width 0.5)
			(island_removal_mode 0)
		)
		(polygon
			(pts
				(xy 10.16 22.987) (xy 10.287 22.987) (xy 10.287 22.733) (xy 10.16 22.733)
			)
		)
	)
	(zone
		(layer "In7.Cu")
		(hatch none 0.5)
		(connect_pads
			(clearance 0)
		)
		(min_thickness 0.25)
		(keepout
			(tracks not_allowed)
			(vias allowed)
			(pads allowed)
			(copperpour not_allowed)
			(footprints allowed)
		)
		(placement
			(enabled no)
			(sheetname "")
		)
		(fill
			(thermal_gap 0.5)
			(thermal_bridge_width 0.5)
			(island_removal_mode 0)
		)
		(polygon
			(pts
				(xy 46.609 4.191) (xy 46.736 4.191) (xy 46.736 3.937) (xy 46.609 3.937)
			)
		)
	)
	(zone
		(layer "In7.Cu")
		(hatch none 0.5)
		(connect_pads
			(clearance 0)
		)
		(min_thickness 0.25)
		(keepout
			(tracks allowed)
			(vias allowed)
			(pads allowed)
			(copperpour allowed)
			(footprints allowed)
		)
		(placement
			(enabled no)
			(sheetname "")
		)
		(fill
			(thermal_gap 0.5)
			(thermal_bridge_width 0.5)
			(island_removal_mode 0)
		)
		(polygon
			(pts
				(xy 37.338 35.179) (xy 37.338 30.988) (xy 35.052 30.988) (xy 35.052 35.179)
			)
		)
	)
	(zone
		(layer "In7.Cu")
		(hatch none 0.5)
		(connect_pads
			(clearance 0)
		)
		(min_thickness 0.25)
		(keepout
			(tracks allowed)
			(vias allowed)
			(pads allowed)
			(copperpour allowed)
			(footprints allowed)
		)
		(placement
			(enabled no)
			(sheetname "")
		)
		(fill
			(thermal_gap 0.5)
			(thermal_bridge_width 0.5)
			(island_removal_mode 0)
		)
		(polygon
			(pts
				(xy 27.178 11.938) (xy 27.178 10.16) (xy 26.289 10.16) (xy 26.289 11.938)
			)
		)
	)
	(zone
		(net "GND")
		(layer "In8.Cu")
		(hatch none 0.5)
		(connect_pads
			(clearance 0.5)
		)
		(min_thickness 0.25)
		(fill yes
			(thermal_gap 0.5)
			(thermal_bridge_width 0.5)
			(island_removal_mode 0)
		)
		(polygon
			(pts
				(xy 39.1382 57.824776)
				(arc
					(start 39.1382 51.325018)
					(mid 38.552378 49.910742)
					(end 37.138102 49.32492)
				)
				(xy 6.138012 49.32492)
				(arc
					(start 6.138012 39.824914)
					(mid 5.552197 38.410631)
					(end 4.137914 37.824816)
				)
				(xy -2.161946 37.824816) (xy -2.161946 -0.124054) (xy -0.127 -2.159) (xy -0.127 -2.1749) (xy 87.1379 -2.1749)
				(xy 87.1379 55.88) (xy 85.193124 57.824776)
			)
		)
		(polygon
			(pts
				(arc
					(start 35.306 38.586207)
					(mid 35.306 37.867793)
					(end 35.306 38.586207)
				)
			)
		)
		(polygon
			(pts
				(xy 47.879 1.143) (xy 47.625 1.143) (xy 47.625 1.016) (xy 47.879 1.016)
			)
		)
		(polygon
			(pts
				(xy 63.5 1.27) (xy 48.006 1.27) (xy 48.006 0.254) (xy 63.5 0.254)
			)
		)
	)
	(zone
		(layer "Cmts.User")
		(hatch none 0.5)
		(connect_pads
			(clearance 0)
		)
		(min_thickness 0.25)
		(keepout
			(tracks allowed)
			(vias allowed)
			(pads allowed)
			(copperpour allowed)
			(footprints allowed)
		)
		(placement
			(enabled no)
			(sheetname "")
		)
		(fill
			(thermal_gap 0.5)
			(thermal_bridge_width 0.5)
			(island_removal_mode 0)
		)
		(polygon
			(pts
				(xy 71.12 20.71878) (xy 84.745779 20.71878) (xy 84.745779 11.684) (xy 71.12 11.684)
			)
		)
	)
	(zone
		(layer "Cmts.User")
		(hatch none 0.5)
		(connect_pads
			(clearance 0)
		)
		(min_thickness 0.25)
		(keepout
			(tracks allowed)
			(vias allowed)
			(pads allowed)
			(copperpour allowed)
			(footprints allowed)
		)
		(placement
			(enabled no)
			(sheetname "")
		)
		(fill
			(thermal_gap 0.5)
			(thermal_bridge_width 0.5)
			(island_removal_mode 0)
		)
		(polygon
			(pts
				(xy 71.12 9.16178) (xy 84.745779 9.16178) (xy 84.745779 0.127) (xy 71.12 0.127)
			)
		)
	)
	(zone
		(layer "Cmts.User")
		(hatch none 0.5)
		(connect_pads
			(clearance 0)
		)
		(min_thickness 0.25)
		(keepout
			(tracks allowed)
			(vias allowed)
			(pads allowed)
			(copperpour allowed)
			(footprints allowed)
		)
		(placement
			(enabled no)
			(sheetname "")
		)
		(fill
			(thermal_gap 0.5)
			(thermal_bridge_width 0.5)
			(island_removal_mode 0)
		)
		(polygon
			(pts
				(xy 38.354 1.524) (xy 38.354 35.282708) (xy 71.12 35.306) (xy 71.12 1.524)
			)
		)
	)
	(zone
		(layer "Cmts.User")
		(hatch none 0.5)
		(connect_pads
			(clearance 0)
		)
		(min_thickness 0.25)
		(keepout
			(tracks allowed)
			(vias allowed)
			(pads allowed)
			(copperpour allowed)
			(footprints allowed)
		)
		(placement
			(enabled no)
			(sheetname "")
		)
		(fill
			(thermal_gap 0.5)
			(thermal_bridge_width 0.5)
			(island_removal_mode 0)
		)
		(polygon
			(pts
				(xy 71.12 32.27578) (xy 84.745779 32.27578) (xy 84.745779 23.241) (xy 71.12 23.241)
			)
		)
	)
	(zone
		(layer "Cmts.User")
		(hatch none 0.5)
		(connect_pads
			(clearance 0)
		)
		(min_thickness 0.25)
		(keepout
			(tracks allowed)
			(vias allowed)
			(pads allowed)
			(copperpour allowed)
			(footprints allowed)
		)
		(placement
			(enabled no)
			(sheetname "")
		)
		(fill
			(thermal_gap 0.5)
			(thermal_bridge_width 0.5)
			(island_removal_mode 0)
		)
		(polygon
			(pts
				(xy 13.462 36.068) (xy 13.462 38.227) (xy 15.621 38.227) (xy 15.621 36.068)
			)
		)
	)
	(zone
		(layer "Cmts.User")
		(hatch none 0.5)
		(connect_pads
			(clearance 0)
		)
		(min_thickness 0.25)
		(keepout
			(tracks allowed)
			(vias allowed)
			(pads allowed)
			(copperpour allowed)
			(footprints allowed)
		)
		(placement
			(enabled no)
			(sheetname "")
		)
		(fill
			(thermal_gap 0.5)
			(thermal_bridge_width 0.5)
			(island_removal_mode 0)
		)
		(polygon
			(pts
				(xy 25.527 19.177) (xy 25.527 30.353) (xy 37.465 30.353) (xy 37.465 19.177)
			)
		)
	)
)
